G04 ================== begin FILE IDENTIFICATION RECORD ==================*
G04 Layout Name:  D:/<user>/Wistron_project/16316-1/gbr-0621/16316-1.brd*
G04 Film Name:    NOTICE*
G04 File Format:  Gerber RS274X*
G04 File Origin:  Cadence Allegro 16.5-S056*
G04 Origin Date:  Wed Jun 21 09:31:56 2017*
G04 *
G04 Layer:  MANUFACTURING/THERMAL*
G04 *
G04 Offset:    (0.00 0.00)*
G04 Mirror:    No*
G04 Mode:      Positive*
G04 Rotation:  0*
G04 FullContactRelief:  No*
G04 UndefLineWidth:     6.00*
G04 ================== end FILE IDENTIFICATION RECORD ====================*
%FSLAX35Y35*MOIN*%
%IR0*IPPOS*OFA0.00000B0.00000*MIA0B0*SFA1.00000B1.00000*%
%ADD10C,.004*%
%ADD11C,.006*%
%ADD12C,.0033*%
%ADD13C,.008*%
%ADD14C,.0055*%
G75*
%LPD*%
G75*
G36*
G01X301800Y213890D02*
G02X352500Y214150I25558J-40503D01*
G01X341350Y192820D01*
X312850D01*
X301800Y213890D01*
G37*
G36*
G01X298620Y274980D02*
X307300D01*
G03X341410Y274970I17058J11442D01*
G01X348960D01*
X338090Y253970D01*
X309590D01*
X298620Y274980D01*
G37*
G54D10*
G01X820594Y153868D02*
X808594Y155868D01*
G01X820009Y224740D02*
Y167889D01*
G01X820594Y161868D02*
Y141868D01*
G01X808594Y155868D02*
Y151868D01*
G01D02*
X820594Y153868D01*
G01X796594D02*
X820594D01*
G01X820009Y167889D02*
X770009D01*
G01D02*
Y177889D01*
G01X810005Y234744D02*
X810009Y234740D01*
G01Y297889D02*
Y234740D01*
G01D02*
X820009Y224740D01*
G01X790009Y217889D02*
Y247889D01*
G01Y177889D02*
Y207889D01*
G01X770009Y217889D02*
X790009D01*
G01X770009Y207889D02*
Y217889D01*
G01X790009Y207889D02*
X770009D01*
G01Y177889D02*
X790009D01*
G01X810514Y319548D02*
Y299548D01*
G01X790009Y257889D02*
Y287889D01*
G01X770009Y297889D02*
X810009D01*
G01X770009Y287889D02*
Y297889D01*
G01X790009Y287889D02*
X770009D01*
G01Y257889D02*
X790009D01*
G01X770009Y247889D02*
Y257889D01*
G01X790009Y247889D02*
X770009D01*
G01X810514Y307548D02*
X822514Y305548D01*
G01Y309548D02*
X810514Y307548D01*
G01D02*
X850514D01*
G01X852594Y151868D02*
Y155868D01*
G01X840009Y167889D02*
X890009D01*
G01X840009Y225249D02*
Y167889D01*
G01X859454Y153868D02*
X840594D01*
G01X852594Y155868D02*
X840594Y153868D01*
G01Y141868D02*
Y161868D01*
G01Y153868D02*
X852594Y151868D01*
G01X845009Y225249D02*
X961000D01*
G01X870009Y217889D02*
Y247889D01*
G01X890009Y217889D02*
X870009D01*
G01Y207889D02*
X890009D01*
G01X870009Y177889D02*
Y207889D01*
G01X890009Y177889D02*
X870009D01*
G01X850009Y297889D02*
Y235249D01*
G01D02*
X840009Y225249D01*
G01X870009Y287889D02*
X890009D01*
G01X870009Y257889D02*
Y287889D01*
G01X890009Y257889D02*
X870009D01*
G01Y247889D02*
X890009D01*
G01X850514Y319548D02*
Y299548D01*
G01X890009Y297889D02*
X850009D01*
G01X850514Y307548D02*
X859374D01*
G01X838514Y309548D02*
Y305548D01*
G01X850514Y307548D02*
X838514Y309548D01*
G01Y305548D02*
X850514Y307548D01*
G01X822514Y305548D02*
Y309548D01*
G01X890009Y167889D02*
Y177889D01*
G01X895009Y217889D02*
X961000D01*
G01X890009Y207889D02*
X890000Y217800D01*
G01X890009Y287889D02*
Y297889D01*
G01Y247889D02*
Y257889D01*
G01X954000Y237249D02*
X956000Y225249D01*
X958000Y237249D01*
X954000D01*
G01X956000Y249249D02*
Y225249D01*
G01X958000Y205889D02*
X956000Y217889D01*
X954000Y205889D01*
X958000D01*
G01X956000Y193889D02*
Y217889D01*
G01X1121654Y169388D02*
Y232028D01*
G01Y151388D02*
X1133654Y149388D01*
G01Y153388D02*
X1121654Y151388D01*
G01D02*
X1161654D01*
G01X1121654Y163388D02*
Y143388D01*
G01X1081654Y169388D02*
X1121654D01*
G01X1081654Y179388D02*
Y169388D01*
G01X1121654Y232028D02*
X1131654Y242028D01*
G01X1101654Y249388D02*
Y219388D01*
G01Y209388D02*
Y179388D01*
G01X1081654Y209388D02*
X1101654D01*
G01X1081654Y219388D02*
Y209388D01*
G01X1101654Y219388D02*
X1081654D01*
G01X1101654Y179388D02*
X1081654D01*
G01X1131654Y242028D02*
Y299388D01*
G01X1101654Y289388D02*
Y259388D01*
G01X1131654Y299388D02*
X1081654D01*
G01Y289388D02*
X1101654D01*
G01X1081654Y299388D02*
Y289388D01*
G01Y249388D02*
X1101654D01*
G01X1081654Y259388D02*
Y249388D01*
G01X1101654Y259388D02*
X1081654D01*
G01X1119654Y321388D02*
Y317388D01*
G01X1131654Y319388D02*
X1119654Y321388D01*
G01Y317388D02*
X1131654Y319388D01*
G01Y327388D02*
Y307388D01*
G01X1107654Y319388D02*
X1131654D01*
G01X1161654Y169388D02*
Y232537D01*
G01X1201654Y169388D02*
X1161654D01*
G01X1149654Y153388D02*
Y149388D01*
G01X1161654Y151388D02*
X1149654Y153388D01*
G01Y149388D02*
X1161654Y151388D01*
G01D02*
X1170514D01*
G01X1161654Y163388D02*
Y143388D01*
G01X1133654Y149388D02*
Y153388D01*
G01X1201654Y209388D02*
X1181654D01*
G01Y219388D02*
X1201654D01*
G01X1181654Y249388D02*
Y219388D01*
G01Y179388D02*
X1201654D01*
G01X1181654Y209388D02*
Y179388D01*
G01X1161658Y232533D02*
X1161654Y232537D01*
G01D02*
X1151654Y242537D01*
G01X1201654Y289388D02*
X1181654D01*
G01X1201654Y249388D02*
X1181654D01*
G01Y259388D02*
X1201654D01*
G01X1181654Y289388D02*
Y259388D01*
G01X1151654Y299388D02*
X1201654D01*
G01X1151654Y242537D02*
Y299388D01*
G01X1163654Y317388D02*
Y321388D01*
G01X1170514Y319388D02*
X1151654D01*
G01D02*
X1163654Y317388D01*
G01Y321388D02*
X1151654Y319388D01*
G01Y307388D02*
Y327388D01*
G01X1201654Y179388D02*
Y169388D01*
G01Y219388D02*
Y209388D01*
G01Y299388D02*
Y289388D01*
G01Y259388D02*
Y249388D01*
G54D11*
G01X4300Y524700D02*
X4250D01*
G01X54300Y770700D02*
X54250D01*
G01X288350Y208820D02*
X283350D01*
Y182820D01*
X288350D01*
G01Y187820D02*
X307850D01*
X296850Y208820D01*
X288350D01*
Y213820D01*
X301850D01*
X312850Y192820D01*
X341350D01*
X352350Y213820D01*
X365850D01*
Y208820D01*
X357350D01*
X346350Y187820D01*
X365850D01*
G01X288350D02*
Y182820D01*
X365850D01*
Y187820D01*
G01X285090Y269970D02*
X280090D01*
Y243970D01*
X285090D01*
G01Y248970D02*
X304590D01*
X293590Y269970D01*
X285090D01*
Y274970D01*
X298590D01*
X309590Y253970D01*
X338090D01*
X349090Y274970D01*
X362590D01*
Y269970D01*
X354090D01*
X343090Y248970D01*
X362590D01*
G01X285090D02*
Y243970D01*
X362590D01*
Y248970D01*
G01X315090Y310830D02*
X303090Y308830D01*
X315090Y306830D01*
Y310830D01*
G01X306290Y308830D02*
X303090D01*
G01X304090Y354830D02*
X292090Y352830D01*
X304090Y350830D01*
Y354830D01*
G01X311290Y352830D02*
X292090D01*
G01X339590Y308830D02*
X304090D01*
G01X283590Y340830D02*
X278590D01*
Y314830D01*
X283590D01*
G01Y319830D02*
Y314830D01*
X361090D01*
Y319830D01*
G01X283590D02*
X303090D01*
X292090Y340830D01*
X283590D01*
Y345830D01*
X297090D01*
X308090Y324830D01*
X336590D01*
X347590Y345830D01*
X361090D01*
Y340830D01*
X352590D01*
X341590Y319830D01*
X361090D01*
G01X385140Y233310D02*
X383140Y221310D01*
X381140Y233310D01*
X385140D01*
G01X383140Y237850D02*
Y221310D01*
G01X385140Y202130D02*
X383140Y214130D01*
X381140Y202130D01*
X385140D01*
G01X383140Y197250D02*
Y214130D01*
G01X357370D02*
X388140D01*
G01X332370Y221310D02*
X388140D01*
G01X365850Y208820D02*
X370850D01*
Y182820D01*
X365850D01*
G01X384990Y287010D02*
X382990Y275010D01*
X380990Y287010D01*
X384990D01*
G01X382990Y275010D02*
Y290150D01*
G01X384990Y254000D02*
X382990Y266000D01*
X380990Y254000D01*
X384990D01*
G01X382990Y250500D02*
Y266000D01*
G01X329290D02*
X387990D01*
G01X346210Y275010D02*
X387990D01*
G01X362590Y269970D02*
X367590D01*
Y243970D01*
X362590D01*
G01X329590Y306830D02*
X341590Y308830D01*
X329590Y310830D01*
Y306830D01*
G01X339890Y308830D02*
X341590D01*
G01X340590Y350830D02*
X352590Y352830D01*
X340590Y354830D01*
Y350830D01*
G01X334890Y352830D02*
X352590D01*
G01X361090Y340830D02*
X366090D01*
Y314830D01*
X361090D01*
G01X849500Y-12451D02*
X821000Y-12500D01*
G01X931340Y624629D02*
X820000D01*
G01X846340Y725829D02*
X820000D01*
G01X849500Y-12500D02*
Y59500D01*
X893500D01*
Y-12500D01*
X849500D01*
G01X837503Y-14472D02*
X849500Y-12451D01*
X837497Y-10472D01*
X837503Y-14472D01*
G01X878500Y67000D02*
X893500Y69500D01*
X878500Y72000D01*
Y67000D01*
G01X864500Y72000D02*
X849500Y69500D01*
X864500Y67000D01*
Y72000D01*
G01X893500Y69500D02*
X849500D01*
G01Y64500D02*
Y79500D01*
G01X827500Y639629D02*
X830000Y624629D01*
X832500Y639629D01*
X827500D01*
G01X830000Y661875D02*
Y624629D01*
G01X832500Y710829D02*
X830000Y725829D01*
X827500Y710829D01*
X832500D01*
G01X830000Y693125D02*
Y725829D01*
G01X932000Y2500D02*
X934500Y-12500D01*
X937000Y2500D01*
X932000D01*
G01X934500Y11875D02*
Y-12500D01*
G01X903500D02*
X944500D01*
G01X937000Y44500D02*
X934500Y59500D01*
X932000Y44500D01*
X937000D01*
G01X934500Y43125D02*
Y59500D01*
G01X903500D02*
X944500D01*
G01X901475Y69500D02*
X893500D01*
G01Y64500D02*
Y79500D01*
G01X1114953Y628479D02*
X1131500Y617000D01*
X1132500D01*
G01X1119916Y626861D02*
X1114953Y628479D01*
X1118206Y624397D01*
X1119916Y626861D01*
G01X1156654Y242537D02*
X1274500D01*
G01X1206654Y249388D02*
X1274500D01*
G01X1271500Y230537D02*
X1269500Y242537D01*
X1267500Y230537D01*
X1271500D01*
G01X1269500Y218537D02*
Y242537D01*
G01X1267500Y261388D02*
X1269500Y249388D01*
X1271500Y261388D01*
X1267500D01*
G01X1269500Y277200D02*
Y249388D01*
G01X11750Y-48833D02*
X12417Y-49250D01*
X13167Y-49500D01*
X13833D01*
X14500Y-49250D01*
X15000Y-48833D01*
X15250Y-48250D01*
X15083Y-47667D01*
X14667Y-47167D01*
X13917Y-46833D01*
X12917Y-46667D01*
X12333Y-46333D01*
X12083Y-45750D01*
X12250Y-45167D01*
X12667Y-44750D01*
X13250Y-44500D01*
X13833D01*
X14417Y-44667D01*
X14917Y-45083D01*
G01X19100Y-46167D02*
Y-49500D01*
G01Y-44833D02*
X18933Y-44750D01*
Y-44583D01*
X19100Y-44500D01*
X19267Y-44583D01*
Y-44750D01*
X19100Y-44833D01*
G01X24700Y-49500D02*
Y-44500D01*
G01X28883Y-49500D02*
Y-44500D01*
G01X31550Y-46167D02*
X28883Y-48083D01*
G01X29967Y-47333D02*
X31717Y-49500D01*
G01X34650Y-48917D02*
X35067Y-49250D01*
X35650Y-49500D01*
X36150D01*
X36650Y-49333D01*
X36983Y-49083D01*
X37150Y-48750D01*
X37067Y-48250D01*
X36733Y-48000D01*
X35233Y-47500D01*
X34900Y-46917D01*
X35067Y-46500D01*
X35400Y-46250D01*
X35900Y-46167D01*
X36400Y-46250D01*
X36900Y-46500D01*
G01X42833Y-46583D02*
X42250Y-46250D01*
X41750Y-46167D01*
X41083Y-46333D01*
X40583Y-46667D01*
X40250Y-47250D01*
X40167Y-47833D01*
X40250Y-48417D01*
X40583Y-48917D01*
X41083Y-49333D01*
X41750Y-49500D01*
X42333Y-49333D01*
X42833Y-49000D01*
G01X45933Y-49500D02*
Y-46167D01*
G01Y-46833D02*
X46350Y-46500D01*
X46767Y-46250D01*
X47350Y-46167D01*
X47767Y-46250D01*
X48267Y-46500D01*
G01X51450Y-47250D02*
X54117D01*
X53867Y-46667D01*
X53450Y-46333D01*
X52867Y-46167D01*
X52283Y-46250D01*
X51783Y-46500D01*
X51450Y-47083D01*
X51283Y-47583D01*
Y-48083D01*
X51450Y-48583D01*
X51867Y-49083D01*
X52367Y-49417D01*
X52950Y-49500D01*
X53533Y-49333D01*
X54117Y-48833D01*
G01X57050Y-47250D02*
X59717D01*
X59467Y-46667D01*
X59050Y-46333D01*
X58467Y-46167D01*
X57883Y-46250D01*
X57383Y-46500D01*
X57050Y-47083D01*
X56883Y-47583D01*
Y-48083D01*
X57050Y-48583D01*
X57467Y-49083D01*
X57967Y-49417D01*
X58550Y-49500D01*
X59133Y-49333D01*
X59717Y-48833D01*
G01X62483Y-49500D02*
Y-46167D01*
G01Y-47000D02*
X62817Y-46583D01*
X63317Y-46250D01*
X63983Y-46167D01*
X64567Y-46250D01*
X65067Y-46583D01*
X65317Y-47167D01*
Y-49500D01*
G01X0Y-24500D02*
X694500D01*
G01X0Y716000D02*
Y-69500D01*
G01D02*
X694500D01*
G01X11750Y-3833D02*
X12417Y-4250D01*
X13167Y-4500D01*
X13833D01*
X14500Y-4250D01*
X15000Y-3833D01*
X15250Y-3250D01*
X15083Y-2667D01*
X14667Y-2167D01*
X13917Y-1833D01*
X12917Y-1667D01*
X12333Y-1333D01*
X12083Y-750D01*
X12250Y-167D01*
X12667Y250D01*
X13250Y500D01*
X13833D01*
X14417Y333D01*
X14917Y-83D01*
G01X19100Y-4500D02*
X18600Y-4417D01*
X18100Y-4083D01*
X17767Y-3500D01*
X17600Y-2833D01*
X17767Y-2167D01*
X18100Y-1583D01*
X18600Y-1250D01*
X19100Y-1167D01*
X19600Y-1250D01*
X20100Y-1583D01*
X20433Y-2167D01*
X20517Y-2833D01*
X20433Y-3500D01*
X20100Y-4083D01*
X19600Y-4417D01*
X19100Y-4500D01*
G01X24700D02*
Y500D01*
G01X31800D02*
Y-4500D01*
G01Y-3750D02*
X31467Y-4167D01*
X30967Y-4417D01*
X30383Y-4500D01*
X29717Y-4333D01*
X29217Y-3917D01*
X28883Y-3417D01*
X28800Y-2833D01*
X28883Y-2250D01*
X29217Y-1750D01*
X29717Y-1333D01*
X30383Y-1167D01*
X30967Y-1250D01*
X31383Y-1417D01*
X31800Y-1750D01*
G01X34650Y-2250D02*
X37317D01*
X37067Y-1667D01*
X36650Y-1333D01*
X36067Y-1167D01*
X35483Y-1250D01*
X34983Y-1500D01*
X34650Y-2083D01*
X34483Y-2583D01*
Y-3083D01*
X34650Y-3583D01*
X35067Y-4083D01*
X35567Y-4417D01*
X36150Y-4500D01*
X36733Y-4333D01*
X37317Y-3833D01*
G01X40333Y-4500D02*
Y-1167D01*
G01Y-1833D02*
X40750Y-1500D01*
X41167Y-1250D01*
X41750Y-1167D01*
X42167Y-1250D01*
X42667Y-1500D01*
G01X50200Y-4500D02*
Y-1167D01*
G01Y-2083D02*
X50450Y-1667D01*
X50867Y-1333D01*
X51450Y-1167D01*
X52033Y-1333D01*
X52450Y-1667D01*
X52700Y-2083D01*
Y-4500D01*
G01Y-2083D02*
X52950Y-1667D01*
X53367Y-1333D01*
X53950Y-1167D01*
X54533Y-1333D01*
X54950Y-1667D01*
X55200Y-2167D01*
Y-4500D01*
G01X59800D02*
Y-1167D01*
G01Y-1750D02*
X59467Y-1417D01*
X58967Y-1250D01*
X58383Y-1167D01*
X57800Y-1333D01*
X57300Y-1667D01*
X56967Y-2167D01*
X56800Y-2833D01*
X56967Y-3500D01*
X57300Y-4000D01*
X57800Y-4333D01*
X58383Y-4500D01*
X58967Y-4417D01*
X59467Y-4167D01*
X59800Y-3833D01*
G01X62650Y-3917D02*
X63067Y-4250D01*
X63650Y-4500D01*
X64150D01*
X64650Y-4333D01*
X64983Y-4083D01*
X65150Y-3750D01*
X65067Y-3250D01*
X64733Y-3000D01*
X63233Y-2500D01*
X62900Y-1917D01*
X63067Y-1500D01*
X63400Y-1250D01*
X63900Y-1167D01*
X64400Y-1250D01*
X64900Y-1500D01*
G01X68083Y-4500D02*
Y500D01*
G01X70750Y-1167D02*
X68083Y-3083D01*
G01X69167Y-2333D02*
X70917Y-4500D01*
G01X0Y19500D02*
X694500D01*
G01X15167Y64000D02*
X11833D01*
Y69000D01*
X15167D01*
G01X13833Y66583D02*
X11833D01*
G01X19100Y69000D02*
Y64000D01*
G01X17933Y67333D02*
X20267D01*
G01X26033Y66917D02*
X25450Y67250D01*
X24950Y67333D01*
X24283Y67167D01*
X23783Y66833D01*
X23450Y66250D01*
X23367Y65667D01*
X23450Y65083D01*
X23783Y64583D01*
X24283Y64167D01*
X24950Y64000D01*
X25533Y64167D01*
X26033Y64500D01*
G01X28883Y64000D02*
Y69000D01*
G01Y66583D02*
X29300Y67000D01*
X29717Y67250D01*
X30383Y67333D01*
X30883Y67250D01*
X31467Y66917D01*
X31717Y66417D01*
Y64000D01*
G01X15167Y111500D02*
X11833D01*
Y116500D01*
X15167D01*
G01X13833Y114083D02*
X11833D01*
G01X17850Y114833D02*
X20350Y111500D01*
G01Y114833D02*
X17850Y111500D01*
G01X24700Y116500D02*
Y111500D01*
G01X23533Y114833D02*
X25867D01*
G01X29050Y113750D02*
X31717D01*
X31467Y114333D01*
X31050Y114667D01*
X30467Y114833D01*
X29883Y114750D01*
X29383Y114500D01*
X29050Y113917D01*
X28883Y113417D01*
Y112917D01*
X29050Y112417D01*
X29467Y111917D01*
X29967Y111583D01*
X30550Y111500D01*
X31133Y111667D01*
X31717Y112167D01*
G01X34733Y111500D02*
Y114833D01*
G01Y114167D02*
X35150Y114500D01*
X35567Y114750D01*
X36150Y114833D01*
X36567Y114750D01*
X37067Y114500D01*
G01X40083Y111500D02*
Y114833D01*
G01Y114000D02*
X40417Y114417D01*
X40917Y114750D01*
X41583Y114833D01*
X42167Y114750D01*
X42667Y114417D01*
X42917Y113833D01*
Y111500D01*
G01X48600D02*
Y114833D01*
G01Y114250D02*
X48267Y114583D01*
X47767Y114750D01*
X47183Y114833D01*
X46600Y114667D01*
X46100Y114333D01*
X45767Y113833D01*
X45600Y113167D01*
X45767Y112500D01*
X46100Y112000D01*
X46600Y111667D01*
X47183Y111500D01*
X47767Y111583D01*
X48267Y111833D01*
X48600Y112167D01*
G01X52700Y111500D02*
Y116500D01*
G01X63900Y111500D02*
Y116500D01*
G01X71000Y111500D02*
Y114833D01*
G01Y114250D02*
X70667Y114583D01*
X70167Y114750D01*
X69583Y114833D01*
X69000Y114667D01*
X68500Y114333D01*
X68167Y113833D01*
X68000Y113167D01*
X68167Y112500D01*
X68500Y112000D01*
X69000Y111667D01*
X69583Y111500D01*
X70167Y111583D01*
X70667Y111833D01*
X71000Y112167D01*
G01X73350Y110000D02*
X73850Y109833D01*
X74517Y110000D01*
X74933Y110333D01*
X75267Y110750D01*
X75767Y112083D01*
X76850Y114833D01*
G01X74183D02*
X75767Y112083D01*
G01X79450Y113750D02*
X82117D01*
X81867Y114333D01*
X81450Y114667D01*
X80867Y114833D01*
X80283Y114750D01*
X79783Y114500D01*
X79450Y113917D01*
X79283Y113417D01*
Y112917D01*
X79450Y112417D01*
X79867Y111917D01*
X80367Y111583D01*
X80950Y111500D01*
X81533Y111667D01*
X82117Y112167D01*
G01X85133Y111500D02*
Y114833D01*
G01Y114167D02*
X85550Y114500D01*
X85967Y114750D01*
X86550Y114833D01*
X86967Y114750D01*
X87467Y114500D01*
G01X0Y105500D02*
X694500D01*
G01X15333Y146083D02*
X14833Y146333D01*
X14250Y146500D01*
X13583D01*
X12833Y146250D01*
X12250Y145833D01*
X11833Y145333D01*
X11500Y144500D01*
X11417Y143750D01*
X11583Y143000D01*
X11833Y142500D01*
X12333Y142000D01*
X12917Y141667D01*
X13500Y141500D01*
X14083D01*
X14667Y141667D01*
X15167Y141917D01*
X15583Y142250D01*
G01X19100Y141500D02*
X18600Y141583D01*
X18100Y141917D01*
X17767Y142500D01*
X17600Y143167D01*
X17767Y143833D01*
X18100Y144417D01*
X18600Y144750D01*
X19100Y144833D01*
X19600Y144750D01*
X20100Y144417D01*
X20433Y143833D01*
X20517Y143167D01*
X20433Y142500D01*
X20100Y141917D01*
X19600Y141583D01*
X19100Y141500D01*
G01X23200Y139833D02*
Y144833D01*
G01Y144083D02*
X23617Y144500D01*
X24033Y144750D01*
X24700Y144833D01*
X25283Y144750D01*
X25867Y144333D01*
X26117Y143750D01*
X26200Y143167D01*
X26117Y142583D01*
X25867Y142000D01*
X25367Y141667D01*
X24700Y141500D01*
X24117Y141583D01*
X23533Y141833D01*
X23200Y142167D01*
G01X28800Y139833D02*
Y144833D01*
G01Y144083D02*
X29217Y144500D01*
X29633Y144750D01*
X30300Y144833D01*
X30883Y144750D01*
X31467Y144333D01*
X31717Y143750D01*
X31800Y143167D01*
X31717Y142583D01*
X31467Y142000D01*
X30967Y141667D01*
X30300Y141500D01*
X29717Y141583D01*
X29133Y141833D01*
X28800Y142167D01*
G01X34650Y143750D02*
X37317D01*
X37067Y144333D01*
X36650Y144667D01*
X36067Y144833D01*
X35483Y144750D01*
X34983Y144500D01*
X34650Y143917D01*
X34483Y143417D01*
Y142917D01*
X34650Y142417D01*
X35067Y141917D01*
X35567Y141583D01*
X36150Y141500D01*
X36733Y141667D01*
X37317Y142167D01*
G01X40333Y141500D02*
Y144833D01*
G01Y144167D02*
X40750Y144500D01*
X41167Y144750D01*
X41750Y144833D01*
X42167Y144750D01*
X42667Y144500D01*
G01X51033Y141500D02*
Y146500D01*
X53033D01*
X53700Y146250D01*
X54200Y145667D01*
X54367Y145000D01*
X54200Y144333D01*
X53783Y143833D01*
X53033Y143583D01*
X51033D01*
G01X58300Y141500D02*
Y146500D01*
G01X65400Y141500D02*
Y144833D01*
G01Y144250D02*
X65067Y144583D01*
X64567Y144750D01*
X63983Y144833D01*
X63400Y144667D01*
X62900Y144333D01*
X62567Y143833D01*
X62400Y143167D01*
X62567Y142500D01*
X62900Y142000D01*
X63400Y141667D01*
X63983Y141500D01*
X64567Y141583D01*
X65067Y141833D01*
X65400Y142167D01*
G01X69500Y146500D02*
Y141500D01*
G01X68333Y144833D02*
X70667D01*
G01X75100D02*
Y141500D01*
G01Y146167D02*
X74933Y146250D01*
Y146417D01*
X75100Y146500D01*
X75267Y146417D01*
Y146250D01*
X75100Y146167D01*
G01X79283Y141500D02*
Y144833D01*
G01Y144000D02*
X79617Y144417D01*
X80117Y144750D01*
X80783Y144833D01*
X81367Y144750D01*
X81867Y144417D01*
X82117Y143833D01*
Y141500D01*
G01X85133Y140250D02*
X85717Y139917D01*
X86383Y139833D01*
X86967Y139917D01*
X87467Y140333D01*
X87800Y140917D01*
Y144833D01*
G01Y144167D02*
X87467Y144500D01*
X86967Y144750D01*
X86383Y144833D01*
X85717Y144667D01*
X85300Y144333D01*
X84967Y143750D01*
X84800Y143167D01*
X84883Y142667D01*
X85217Y142083D01*
X85717Y141667D01*
X86383Y141500D01*
X86883Y141583D01*
X87467Y141917D01*
X87800Y142250D01*
G01X0Y120500D02*
X694500D01*
G01X1500Y175500D02*
X694500D01*
G01X11667Y459000D02*
Y464000D01*
X13333D01*
X14000Y463750D01*
X14500Y463417D01*
X14917Y462917D01*
X15250Y462333D01*
X15333Y461500D01*
X15250Y460667D01*
X14917Y460083D01*
X14500Y459583D01*
X14000Y459250D01*
X13333Y459000D01*
X11667D01*
G01X17933D02*
Y462333D01*
G01Y461667D02*
X18350Y462000D01*
X18767Y462250D01*
X19350Y462333D01*
X19767Y462250D01*
X20267Y462000D01*
G01X24700Y462333D02*
Y459000D01*
G01Y463667D02*
X24533Y463750D01*
Y463917D01*
X24700Y464000D01*
X24867Y463917D01*
Y463750D01*
X24700Y463667D01*
G01X30300Y459000D02*
Y464000D01*
G01X35900Y459000D02*
Y464000D01*
G01X0Y599000D02*
X694500D01*
G01X-1000Y654000D02*
X694500D01*
G01X9917Y693667D02*
X10417Y694167D01*
X11000Y694417D01*
X11667Y694500D01*
X12500Y694333D01*
X13083Y693917D01*
X13250Y693417D01*
X13167Y692917D01*
X12833Y692500D01*
X11167Y691667D01*
X10417Y691083D01*
X9917Y690250D01*
X9750Y689500D01*
X13250D01*
G01X17100Y689333D02*
X16933Y689417D01*
Y689583D01*
X17100Y689667D01*
X17267Y689583D01*
Y689417D01*
X17100Y689333D01*
G01X22700Y694500D02*
Y689500D01*
G01X20783Y694500D02*
X24617D01*
G01X28300Y689500D02*
X27800Y689583D01*
X27300Y689917D01*
X26967Y690500D01*
X26800Y691167D01*
X26967Y691833D01*
X27300Y692417D01*
X27800Y692750D01*
X28300Y692833D01*
X28800Y692750D01*
X29300Y692417D01*
X29633Y691833D01*
X29717Y691167D01*
X29633Y690500D01*
X29300Y689917D01*
X28800Y689583D01*
X28300Y689500D01*
G01X33900D02*
Y694500D01*
G01X38250Y691750D02*
X40917D01*
X40667Y692333D01*
X40250Y692667D01*
X39667Y692833D01*
X39083Y692750D01*
X38583Y692500D01*
X38250Y691917D01*
X38083Y691417D01*
Y690917D01*
X38250Y690417D01*
X38667Y689917D01*
X39167Y689583D01*
X39750Y689500D01*
X40333Y689667D01*
X40917Y690167D01*
G01X43933Y689500D02*
Y692833D01*
G01Y692167D02*
X44350Y692500D01*
X44767Y692750D01*
X45350Y692833D01*
X45767Y692750D01*
X46267Y692500D01*
G01X52200Y689500D02*
Y692833D01*
G01Y692250D02*
X51867Y692583D01*
X51367Y692750D01*
X50783Y692833D01*
X50200Y692667D01*
X49700Y692333D01*
X49367Y691833D01*
X49200Y691167D01*
X49367Y690500D01*
X49700Y690000D01*
X50200Y689667D01*
X50783Y689500D01*
X51367Y689583D01*
X51867Y689833D01*
X52200Y690167D01*
G01X54883Y689500D02*
Y692833D01*
G01Y692000D02*
X55217Y692417D01*
X55717Y692750D01*
X56383Y692833D01*
X56967Y692750D01*
X57467Y692417D01*
X57717Y691833D01*
Y689500D01*
G01X63233Y692417D02*
X62650Y692750D01*
X62150Y692833D01*
X61483Y692667D01*
X60983Y692333D01*
X60650Y691750D01*
X60567Y691167D01*
X60650Y690583D01*
X60983Y690083D01*
X61483Y689667D01*
X62150Y689500D01*
X62733Y689667D01*
X63233Y690000D01*
G01X66250Y691750D02*
X68917D01*
X68667Y692333D01*
X68250Y692667D01*
X67667Y692833D01*
X67083Y692750D01*
X66583Y692500D01*
X66250Y691917D01*
X66083Y691417D01*
Y690917D01*
X66250Y690417D01*
X66667Y689917D01*
X67167Y689583D01*
X67750Y689500D01*
X68333Y689667D01*
X68917Y690167D01*
G01X78700Y694500D02*
Y689500D01*
G01X77533Y692833D02*
X79867D01*
G01X85800Y689500D02*
Y692833D01*
G01Y692250D02*
X85467Y692583D01*
X84967Y692750D01*
X84383Y692833D01*
X83800Y692667D01*
X83300Y692333D01*
X82967Y691833D01*
X82800Y691167D01*
X82967Y690500D01*
X83300Y690000D01*
X83800Y689667D01*
X84383Y689500D01*
X84967Y689583D01*
X85467Y689833D01*
X85800Y690167D01*
G01X88400Y689500D02*
Y694500D01*
G01Y692000D02*
X88817Y692500D01*
X89317Y692750D01*
X89817Y692833D01*
X90567Y692667D01*
X91067Y692333D01*
X91400Y691750D01*
Y691083D01*
X91233Y690417D01*
X90900Y689917D01*
X90317Y689583D01*
X89817Y689500D01*
X89317Y689583D01*
X88817Y689833D01*
X88400Y690250D01*
G01X95500Y689500D02*
Y694500D01*
G01X99850Y691750D02*
X102517D01*
X102267Y692333D01*
X101850Y692667D01*
X101267Y692833D01*
X100683Y692750D01*
X100183Y692500D01*
X99850Y691917D01*
X99683Y691417D01*
Y690917D01*
X99850Y690417D01*
X100267Y689917D01*
X100767Y689583D01*
X101350Y689500D01*
X101933Y689667D01*
X102517Y690167D01*
G01X106700Y689333D02*
X106533Y689417D01*
Y689583D01*
X106700Y689667D01*
X106867Y689583D01*
Y689417D01*
X106700Y689333D01*
G01Y691583D02*
X106533Y691667D01*
Y691833D01*
X106700Y691917D01*
X106867Y691833D01*
Y691667D01*
X106700Y691583D01*
G01X0Y679000D02*
X694500D01*
G01X0Y850500D02*
Y709000D01*
X694500D01*
Y850500D01*
G01X7000Y832500D02*
Y837500D01*
X6000Y836500D01*
G01Y832500D02*
X8000D01*
G01X12600Y832333D02*
X12433Y832417D01*
Y832583D01*
X12600Y832667D01*
X12767Y832583D01*
Y832417D01*
X12600Y832333D01*
G01X16450Y833167D02*
X17117Y832750D01*
X17867Y832500D01*
X18533D01*
X19200Y832750D01*
X19700Y833167D01*
X19950Y833750D01*
X19783Y834333D01*
X19367Y834833D01*
X18617Y835167D01*
X17617Y835333D01*
X17033Y835667D01*
X16783Y836250D01*
X16950Y836833D01*
X17367Y837250D01*
X17950Y837500D01*
X18533D01*
X19117Y837333D01*
X19617Y836917D01*
G01X22300Y830833D02*
Y835833D01*
G01Y835083D02*
X22717Y835500D01*
X23133Y835750D01*
X23800Y835833D01*
X24383Y835750D01*
X24967Y835333D01*
X25217Y834750D01*
X25300Y834167D01*
X25217Y833583D01*
X24967Y833000D01*
X24467Y832667D01*
X23800Y832500D01*
X23217Y832583D01*
X22633Y832833D01*
X22300Y833167D01*
G01X28150Y834750D02*
X30817D01*
X30567Y835333D01*
X30150Y835667D01*
X29567Y835833D01*
X28983Y835750D01*
X28483Y835500D01*
X28150Y834917D01*
X27983Y834417D01*
Y833917D01*
X28150Y833417D01*
X28567Y832917D01*
X29067Y832583D01*
X29650Y832500D01*
X30233Y832667D01*
X30817Y833167D01*
G01X36333Y835417D02*
X35750Y835750D01*
X35250Y835833D01*
X34583Y835667D01*
X34083Y835333D01*
X33750Y834750D01*
X33667Y834167D01*
X33750Y833583D01*
X34083Y833083D01*
X34583Y832667D01*
X35250Y832500D01*
X35833Y832667D01*
X36333Y833000D01*
G01X40600Y835833D02*
Y832500D01*
G01Y837167D02*
X40433Y837250D01*
Y837417D01*
X40600Y837500D01*
X40767Y837417D01*
Y837250D01*
X40600Y837167D01*
G01X45700Y832500D02*
Y836750D01*
X45867Y837167D01*
X46200Y837417D01*
X46700Y837500D01*
X47200Y837333D01*
X47450Y836917D01*
G01X46450Y835500D02*
X44783D01*
G01X51800Y835833D02*
Y832500D01*
G01Y837167D02*
X51633Y837250D01*
Y837417D01*
X51800Y837500D01*
X51967Y837417D01*
Y837250D01*
X51800Y837167D01*
G01X58733Y835417D02*
X58150Y835750D01*
X57650Y835833D01*
X56983Y835667D01*
X56483Y835333D01*
X56150Y834750D01*
X56067Y834167D01*
X56150Y833583D01*
X56483Y833083D01*
X56983Y832667D01*
X57650Y832500D01*
X58233Y832667D01*
X58733Y833000D01*
G01X64500Y832500D02*
Y835833D01*
G01Y835250D02*
X64167Y835583D01*
X63667Y835750D01*
X63083Y835833D01*
X62500Y835667D01*
X62000Y835333D01*
X61667Y834833D01*
X61500Y834167D01*
X61667Y833500D01*
X62000Y833000D01*
X62500Y832667D01*
X63083Y832500D01*
X63667Y832583D01*
X64167Y832833D01*
X64500Y833167D01*
G01X68600Y837500D02*
Y832500D01*
G01X67433Y835833D02*
X69767D01*
G01X74200D02*
Y832500D01*
G01Y837167D02*
X74033Y837250D01*
Y837417D01*
X74200Y837500D01*
X74367Y837417D01*
Y837250D01*
X74200Y837167D01*
G01X79800Y832500D02*
X79300Y832583D01*
X78800Y832917D01*
X78467Y833500D01*
X78300Y834167D01*
X78467Y834833D01*
X78800Y835417D01*
X79300Y835750D01*
X79800Y835833D01*
X80300Y835750D01*
X80800Y835417D01*
X81133Y834833D01*
X81217Y834167D01*
X81133Y833500D01*
X80800Y832917D01*
X80300Y832583D01*
X79800Y832500D01*
G01X83983D02*
Y835833D01*
G01Y835000D02*
X84317Y835417D01*
X84817Y835750D01*
X85483Y835833D01*
X86067Y835750D01*
X86567Y835417D01*
X86817Y834833D01*
Y832500D01*
G01X98100Y837500D02*
Y832500D01*
G01Y833250D02*
X97767Y832833D01*
X97267Y832583D01*
X96683Y832500D01*
X96017Y832667D01*
X95517Y833083D01*
X95183Y833583D01*
X95100Y834167D01*
X95183Y834750D01*
X95517Y835250D01*
X96017Y835667D01*
X96683Y835833D01*
X97267Y835750D01*
X97683Y835583D01*
X98100Y835250D01*
G01X102200Y832500D02*
X101700Y832583D01*
X101200Y832917D01*
X100867Y833500D01*
X100700Y834167D01*
X100867Y834833D01*
X101200Y835417D01*
X101700Y835750D01*
X102200Y835833D01*
X102700Y835750D01*
X103200Y835417D01*
X103533Y834833D01*
X103617Y834167D01*
X103533Y833500D01*
X103200Y832917D01*
X102700Y832583D01*
X102200Y832500D01*
G01X109133Y835417D02*
X108550Y835750D01*
X108050Y835833D01*
X107383Y835667D01*
X106883Y835333D01*
X106550Y834750D01*
X106467Y834167D01*
X106550Y833583D01*
X106883Y833083D01*
X107383Y832667D01*
X108050Y832500D01*
X108633Y832667D01*
X109133Y833000D01*
G01X111983Y835833D02*
Y833500D01*
X112317Y832917D01*
X112817Y832583D01*
X113400Y832500D01*
X113983Y832583D01*
X114483Y832917D01*
X114817Y833500D01*
G01Y832500D02*
Y835833D01*
G01X116500Y832500D02*
Y835833D01*
G01Y834917D02*
X116750Y835333D01*
X117167Y835667D01*
X117750Y835833D01*
X118333Y835667D01*
X118750Y835333D01*
X119000Y834917D01*
Y832500D01*
G01Y834917D02*
X119250Y835333D01*
X119667Y835667D01*
X120250Y835833D01*
X120833Y835667D01*
X121250Y835333D01*
X121500Y834833D01*
Y832500D01*
G01X123350Y834750D02*
X126017D01*
X125767Y835333D01*
X125350Y835667D01*
X124767Y835833D01*
X124183Y835750D01*
X123683Y835500D01*
X123350Y834917D01*
X123183Y834417D01*
Y833917D01*
X123350Y833417D01*
X123767Y832917D01*
X124267Y832583D01*
X124850Y832500D01*
X125433Y832667D01*
X126017Y833167D01*
G01X128783Y832500D02*
Y835833D01*
G01Y835000D02*
X129117Y835417D01*
X129617Y835750D01*
X130283Y835833D01*
X130867Y835750D01*
X131367Y835417D01*
X131617Y834833D01*
Y832500D01*
G01X135800Y837500D02*
Y832500D01*
G01X134633Y835833D02*
X136967D01*
G01X141400Y832333D02*
X141233Y832417D01*
Y832583D01*
X141400Y832667D01*
X141567Y832583D01*
Y832417D01*
X141400Y832333D01*
G01Y834583D02*
X141233Y834667D01*
Y834833D01*
X141400Y834917D01*
X141567Y834833D01*
Y834667D01*
X141400Y834583D01*
G01X0Y820500D02*
X694500D01*
G01X0Y850500D02*
X694500D01*
G01X24960Y626740D02*
X26960D01*
G01X25960D02*
Y621740D01*
G01X24960D02*
X26960D01*
G01X30143D02*
Y625073D01*
G01Y624240D02*
X30477Y624657D01*
X30977Y624990D01*
X31643Y625073D01*
X32227Y624990D01*
X32727Y624657D01*
X32977Y624073D01*
Y621740D01*
G01X35743D02*
Y625073D01*
G01Y624240D02*
X36077Y624657D01*
X36577Y624990D01*
X37243Y625073D01*
X37827Y624990D01*
X38327Y624657D01*
X38577Y624073D01*
Y621740D01*
G01X41510Y623990D02*
X44177D01*
X43927Y624573D01*
X43510Y624907D01*
X42927Y625073D01*
X42343Y624990D01*
X41843Y624740D01*
X41510Y624157D01*
X41343Y623657D01*
Y623157D01*
X41510Y622657D01*
X41927Y622157D01*
X42427Y621823D01*
X43010Y621740D01*
X43593Y621907D01*
X44177Y622407D01*
G01X47193Y621740D02*
Y625073D01*
G01Y624407D02*
X47610Y624740D01*
X48027Y624990D01*
X48610Y625073D01*
X49027Y624990D01*
X49527Y624740D01*
G01X59560Y621740D02*
Y626740D01*
G01X66660Y621740D02*
Y625073D01*
G01Y624490D02*
X66327Y624823D01*
X65827Y624990D01*
X65243Y625073D01*
X64660Y624907D01*
X64160Y624573D01*
X63827Y624073D01*
X63660Y623407D01*
X63827Y622740D01*
X64160Y622240D01*
X64660Y621907D01*
X65243Y621740D01*
X65827Y621823D01*
X66327Y622073D01*
X66660Y622407D01*
G01X69010Y620240D02*
X69510Y620073D01*
X70177Y620240D01*
X70593Y620573D01*
X70927Y620990D01*
X71427Y622323D01*
X72510Y625073D01*
G01X69843D02*
X71427Y622323D01*
G01X75110Y623990D02*
X77777D01*
X77527Y624573D01*
X77110Y624907D01*
X76527Y625073D01*
X75943Y624990D01*
X75443Y624740D01*
X75110Y624157D01*
X74943Y623657D01*
Y623157D01*
X75110Y622657D01*
X75527Y622157D01*
X76027Y621823D01*
X76610Y621740D01*
X77193Y621907D01*
X77777Y622407D01*
G01X80793Y621740D02*
Y625073D01*
G01Y624407D02*
X81210Y624740D01*
X81627Y624990D01*
X82210Y625073D01*
X82627Y624990D01*
X83127Y624740D01*
G01X34000Y663333D02*
Y668333D01*
G01Y667583D02*
X34417Y668000D01*
X34833Y668250D01*
X35500Y668333D01*
X36083Y668250D01*
X36667Y667833D01*
X36917Y667250D01*
X37000Y666667D01*
X36917Y666083D01*
X36667Y665500D01*
X36167Y665167D01*
X35500Y665000D01*
X34917Y665083D01*
X34333Y665333D01*
X34000Y665667D01*
G01X39933Y665000D02*
Y668333D01*
G01Y667667D02*
X40350Y668000D01*
X40767Y668250D01*
X41350Y668333D01*
X41767Y668250D01*
X42267Y668000D01*
G01X46700Y665000D02*
X46200Y665083D01*
X45700Y665417D01*
X45367Y666000D01*
X45200Y666667D01*
X45367Y667333D01*
X45700Y667917D01*
X46200Y668250D01*
X46700Y668333D01*
X47200Y668250D01*
X47700Y667917D01*
X48033Y667333D01*
X48117Y666667D01*
X48033Y666000D01*
X47700Y665417D01*
X47200Y665083D01*
X46700Y665000D01*
G01X53633Y667917D02*
X53050Y668250D01*
X52550Y668333D01*
X51883Y668167D01*
X51383Y667833D01*
X51050Y667250D01*
X50967Y666667D01*
X51050Y666083D01*
X51383Y665583D01*
X51883Y665167D01*
X52550Y665000D01*
X53133Y665167D01*
X53633Y665500D01*
G01X56650Y667250D02*
X59317D01*
X59067Y667833D01*
X58650Y668167D01*
X58067Y668333D01*
X57483Y668250D01*
X56983Y668000D01*
X56650Y667417D01*
X56483Y666917D01*
Y666417D01*
X56650Y665917D01*
X57067Y665417D01*
X57567Y665083D01*
X58150Y665000D01*
X58733Y665167D01*
X59317Y665667D01*
G01X62250Y665583D02*
X62667Y665250D01*
X63250Y665000D01*
X63750D01*
X64250Y665167D01*
X64583Y665417D01*
X64750Y665750D01*
X64667Y666250D01*
X64333Y666500D01*
X62833Y667000D01*
X62500Y667583D01*
X62667Y668000D01*
X63000Y668250D01*
X63500Y668333D01*
X64000Y668250D01*
X64500Y668000D01*
G01X67850Y665583D02*
X68267Y665250D01*
X68850Y665000D01*
X69350D01*
X69850Y665167D01*
X70183Y665417D01*
X70350Y665750D01*
X70267Y666250D01*
X69933Y666500D01*
X68433Y667000D01*
X68100Y667583D01*
X68267Y668000D01*
X68600Y668250D01*
X69100Y668333D01*
X69600Y668250D01*
X70100Y668000D01*
G01X67000Y725433D02*
X66833Y725517D01*
Y725683D01*
X67000Y725767D01*
X67167Y725683D01*
Y725517D01*
X67000Y725433D01*
G01Y734433D02*
X66833Y734517D01*
Y734683D01*
X67000Y734767D01*
X67167Y734683D01*
Y734517D01*
X67000Y734433D01*
G01X71000Y729600D02*
X73000D01*
G01X72000D02*
Y724600D01*
G01X71000D02*
X73000D01*
G01X75933D02*
Y729600D01*
X77933D01*
X78600Y729350D01*
X79100Y728767D01*
X79267Y728100D01*
X79100Y727433D01*
X78683Y726933D01*
X77933Y726683D01*
X75933D01*
G01X85033Y729183D02*
X84533Y729433D01*
X83950Y729600D01*
X83283D01*
X82533Y729350D01*
X81950Y728933D01*
X81533Y728433D01*
X81200Y727600D01*
X81117Y726850D01*
X81283Y726100D01*
X81533Y725600D01*
X82033Y725100D01*
X82617Y724767D01*
X83200Y724600D01*
X83783D01*
X84367Y724767D01*
X84867Y725017D01*
X85283Y725350D01*
G01X87717Y726267D02*
X89883D01*
G01X92733Y729600D02*
Y724600D01*
X96067D01*
G01X98917Y726267D02*
X101083D01*
G01X105600Y724600D02*
Y729600D01*
X104600Y728600D01*
G01Y724600D02*
X106600D01*
G01X111200Y729600D02*
X110533Y729433D01*
X110033Y729017D01*
X109700Y728517D01*
X109450Y727850D01*
X109367Y727100D01*
X109450Y726350D01*
X109700Y725683D01*
X110033Y725183D01*
X110533Y724767D01*
X111200Y724600D01*
X111867Y724767D01*
X112367Y725183D01*
X112700Y725683D01*
X112950Y726350D01*
X113033Y727100D01*
X112950Y727850D01*
X112700Y728517D01*
X112367Y729017D01*
X111867Y729433D01*
X111200Y729600D01*
G01X115383Y725183D02*
X115967Y724767D01*
X116633Y724600D01*
X117300Y724767D01*
X117883Y725267D01*
X118300Y726017D01*
X118467Y726767D01*
Y727683D01*
X118300Y728433D01*
X117883Y729100D01*
X117383Y729433D01*
X116800Y729600D01*
X116133Y729433D01*
X115633Y729100D01*
X115300Y728600D01*
X115133Y727933D01*
X115300Y727350D01*
X115717Y726767D01*
X116217Y726433D01*
X116800Y726350D01*
X117467Y726517D01*
X117967Y726933D01*
X118467Y727683D01*
G01X126250Y725267D02*
X126917Y724850D01*
X127667Y724600D01*
X128333D01*
X129000Y724850D01*
X129500Y725267D01*
X129750Y725850D01*
X129583Y726433D01*
X129167Y726933D01*
X128417Y727267D01*
X127417Y727433D01*
X126833Y727767D01*
X126583Y728350D01*
X126750Y728933D01*
X127167Y729350D01*
X127750Y729600D01*
X128333D01*
X128917Y729433D01*
X129417Y729017D01*
G01X132100Y722933D02*
Y727933D01*
G01Y727183D02*
X132517Y727600D01*
X132933Y727850D01*
X133600Y727933D01*
X134183Y727850D01*
X134767Y727433D01*
X135017Y726850D01*
X135100Y726267D01*
X135017Y725683D01*
X134767Y725100D01*
X134267Y724767D01*
X133600Y724600D01*
X133017Y724683D01*
X132433Y724933D01*
X132100Y725267D01*
G01X137950Y726850D02*
X140617D01*
X140367Y727433D01*
X139950Y727767D01*
X139367Y727933D01*
X138783Y727850D01*
X138283Y727600D01*
X137950Y727017D01*
X137783Y726517D01*
Y726017D01*
X137950Y725517D01*
X138367Y725017D01*
X138867Y724683D01*
X139450Y724600D01*
X140033Y724767D01*
X140617Y725267D01*
G01X146133Y727517D02*
X145550Y727850D01*
X145050Y727933D01*
X144383Y727767D01*
X143883Y727433D01*
X143550Y726850D01*
X143467Y726267D01*
X143550Y725683D01*
X143883Y725183D01*
X144383Y724767D01*
X145050Y724600D01*
X145633Y724767D01*
X146133Y725100D01*
G01X150400Y727933D02*
Y724600D01*
G01Y729267D02*
X150233Y729350D01*
Y729517D01*
X150400Y729600D01*
X150567Y729517D01*
Y729350D01*
X150400Y729267D01*
G01X155500Y724600D02*
Y728850D01*
X155667Y729267D01*
X156000Y729517D01*
X156500Y729600D01*
X157000Y729433D01*
X157250Y729017D01*
G01X156250Y727600D02*
X154583D01*
G01X161600Y727933D02*
Y724600D01*
G01Y729267D02*
X161433Y729350D01*
Y729517D01*
X161600Y729600D01*
X161767Y729517D01*
Y729350D01*
X161600Y729267D01*
G01X168533Y727517D02*
X167950Y727850D01*
X167450Y727933D01*
X166783Y727767D01*
X166283Y727433D01*
X165950Y726850D01*
X165867Y726267D01*
X165950Y725683D01*
X166283Y725183D01*
X166783Y724767D01*
X167450Y724600D01*
X168033Y724767D01*
X168533Y725100D01*
G01X174300Y724600D02*
Y727933D01*
G01Y727350D02*
X173967Y727683D01*
X173467Y727850D01*
X172883Y727933D01*
X172300Y727767D01*
X171800Y727433D01*
X171467Y726933D01*
X171300Y726267D01*
X171467Y725600D01*
X171800Y725100D01*
X172300Y724767D01*
X172883Y724600D01*
X173467Y724683D01*
X173967Y724933D01*
X174300Y725267D01*
G01X178400Y729600D02*
Y724600D01*
G01X177233Y727933D02*
X179567D01*
G01X184000D02*
Y724600D01*
G01Y729267D02*
X183833Y729350D01*
Y729517D01*
X184000Y729600D01*
X184167Y729517D01*
Y729350D01*
X184000Y729267D01*
G01X189600Y724600D02*
X189100Y724683D01*
X188600Y725017D01*
X188267Y725600D01*
X188100Y726267D01*
X188267Y726933D01*
X188600Y727517D01*
X189100Y727850D01*
X189600Y727933D01*
X190100Y727850D01*
X190600Y727517D01*
X190933Y726933D01*
X191017Y726267D01*
X190933Y725600D01*
X190600Y725017D01*
X190100Y724683D01*
X189600Y724600D01*
G01X193783D02*
Y727933D01*
G01Y727100D02*
X194117Y727517D01*
X194617Y727850D01*
X195283Y727933D01*
X195867Y727850D01*
X196367Y727517D01*
X196617Y726933D01*
Y724600D01*
G01X205900D02*
Y728850D01*
X206067Y729267D01*
X206400Y729517D01*
X206900Y729600D01*
X207400Y729433D01*
X207650Y729017D01*
G01X206650Y727600D02*
X204983D01*
G01X212000Y724600D02*
X211500Y724683D01*
X211000Y725017D01*
X210667Y725600D01*
X210500Y726267D01*
X210667Y726933D01*
X211000Y727517D01*
X211500Y727850D01*
X212000Y727933D01*
X212500Y727850D01*
X213000Y727517D01*
X213333Y726933D01*
X213417Y726267D01*
X213333Y725600D01*
X213000Y725017D01*
X212500Y724683D01*
X212000Y724600D01*
G01X216433D02*
Y727933D01*
G01Y727267D02*
X216850Y727600D01*
X217267Y727850D01*
X217850Y727933D01*
X218267Y727850D01*
X218767Y727600D01*
G01X227133Y724600D02*
Y729600D01*
X229217D01*
X229883Y729350D01*
X230300Y729017D01*
X230467Y728350D01*
X230300Y727683D01*
X229800Y727267D01*
X229217Y727017D01*
X227133D01*
G01X229217D02*
X230467Y724600D01*
G01X233150Y726850D02*
X235817D01*
X235567Y727433D01*
X235150Y727767D01*
X234567Y727933D01*
X233983Y727850D01*
X233483Y727600D01*
X233150Y727017D01*
X232983Y726517D01*
Y726017D01*
X233150Y725517D01*
X233567Y725017D01*
X234067Y724683D01*
X234650Y724600D01*
X235233Y724767D01*
X235817Y725267D01*
G01X238750Y725183D02*
X239167Y724850D01*
X239750Y724600D01*
X240250D01*
X240750Y724767D01*
X241083Y725017D01*
X241250Y725350D01*
X241167Y725850D01*
X240833Y726100D01*
X239333Y726600D01*
X239000Y727183D01*
X239167Y727600D01*
X239500Y727850D01*
X240000Y727933D01*
X240500Y727850D01*
X241000Y727600D01*
G01X245600Y727933D02*
Y724600D01*
G01Y729267D02*
X245433Y729350D01*
Y729517D01*
X245600Y729600D01*
X245767Y729517D01*
Y729350D01*
X245600Y729267D01*
G01X249783Y724600D02*
Y727933D01*
G01Y727100D02*
X250117Y727517D01*
X250617Y727850D01*
X251283Y727933D01*
X251867Y727850D01*
X252367Y727517D01*
X252617Y726933D01*
Y724600D01*
G01X261400Y729600D02*
X263400D01*
G01X262400D02*
Y724600D01*
G01X261400D02*
X263400D01*
G01X265500D02*
Y727933D01*
G01Y727017D02*
X265750Y727433D01*
X266167Y727767D01*
X266750Y727933D01*
X267333Y727767D01*
X267750Y727433D01*
X268000Y727017D01*
Y724600D01*
G01Y727017D02*
X268250Y727433D01*
X268667Y727767D01*
X269250Y727933D01*
X269833Y727767D01*
X270250Y727433D01*
X270500Y726933D01*
Y724600D01*
G01X272100Y722933D02*
Y727933D01*
G01Y727183D02*
X272517Y727600D01*
X272933Y727850D01*
X273600Y727933D01*
X274183Y727850D01*
X274767Y727433D01*
X275017Y726850D01*
X275100Y726267D01*
X275017Y725683D01*
X274767Y725100D01*
X274267Y724767D01*
X273600Y724600D01*
X273017Y724683D01*
X272433Y724933D01*
X272100Y725267D01*
G01X278033Y724600D02*
Y727933D01*
G01Y727267D02*
X278450Y727600D01*
X278867Y727850D01*
X279450Y727933D01*
X279867Y727850D01*
X280367Y727600D01*
G01X283550Y726850D02*
X286217D01*
X285967Y727433D01*
X285550Y727767D01*
X284967Y727933D01*
X284383Y727850D01*
X283883Y727600D01*
X283550Y727017D01*
X283383Y726517D01*
Y726017D01*
X283550Y725517D01*
X283967Y725017D01*
X284467Y724683D01*
X285050Y724600D01*
X285633Y724767D01*
X286217Y725267D01*
G01X289233Y723350D02*
X289817Y723017D01*
X290483Y722933D01*
X291067Y723017D01*
X291567Y723433D01*
X291900Y724017D01*
Y727933D01*
G01Y727267D02*
X291567Y727600D01*
X291067Y727850D01*
X290483Y727933D01*
X289817Y727767D01*
X289400Y727433D01*
X289067Y726850D01*
X288900Y726267D01*
X288983Y725767D01*
X289317Y725183D01*
X289817Y724767D01*
X290483Y724600D01*
X290983Y724683D01*
X291567Y725017D01*
X291900Y725350D01*
G01X294583Y724600D02*
Y727933D01*
G01Y727100D02*
X294917Y727517D01*
X295417Y727850D01*
X296083Y727933D01*
X296667Y727850D01*
X297167Y727517D01*
X297417Y726933D01*
Y724600D01*
G01X303100D02*
Y727933D01*
G01Y727350D02*
X302767Y727683D01*
X302267Y727850D01*
X301683Y727933D01*
X301100Y727767D01*
X300600Y727433D01*
X300267Y726933D01*
X300100Y726267D01*
X300267Y725600D01*
X300600Y725100D01*
X301100Y724767D01*
X301683Y724600D01*
X302267Y724683D01*
X302767Y724933D01*
X303100Y725267D01*
G01X307200Y729600D02*
Y724600D01*
G01X306033Y727933D02*
X308367D01*
G01X311550Y726850D02*
X314217D01*
X313967Y727433D01*
X313550Y727767D01*
X312967Y727933D01*
X312383Y727850D01*
X311883Y727600D01*
X311550Y727017D01*
X311383Y726517D01*
Y726017D01*
X311550Y725517D01*
X311967Y725017D01*
X312467Y724683D01*
X313050Y724600D01*
X313633Y724767D01*
X314217Y725267D01*
G01X319900Y729600D02*
Y724600D01*
G01Y725350D02*
X319567Y724933D01*
X319067Y724683D01*
X318483Y724600D01*
X317817Y724767D01*
X317317Y725183D01*
X316983Y725683D01*
X316900Y726267D01*
X316983Y726850D01*
X317317Y727350D01*
X317817Y727767D01*
X318483Y727933D01*
X319067Y727850D01*
X319483Y727683D01*
X319900Y727350D01*
G01X328017Y724600D02*
Y729600D01*
X331183D01*
G01X330017Y727183D02*
X328017D01*
G01X336700Y724600D02*
Y727933D01*
G01Y727350D02*
X336367Y727683D01*
X335867Y727850D01*
X335283Y727933D01*
X334700Y727767D01*
X334200Y727433D01*
X333867Y726933D01*
X333700Y726267D01*
X333867Y725600D01*
X334200Y725100D01*
X334700Y724767D01*
X335283Y724600D01*
X335867Y724683D01*
X336367Y724933D01*
X336700Y725267D01*
G01X339300Y724600D02*
Y729600D01*
G01Y727100D02*
X339717Y727600D01*
X340217Y727850D01*
X340717Y727933D01*
X341467Y727767D01*
X341967Y727433D01*
X342300Y726850D01*
Y726183D01*
X342133Y725517D01*
X341800Y725017D01*
X341217Y724683D01*
X340717Y724600D01*
X340217Y724683D01*
X339717Y724933D01*
X339300Y725350D01*
G01X345233Y724600D02*
Y727933D01*
G01Y727267D02*
X345650Y727600D01*
X346067Y727850D01*
X346650Y727933D01*
X347067Y727850D01*
X347567Y727600D01*
G01X352000Y727933D02*
Y724600D01*
G01Y729267D02*
X351833Y729350D01*
Y729517D01*
X352000Y729600D01*
X352167Y729517D01*
Y729350D01*
X352000Y729267D01*
G01X358933Y727517D02*
X358350Y727850D01*
X357850Y727933D01*
X357183Y727767D01*
X356683Y727433D01*
X356350Y726850D01*
X356267Y726267D01*
X356350Y725683D01*
X356683Y725183D01*
X357183Y724767D01*
X357850Y724600D01*
X358433Y724767D01*
X358933Y725100D01*
G01X362783Y722933D02*
X361950Y723767D01*
X361533Y724600D01*
Y727933D01*
X361950Y728767D01*
X362783Y729600D01*
G01X367133Y724600D02*
Y729600D01*
X369133D01*
X369800Y729350D01*
X370300Y728767D01*
X370467Y728100D01*
X370300Y727433D01*
X369883Y726933D01*
X369133Y726683D01*
X367133D01*
G01X373233Y724600D02*
Y727933D01*
G01Y727267D02*
X373650Y727600D01*
X374067Y727850D01*
X374650Y727933D01*
X375067Y727850D01*
X375567Y727600D01*
G01X378750Y726850D02*
X381417D01*
X381167Y727433D01*
X380750Y727767D01*
X380167Y727933D01*
X379583Y727850D01*
X379083Y727600D01*
X378750Y727017D01*
X378583Y726517D01*
Y726017D01*
X378750Y725517D01*
X379167Y725017D01*
X379667Y724683D01*
X380250Y724600D01*
X380833Y724767D01*
X381417Y725267D01*
G01X384100Y722933D02*
Y727933D01*
G01Y727183D02*
X384517Y727600D01*
X384933Y727850D01*
X385600Y727933D01*
X386183Y727850D01*
X386767Y727433D01*
X387017Y726850D01*
X387100Y726267D01*
X387017Y725683D01*
X386767Y725100D01*
X386267Y724767D01*
X385600Y724600D01*
X385017Y724683D01*
X384433Y724933D01*
X384100Y725267D01*
G01X390033Y724600D02*
Y727933D01*
G01Y727267D02*
X390450Y727600D01*
X390867Y727850D01*
X391450Y727933D01*
X391867Y727850D01*
X392367Y727600D01*
G01X395550Y726850D02*
X398217D01*
X397967Y727433D01*
X397550Y727767D01*
X396967Y727933D01*
X396383Y727850D01*
X395883Y727600D01*
X395550Y727017D01*
X395383Y726517D01*
Y726017D01*
X395550Y725517D01*
X395967Y725017D01*
X396467Y724683D01*
X397050Y724600D01*
X397633Y724767D01*
X398217Y725267D01*
G01X401233Y723350D02*
X401817Y723017D01*
X402483Y722933D01*
X403067Y723017D01*
X403567Y723433D01*
X403900Y724017D01*
Y727933D01*
G01Y727267D02*
X403567Y727600D01*
X403067Y727850D01*
X402483Y727933D01*
X401817Y727767D01*
X401400Y727433D01*
X401067Y726850D01*
X400900Y726267D01*
X400983Y725767D01*
X401317Y725183D01*
X401817Y724767D01*
X402483Y724600D01*
X402983Y724683D01*
X403567Y725017D01*
X403900Y725350D01*
G01X408417Y722933D02*
X409250Y723767D01*
X409667Y724600D01*
Y727933D01*
X409250Y728767D01*
X408417Y729600D01*
G01X418700Y724600D02*
Y728850D01*
X418867Y729267D01*
X419200Y729517D01*
X419700Y729600D01*
X420200Y729433D01*
X420450Y729017D01*
G01X419450Y727600D02*
X417783D01*
G01X424800Y724600D02*
X424300Y724683D01*
X423800Y725017D01*
X423467Y725600D01*
X423300Y726267D01*
X423467Y726933D01*
X423800Y727517D01*
X424300Y727850D01*
X424800Y727933D01*
X425300Y727850D01*
X425800Y727517D01*
X426133Y726933D01*
X426217Y726267D01*
X426133Y725600D01*
X425800Y725017D01*
X425300Y724683D01*
X424800Y724600D01*
G01X429233D02*
Y727933D01*
G01Y727267D02*
X429650Y727600D01*
X430067Y727850D01*
X430650Y727933D01*
X431067Y727850D01*
X431567Y727600D01*
G01X439433Y724600D02*
Y729600D01*
X441600Y725433D01*
X443767Y729600D01*
Y724600D01*
G01X445783Y727933D02*
Y725600D01*
X446117Y725017D01*
X446617Y724683D01*
X447200Y724600D01*
X447783Y724683D01*
X448283Y725017D01*
X448617Y725600D01*
G01Y724600D02*
Y727933D01*
G01X452800Y724600D02*
Y729600D01*
G01X458400D02*
Y724600D01*
G01X457233Y727933D02*
X459567D01*
G01X464000D02*
Y724600D01*
G01Y729267D02*
X463833Y729350D01*
Y729517D01*
X464000Y729600D01*
X464167Y729517D01*
Y729350D01*
X464000Y729267D01*
G01X469600Y724600D02*
Y729600D01*
G01X476700Y724600D02*
Y727933D01*
G01Y727350D02*
X476367Y727683D01*
X475867Y727850D01*
X475283Y727933D01*
X474700Y727767D01*
X474200Y727433D01*
X473867Y726933D01*
X473700Y726267D01*
X473867Y725600D01*
X474200Y725100D01*
X474700Y724767D01*
X475283Y724600D01*
X475867Y724683D01*
X476367Y724933D01*
X476700Y725267D01*
G01X479050Y723100D02*
X479550Y722933D01*
X480217Y723100D01*
X480633Y723433D01*
X480967Y723850D01*
X481467Y725183D01*
X482550Y727933D01*
G01X479883D02*
X481467Y725183D01*
G01X485150Y726850D02*
X487817D01*
X487567Y727433D01*
X487150Y727767D01*
X486567Y727933D01*
X485983Y727850D01*
X485483Y727600D01*
X485150Y727017D01*
X484983Y726517D01*
Y726017D01*
X485150Y725517D01*
X485567Y725017D01*
X486067Y724683D01*
X486650Y724600D01*
X487233Y724767D01*
X487817Y725267D01*
G01X490833Y724600D02*
Y727933D01*
G01Y727267D02*
X491250Y727600D01*
X491667Y727850D01*
X492250Y727933D01*
X492667Y727850D01*
X493167Y727600D01*
G01X501533Y724600D02*
Y729600D01*
X503533D01*
X504200Y729350D01*
X504700Y728767D01*
X504867Y728100D01*
X504700Y727433D01*
X504283Y726933D01*
X503533Y726683D01*
X501533D01*
G01X507633Y724600D02*
Y727933D01*
G01Y727267D02*
X508050Y727600D01*
X508467Y727850D01*
X509050Y727933D01*
X509467Y727850D01*
X509967Y727600D01*
G01X514400Y727933D02*
Y724600D01*
G01Y729267D02*
X514233Y729350D01*
Y729517D01*
X514400Y729600D01*
X514567Y729517D01*
Y729350D01*
X514400Y729267D01*
G01X518583Y724600D02*
Y727933D01*
G01Y727100D02*
X518917Y727517D01*
X519417Y727850D01*
X520083Y727933D01*
X520667Y727850D01*
X521167Y727517D01*
X521417Y726933D01*
Y724600D01*
G01X525600Y729600D02*
Y724600D01*
G01X524433Y727933D02*
X526767D01*
G01X529950Y726850D02*
X532617D01*
X532367Y727433D01*
X531950Y727767D01*
X531367Y727933D01*
X530783Y727850D01*
X530283Y727600D01*
X529950Y727017D01*
X529783Y726517D01*
Y726017D01*
X529950Y725517D01*
X530367Y725017D01*
X530867Y724683D01*
X531450Y724600D01*
X532033Y724767D01*
X532617Y725267D01*
G01X538300Y729600D02*
Y724600D01*
G01Y725350D02*
X537967Y724933D01*
X537467Y724683D01*
X536883Y724600D01*
X536217Y724767D01*
X535717Y725183D01*
X535383Y725683D01*
X535300Y726267D01*
X535383Y726850D01*
X535717Y727350D01*
X536217Y727767D01*
X536883Y727933D01*
X537467Y727850D01*
X537883Y727683D01*
X538300Y727350D01*
G01X548667Y727267D02*
X549000Y727517D01*
X549250Y727933D01*
X549417Y728517D01*
X549250Y729017D01*
X548917Y729350D01*
X548333Y729600D01*
X546083D01*
Y724600D01*
X548833D01*
X549417Y724933D01*
X549750Y725433D01*
X549917Y726017D01*
X549750Y726600D01*
X549250Y727100D01*
X548667Y727267D01*
X546083D01*
G01X553600Y724600D02*
X553100Y724683D01*
X552600Y725017D01*
X552267Y725600D01*
X552100Y726267D01*
X552267Y726933D01*
X552600Y727517D01*
X553100Y727850D01*
X553600Y727933D01*
X554100Y727850D01*
X554600Y727517D01*
X554933Y726933D01*
X555017Y726267D01*
X554933Y725600D01*
X554600Y725017D01*
X554100Y724683D01*
X553600Y724600D01*
G01X560700D02*
Y727933D01*
G01Y727350D02*
X560367Y727683D01*
X559867Y727850D01*
X559283Y727933D01*
X558700Y727767D01*
X558200Y727433D01*
X557867Y726933D01*
X557700Y726267D01*
X557867Y725600D01*
X558200Y725100D01*
X558700Y724767D01*
X559283Y724600D01*
X559867Y724683D01*
X560367Y724933D01*
X560700Y725267D01*
G01X563633Y724600D02*
Y727933D01*
G01Y727267D02*
X564050Y727600D01*
X564467Y727850D01*
X565050Y727933D01*
X565467Y727850D01*
X565967Y727600D01*
G01X571900Y729600D02*
Y724600D01*
G01Y725350D02*
X571567Y724933D01*
X571067Y724683D01*
X570483Y724600D01*
X569817Y724767D01*
X569317Y725183D01*
X568983Y725683D01*
X568900Y726267D01*
X568983Y726850D01*
X569317Y727350D01*
X569817Y727767D01*
X570483Y727933D01*
X571067Y727850D01*
X571483Y727683D01*
X571900Y727350D01*
G01X574750Y725183D02*
X575167Y724850D01*
X575750Y724600D01*
X576250D01*
X576750Y724767D01*
X577083Y725017D01*
X577250Y725350D01*
X577167Y725850D01*
X576833Y726100D01*
X575333Y726600D01*
X575000Y727183D01*
X575167Y727600D01*
X575500Y727850D01*
X576000Y727933D01*
X576500Y727850D01*
X577000Y727600D01*
G01X71000Y738600D02*
X73000D01*
G01X72000D02*
Y733600D01*
G01X71000D02*
X73000D01*
G01X75933D02*
Y738600D01*
X77933D01*
X78600Y738350D01*
X79100Y737767D01*
X79267Y737100D01*
X79100Y736433D01*
X78683Y735933D01*
X77933Y735683D01*
X75933D01*
G01X85033Y738183D02*
X84533Y738433D01*
X83950Y738600D01*
X83283D01*
X82533Y738350D01*
X81950Y737933D01*
X81533Y737433D01*
X81200Y736600D01*
X81117Y735850D01*
X81283Y735100D01*
X81533Y734600D01*
X82033Y734100D01*
X82617Y733767D01*
X83200Y733600D01*
X83783D01*
X84367Y733767D01*
X84867Y734017D01*
X85283Y734350D01*
G01X87717Y735267D02*
X89883D01*
G01X92233Y733600D02*
Y738600D01*
X94400Y734433D01*
X96567Y738600D01*
Y733600D01*
G01X98417D02*
Y738600D01*
X101583D01*
G01X100417Y736183D02*
X98417D01*
G01X104517Y735267D02*
X106683D01*
G01X111200Y733600D02*
Y738600D01*
X110200Y737600D01*
G01Y733600D02*
X112200D01*
G01X114967Y734350D02*
X115467Y733933D01*
X116050Y733683D01*
X116800Y733600D01*
X117550Y733767D01*
X118133Y734100D01*
X118550Y734683D01*
X118633Y735350D01*
X118467Y736017D01*
X118050Y736433D01*
X117467Y736767D01*
X116883Y736850D01*
X116300Y736767D01*
X115550Y736433D01*
X115800Y738600D01*
X118050D01*
G01X122400D02*
X121733Y738433D01*
X121233Y738017D01*
X120900Y737517D01*
X120650Y736850D01*
X120567Y736100D01*
X120650Y735350D01*
X120900Y734683D01*
X121233Y734183D01*
X121733Y733767D01*
X122400Y733600D01*
X123067Y733767D01*
X123567Y734183D01*
X123900Y734683D01*
X124150Y735350D01*
X124233Y736100D01*
X124150Y736850D01*
X123900Y737517D01*
X123567Y738017D01*
X123067Y738433D01*
X122400Y738600D01*
G01X131433Y733600D02*
Y738600D01*
X133600Y734433D01*
X135767Y738600D01*
Y733600D01*
G01X137950Y735850D02*
X140617D01*
X140367Y736433D01*
X139950Y736767D01*
X139367Y736933D01*
X138783Y736850D01*
X138283Y736600D01*
X137950Y736017D01*
X137783Y735517D01*
Y735017D01*
X137950Y734517D01*
X138367Y734017D01*
X138867Y733683D01*
X139450Y733600D01*
X140033Y733767D01*
X140617Y734267D01*
G01X144800Y738600D02*
Y733600D01*
G01X143633Y736933D02*
X145967D01*
G01X151900Y733600D02*
Y736933D01*
G01Y736350D02*
X151567Y736683D01*
X151067Y736850D01*
X150483Y736933D01*
X149900Y736767D01*
X149400Y736433D01*
X149067Y735933D01*
X148900Y735267D01*
X149067Y734600D01*
X149400Y734100D01*
X149900Y733767D01*
X150483Y733600D01*
X151067Y733683D01*
X151567Y733933D01*
X151900Y734267D01*
G01X156000Y733600D02*
Y738600D01*
G01X165617Y733600D02*
Y738600D01*
X168783D01*
G01X167617Y736183D02*
X165617D01*
G01X172800Y733600D02*
X172300Y733683D01*
X171800Y734017D01*
X171467Y734600D01*
X171300Y735267D01*
X171467Y735933D01*
X171800Y736517D01*
X172300Y736850D01*
X172800Y736933D01*
X173300Y736850D01*
X173800Y736517D01*
X174133Y735933D01*
X174217Y735267D01*
X174133Y734600D01*
X173800Y734017D01*
X173300Y733683D01*
X172800Y733600D01*
G01X178400Y736933D02*
Y733600D01*
G01Y738267D02*
X178233Y738350D01*
Y738517D01*
X178400Y738600D01*
X178567Y738517D01*
Y738350D01*
X178400Y738267D01*
G01X184000Y733600D02*
Y738600D01*
G01X194700Y733600D02*
Y737850D01*
X194867Y738267D01*
X195200Y738517D01*
X195700Y738600D01*
X196200Y738433D01*
X196450Y738017D01*
G01X195450Y736600D02*
X193783D01*
G01X200800Y733600D02*
X200300Y733683D01*
X199800Y734017D01*
X199467Y734600D01*
X199300Y735267D01*
X199467Y735933D01*
X199800Y736517D01*
X200300Y736850D01*
X200800Y736933D01*
X201300Y736850D01*
X201800Y736517D01*
X202133Y735933D01*
X202217Y735267D01*
X202133Y734600D01*
X201800Y734017D01*
X201300Y733683D01*
X200800Y733600D01*
G01X205233D02*
Y736933D01*
G01Y736267D02*
X205650Y736600D01*
X206067Y736850D01*
X206650Y736933D01*
X207067Y736850D01*
X207567Y736600D01*
G01X215933Y733600D02*
Y738600D01*
X217933D01*
X218600Y738350D01*
X219100Y737767D01*
X219267Y737100D01*
X219100Y736433D01*
X218683Y735933D01*
X217933Y735683D01*
X215933D01*
G01X222033Y733600D02*
Y736933D01*
G01Y736267D02*
X222450Y736600D01*
X222867Y736850D01*
X223450Y736933D01*
X223867Y736850D01*
X224367Y736600D01*
G01X228800Y736933D02*
Y733600D01*
G01Y738267D02*
X228633Y738350D01*
Y738517D01*
X228800Y738600D01*
X228967Y738517D01*
Y738350D01*
X228800Y738267D01*
G01X232983Y733600D02*
Y736933D01*
G01Y736100D02*
X233317Y736517D01*
X233817Y736850D01*
X234483Y736933D01*
X235067Y736850D01*
X235567Y736517D01*
X235817Y735933D01*
Y733600D01*
G01X240000Y738600D02*
Y733600D01*
G01X238833Y736933D02*
X241167D01*
G01X244350Y735850D02*
X247017D01*
X246767Y736433D01*
X246350Y736767D01*
X245767Y736933D01*
X245183Y736850D01*
X244683Y736600D01*
X244350Y736017D01*
X244183Y735517D01*
Y735017D01*
X244350Y734517D01*
X244767Y734017D01*
X245267Y733683D01*
X245850Y733600D01*
X246433Y733767D01*
X247017Y734267D01*
G01X252700Y738600D02*
Y733600D01*
G01Y734350D02*
X252367Y733933D01*
X251867Y733683D01*
X251283Y733600D01*
X250617Y733767D01*
X250117Y734183D01*
X249783Y734683D01*
X249700Y735267D01*
X249783Y735850D01*
X250117Y736350D01*
X250617Y736767D01*
X251283Y736933D01*
X251867Y736850D01*
X252283Y736683D01*
X252700Y736350D01*
G01X259900Y738600D02*
X261067Y733600D01*
X262400Y738600D01*
X263733Y733600D01*
X264900Y738600D01*
G01X268000Y736933D02*
Y733600D01*
G01Y738267D02*
X267833Y738350D01*
Y738517D01*
X268000Y738600D01*
X268167Y738517D01*
Y738350D01*
X268000Y738267D01*
G01X272433Y733600D02*
Y736933D01*
G01Y736267D02*
X272850Y736600D01*
X273267Y736850D01*
X273850Y736933D01*
X274267Y736850D01*
X274767Y736600D01*
G01X279200Y736933D02*
Y733600D01*
G01Y738267D02*
X279033Y738350D01*
Y738517D01*
X279200Y738600D01*
X279367Y738517D01*
Y738350D01*
X279200Y738267D01*
G01X283383Y733600D02*
Y736933D01*
G01Y736100D02*
X283717Y736517D01*
X284217Y736850D01*
X284883Y736933D01*
X285467Y736850D01*
X285967Y736517D01*
X286217Y735933D01*
Y733600D01*
G01X289233Y732350D02*
X289817Y732017D01*
X290483Y731933D01*
X291067Y732017D01*
X291567Y732433D01*
X291900Y733017D01*
Y736933D01*
G01Y736267D02*
X291567Y736600D01*
X291067Y736850D01*
X290483Y736933D01*
X289817Y736767D01*
X289400Y736433D01*
X289067Y735850D01*
X288900Y735267D01*
X288983Y734767D01*
X289317Y734183D01*
X289817Y733767D01*
X290483Y733600D01*
X290983Y733683D01*
X291567Y734017D01*
X291900Y734350D01*
G01X299517Y733600D02*
X301600Y738600D01*
X303683Y733600D01*
G01X302933Y735350D02*
X300267D01*
G01X305700Y731933D02*
Y736933D01*
G01Y736183D02*
X306117Y736600D01*
X306533Y736850D01*
X307200Y736933D01*
X307783Y736850D01*
X308367Y736433D01*
X308617Y735850D01*
X308700Y735267D01*
X308617Y734683D01*
X308367Y734100D01*
X307867Y733767D01*
X307200Y733600D01*
X306617Y733683D01*
X306033Y733933D01*
X305700Y734267D01*
G01X311300Y731933D02*
Y736933D01*
G01Y736183D02*
X311717Y736600D01*
X312133Y736850D01*
X312800Y736933D01*
X313383Y736850D01*
X313967Y736433D01*
X314217Y735850D01*
X314300Y735267D01*
X314217Y734683D01*
X313967Y734100D01*
X313467Y733767D01*
X312800Y733600D01*
X312217Y733683D01*
X311633Y733933D01*
X311300Y734267D01*
G01X318400Y733600D02*
Y738600D01*
G01X324000Y736933D02*
Y733600D01*
G01Y738267D02*
X323833Y738350D01*
Y738517D01*
X324000Y738600D01*
X324167Y738517D01*
Y738350D01*
X324000Y738267D01*
G01X330933Y736517D02*
X330350Y736850D01*
X329850Y736933D01*
X329183Y736767D01*
X328683Y736433D01*
X328350Y735850D01*
X328267Y735267D01*
X328350Y734683D01*
X328683Y734183D01*
X329183Y733767D01*
X329850Y733600D01*
X330433Y733767D01*
X330933Y734100D01*
G01X336700Y733600D02*
Y736933D01*
G01Y736350D02*
X336367Y736683D01*
X335867Y736850D01*
X335283Y736933D01*
X334700Y736767D01*
X334200Y736433D01*
X333867Y735933D01*
X333700Y735267D01*
X333867Y734600D01*
X334200Y734100D01*
X334700Y733767D01*
X335283Y733600D01*
X335867Y733683D01*
X336367Y733933D01*
X336700Y734267D01*
G01X340800Y738600D02*
Y733600D01*
G01X339633Y736933D02*
X341967D01*
G01X346400D02*
Y733600D01*
G01Y738267D02*
X346233Y738350D01*
Y738517D01*
X346400Y738600D01*
X346567Y738517D01*
Y738350D01*
X346400Y738267D01*
G01X352000Y733600D02*
X351500Y733683D01*
X351000Y734017D01*
X350667Y734600D01*
X350500Y735267D01*
X350667Y735933D01*
X351000Y736517D01*
X351500Y736850D01*
X352000Y736933D01*
X352500Y736850D01*
X353000Y736517D01*
X353333Y735933D01*
X353417Y735267D01*
X353333Y734600D01*
X353000Y734017D01*
X352500Y733683D01*
X352000Y733600D01*
G01X356183D02*
Y736933D01*
G01Y736100D02*
X356517Y736517D01*
X357017Y736850D01*
X357683Y736933D01*
X358267Y736850D01*
X358767Y736517D01*
X359017Y735933D01*
Y733600D01*
G01X361950Y734183D02*
X362367Y733850D01*
X362950Y733600D01*
X363450D01*
X363950Y733767D01*
X364283Y734017D01*
X364450Y734350D01*
X364367Y734850D01*
X364033Y735100D01*
X362533Y735600D01*
X362200Y736183D01*
X362367Y736600D01*
X362700Y736850D01*
X363200Y736933D01*
X363700Y736850D01*
X364200Y736600D01*
G01X57000Y802500D02*
X59000D01*
G01X58000D02*
Y797500D01*
G01X57000D02*
X59000D01*
G01X63100D02*
Y801750D01*
X63267Y802167D01*
X63600Y802417D01*
X64100Y802500D01*
X64600Y802333D01*
X64850Y801917D01*
G01X63850Y800500D02*
X62183D01*
G01X74800Y802500D02*
Y797500D01*
G01X73633Y800833D02*
X75967D01*
G01X78983Y797500D02*
Y802500D01*
G01Y800083D02*
X79400Y800500D01*
X79817Y800750D01*
X80483Y800833D01*
X80983Y800750D01*
X81567Y800417D01*
X81817Y799917D01*
Y797500D01*
G01X84750Y799750D02*
X87417D01*
X87167Y800333D01*
X86750Y800667D01*
X86167Y800833D01*
X85583Y800750D01*
X85083Y800500D01*
X84750Y799917D01*
X84583Y799417D01*
Y798917D01*
X84750Y798417D01*
X85167Y797917D01*
X85667Y797583D01*
X86250Y797500D01*
X86833Y797667D01*
X87417Y798167D01*
G01X98533Y800417D02*
X97950Y800750D01*
X97450Y800833D01*
X96783Y800667D01*
X96283Y800333D01*
X95950Y799750D01*
X95867Y799167D01*
X95950Y798583D01*
X96283Y798083D01*
X96783Y797667D01*
X97450Y797500D01*
X98033Y797667D01*
X98533Y798000D01*
G01X101633Y797500D02*
Y800833D01*
G01Y800167D02*
X102050Y800500D01*
X102467Y800750D01*
X103050Y800833D01*
X103467Y800750D01*
X103967Y800500D01*
G01X108400Y800833D02*
Y797500D01*
G01Y802167D02*
X108233Y802250D01*
Y802417D01*
X108400Y802500D01*
X108567Y802417D01*
Y802250D01*
X108400Y802167D01*
G01X114000Y802500D02*
Y797500D01*
G01X112833Y800833D02*
X115167D01*
G01X118350Y799750D02*
X121017D01*
X120767Y800333D01*
X120350Y800667D01*
X119767Y800833D01*
X119183Y800750D01*
X118683Y800500D01*
X118350Y799917D01*
X118183Y799417D01*
Y798917D01*
X118350Y798417D01*
X118767Y797917D01*
X119267Y797583D01*
X119850Y797500D01*
X120433Y797667D01*
X121017Y798167D01*
G01X124033Y797500D02*
Y800833D01*
G01Y800167D02*
X124450Y800500D01*
X124867Y800750D01*
X125450Y800833D01*
X125867Y800750D01*
X126367Y800500D01*
G01X130800Y800833D02*
Y797500D01*
G01Y802167D02*
X130633Y802250D01*
Y802417D01*
X130800Y802500D01*
X130967Y802417D01*
Y802250D01*
X130800Y802167D01*
G01X137900Y797500D02*
Y800833D01*
G01Y800250D02*
X137567Y800583D01*
X137067Y800750D01*
X136483Y800833D01*
X135900Y800667D01*
X135400Y800333D01*
X135067Y799833D01*
X134900Y799167D01*
X135067Y798500D01*
X135400Y798000D01*
X135900Y797667D01*
X136483Y797500D01*
X137067Y797583D01*
X137567Y797833D01*
X137900Y798167D01*
G01X147600Y800833D02*
Y797500D01*
G01Y802167D02*
X147433Y802250D01*
Y802417D01*
X147600Y802500D01*
X147767Y802417D01*
Y802250D01*
X147600Y802167D01*
G01X151950Y798083D02*
X152367Y797750D01*
X152950Y797500D01*
X153450D01*
X153950Y797667D01*
X154283Y797917D01*
X154450Y798250D01*
X154367Y798750D01*
X154033Y799000D01*
X152533Y799500D01*
X152200Y800083D01*
X152367Y800500D01*
X152700Y800750D01*
X153200Y800833D01*
X153700Y800750D01*
X154200Y800500D01*
G01X162983Y797500D02*
Y800833D01*
G01Y800000D02*
X163317Y800417D01*
X163817Y800750D01*
X164483Y800833D01*
X165067Y800750D01*
X165567Y800417D01*
X165817Y799833D01*
Y797500D01*
G01X170000D02*
X169500Y797583D01*
X169000Y797917D01*
X168667Y798500D01*
X168500Y799167D01*
X168667Y799833D01*
X169000Y800417D01*
X169500Y800750D01*
X170000Y800833D01*
X170500Y800750D01*
X171000Y800417D01*
X171333Y799833D01*
X171417Y799167D01*
X171333Y798500D01*
X171000Y797917D01*
X170500Y797583D01*
X170000Y797500D01*
G01X175600Y802500D02*
Y797500D01*
G01X174433Y800833D02*
X176767D01*
G01X185550Y798083D02*
X185967Y797750D01*
X186550Y797500D01*
X187050D01*
X187550Y797667D01*
X187883Y797917D01*
X188050Y798250D01*
X187967Y798750D01*
X187633Y799000D01*
X186133Y799500D01*
X185800Y800083D01*
X185967Y800500D01*
X186300Y800750D01*
X186800Y800833D01*
X187300Y800750D01*
X187800Y800500D01*
G01X190900Y795833D02*
Y800833D01*
G01Y800083D02*
X191317Y800500D01*
X191733Y800750D01*
X192400Y800833D01*
X192983Y800750D01*
X193567Y800333D01*
X193817Y799750D01*
X193900Y799167D01*
X193817Y798583D01*
X193567Y798000D01*
X193067Y797667D01*
X192400Y797500D01*
X191817Y797583D01*
X191233Y797833D01*
X190900Y798167D01*
G01X196750Y799750D02*
X199417D01*
X199167Y800333D01*
X198750Y800667D01*
X198167Y800833D01*
X197583Y800750D01*
X197083Y800500D01*
X196750Y799917D01*
X196583Y799417D01*
Y798917D01*
X196750Y798417D01*
X197167Y797917D01*
X197667Y797583D01*
X198250Y797500D01*
X198833Y797667D01*
X199417Y798167D01*
G01X204933Y800417D02*
X204350Y800750D01*
X203850Y800833D01*
X203183Y800667D01*
X202683Y800333D01*
X202350Y799750D01*
X202267Y799167D01*
X202350Y798583D01*
X202683Y798083D01*
X203183Y797667D01*
X203850Y797500D01*
X204433Y797667D01*
X204933Y798000D01*
G01X209200Y800833D02*
Y797500D01*
G01Y802167D02*
X209033Y802250D01*
Y802417D01*
X209200Y802500D01*
X209367Y802417D01*
Y802250D01*
X209200Y802167D01*
G01X214300Y797500D02*
Y801750D01*
X214467Y802167D01*
X214800Y802417D01*
X215300Y802500D01*
X215800Y802333D01*
X216050Y801917D01*
G01X215050Y800500D02*
X213383D01*
G01X220400Y800833D02*
Y797500D01*
G01Y802167D02*
X220233Y802250D01*
Y802417D01*
X220400Y802500D01*
X220567Y802417D01*
Y802250D01*
X220400Y802167D01*
G01X224750Y799750D02*
X227417D01*
X227167Y800333D01*
X226750Y800667D01*
X226167Y800833D01*
X225583Y800750D01*
X225083Y800500D01*
X224750Y799917D01*
X224583Y799417D01*
Y798917D01*
X224750Y798417D01*
X225167Y797917D01*
X225667Y797583D01*
X226250Y797500D01*
X226833Y797667D01*
X227417Y798167D01*
G01X233100Y802500D02*
Y797500D01*
G01Y798250D02*
X232767Y797833D01*
X232267Y797583D01*
X231683Y797500D01*
X231017Y797667D01*
X230517Y798083D01*
X230183Y798583D01*
X230100Y799167D01*
X230183Y799750D01*
X230517Y800250D01*
X231017Y800667D01*
X231683Y800833D01*
X232267Y800750D01*
X232683Y800583D01*
X233100Y800250D01*
G01X242800Y800833D02*
Y797500D01*
G01Y802167D02*
X242633Y802250D01*
Y802417D01*
X242800Y802500D01*
X242967Y802417D01*
Y802250D01*
X242800Y802167D01*
G01X246983Y797500D02*
Y800833D01*
G01Y800000D02*
X247317Y800417D01*
X247817Y800750D01*
X248483Y800833D01*
X249067Y800750D01*
X249567Y800417D01*
X249817Y799833D01*
Y797500D01*
G01X259600Y802500D02*
Y797500D01*
G01X258433Y800833D02*
X260767D01*
G01X263783Y797500D02*
Y802500D01*
G01Y800083D02*
X264200Y800500D01*
X264617Y800750D01*
X265283Y800833D01*
X265783Y800750D01*
X266367Y800417D01*
X266617Y799917D01*
Y797500D01*
G01X269550Y799750D02*
X272217D01*
X271967Y800333D01*
X271550Y800667D01*
X270967Y800833D01*
X270383Y800750D01*
X269883Y800500D01*
X269550Y799917D01*
X269383Y799417D01*
Y798917D01*
X269550Y798417D01*
X269967Y797917D01*
X270467Y797583D01*
X271050Y797500D01*
X271633Y797667D01*
X272217Y798167D01*
G01X282000Y802500D02*
Y797500D01*
G01X280833Y800833D02*
X283167D01*
G01X289100Y797500D02*
Y800833D01*
G01Y800250D02*
X288767Y800583D01*
X288267Y800750D01*
X287683Y800833D01*
X287100Y800667D01*
X286600Y800333D01*
X286267Y799833D01*
X286100Y799167D01*
X286267Y798500D01*
X286600Y798000D01*
X287100Y797667D01*
X287683Y797500D01*
X288267Y797583D01*
X288767Y797833D01*
X289100Y798167D01*
G01X291700Y797500D02*
Y802500D01*
G01Y800000D02*
X292117Y800500D01*
X292617Y800750D01*
X293117Y800833D01*
X293867Y800667D01*
X294367Y800333D01*
X294700Y799750D01*
Y799083D01*
X294533Y798417D01*
X294200Y797917D01*
X293617Y797583D01*
X293117Y797500D01*
X292617Y797583D01*
X292117Y797833D01*
X291700Y798250D01*
G01X298800Y797500D02*
Y802500D01*
G01X303150Y799750D02*
X305817D01*
X305567Y800333D01*
X305150Y800667D01*
X304567Y800833D01*
X303983Y800750D01*
X303483Y800500D01*
X303150Y799917D01*
X302983Y799417D01*
Y798917D01*
X303150Y798417D01*
X303567Y797917D01*
X304067Y797583D01*
X304650Y797500D01*
X305233Y797667D01*
X305817Y798167D01*
G01X310000Y797333D02*
X309833Y797417D01*
Y797583D01*
X310000Y797667D01*
X310167Y797583D01*
Y797417D01*
X310000Y797333D01*
G01Y799583D02*
X309833Y799667D01*
Y799833D01*
X310000Y799917D01*
X310167Y799833D01*
Y799667D01*
X310000Y799583D01*
G01X67000Y743433D02*
X66833Y743517D01*
Y743683D01*
X67000Y743767D01*
X67167Y743683D01*
Y743517D01*
X67000Y743433D01*
G01Y752433D02*
X66833Y752517D01*
Y752683D01*
X67000Y752767D01*
X67167Y752683D01*
Y752517D01*
X67000Y752433D01*
G01Y761433D02*
X66833Y761517D01*
Y761683D01*
X67000Y761767D01*
X67167Y761683D01*
Y761517D01*
X67000Y761433D01*
G01Y770433D02*
X66833Y770517D01*
Y770683D01*
X67000Y770767D01*
X67167Y770683D01*
Y770517D01*
X67000Y770433D01*
G01X71000Y747600D02*
X73000D01*
G01X72000D02*
Y742600D01*
G01X71000D02*
X73000D01*
G01X75933D02*
Y747600D01*
X77933D01*
X78600Y747350D01*
X79100Y746767D01*
X79267Y746100D01*
X79100Y745433D01*
X78683Y744933D01*
X77933Y744683D01*
X75933D01*
G01X85033Y747183D02*
X84533Y747433D01*
X83950Y747600D01*
X83283D01*
X82533Y747350D01*
X81950Y746933D01*
X81533Y746433D01*
X81200Y745600D01*
X81117Y744850D01*
X81283Y744100D01*
X81533Y743600D01*
X82033Y743100D01*
X82617Y742767D01*
X83200Y742600D01*
X83783D01*
X84367Y742767D01*
X84867Y743017D01*
X85283Y743350D01*
G01X87717Y744267D02*
X89883D01*
G01X95400Y742600D02*
Y747600D01*
X92317Y744017D01*
X96483D01*
G01X100000Y742600D02*
Y747600D01*
X99000Y746600D01*
G01Y742600D02*
X101000D01*
G01X105600Y747600D02*
X104933Y747433D01*
X104433Y747017D01*
X104100Y746517D01*
X103850Y745850D01*
X103767Y745100D01*
X103850Y744350D01*
X104100Y743683D01*
X104433Y743183D01*
X104933Y742767D01*
X105600Y742600D01*
X106267Y742767D01*
X106767Y743183D01*
X107100Y743683D01*
X107350Y744350D01*
X107433Y745100D01*
X107350Y745850D01*
X107100Y746517D01*
X106767Y747017D01*
X106267Y747433D01*
X105600Y747600D01*
G01X111200Y742600D02*
Y747600D01*
X110200Y746600D01*
G01Y742600D02*
X112200D01*
G01X120650Y743267D02*
X121317Y742850D01*
X122067Y742600D01*
X122733D01*
X123400Y742850D01*
X123900Y743267D01*
X124150Y743850D01*
X123983Y744433D01*
X123567Y744933D01*
X122817Y745267D01*
X121817Y745433D01*
X121233Y745767D01*
X120983Y746350D01*
X121150Y746933D01*
X121567Y747350D01*
X122150Y747600D01*
X122733D01*
X123317Y747433D01*
X123817Y747017D01*
G01X126500Y740933D02*
Y745933D01*
G01Y745183D02*
X126917Y745600D01*
X127333Y745850D01*
X128000Y745933D01*
X128583Y745850D01*
X129167Y745433D01*
X129417Y744850D01*
X129500Y744267D01*
X129417Y743683D01*
X129167Y743100D01*
X128667Y742767D01*
X128000Y742600D01*
X127417Y742683D01*
X126833Y742933D01*
X126500Y743267D01*
G01X132350Y744850D02*
X135017D01*
X134767Y745433D01*
X134350Y745767D01*
X133767Y745933D01*
X133183Y745850D01*
X132683Y745600D01*
X132350Y745017D01*
X132183Y744517D01*
Y744017D01*
X132350Y743517D01*
X132767Y743017D01*
X133267Y742683D01*
X133850Y742600D01*
X134433Y742767D01*
X135017Y743267D01*
G01X140533Y745517D02*
X139950Y745850D01*
X139450Y745933D01*
X138783Y745767D01*
X138283Y745433D01*
X137950Y744850D01*
X137867Y744267D01*
X137950Y743683D01*
X138283Y743183D01*
X138783Y742767D01*
X139450Y742600D01*
X140033Y742767D01*
X140533Y743100D01*
G01X144800Y745933D02*
Y742600D01*
G01Y747267D02*
X144633Y747350D01*
Y747517D01*
X144800Y747600D01*
X144967Y747517D01*
Y747350D01*
X144800Y747267D01*
G01X149900Y742600D02*
Y746850D01*
X150067Y747267D01*
X150400Y747517D01*
X150900Y747600D01*
X151400Y747433D01*
X151650Y747017D01*
G01X150650Y745600D02*
X148983D01*
G01X156000Y745933D02*
Y742600D01*
G01Y747267D02*
X155833Y747350D01*
Y747517D01*
X156000Y747600D01*
X156167Y747517D01*
Y747350D01*
X156000Y747267D01*
G01X162933Y745517D02*
X162350Y745850D01*
X161850Y745933D01*
X161183Y745767D01*
X160683Y745433D01*
X160350Y744850D01*
X160267Y744267D01*
X160350Y743683D01*
X160683Y743183D01*
X161183Y742767D01*
X161850Y742600D01*
X162433Y742767D01*
X162933Y743100D01*
G01X168700Y742600D02*
Y745933D01*
G01Y745350D02*
X168367Y745683D01*
X167867Y745850D01*
X167283Y745933D01*
X166700Y745767D01*
X166200Y745433D01*
X165867Y744933D01*
X165700Y744267D01*
X165867Y743600D01*
X166200Y743100D01*
X166700Y742767D01*
X167283Y742600D01*
X167867Y742683D01*
X168367Y742933D01*
X168700Y743267D01*
G01X172800Y747600D02*
Y742600D01*
G01X171633Y745933D02*
X173967D01*
G01X178400D02*
Y742600D01*
G01Y747267D02*
X178233Y747350D01*
Y747517D01*
X178400Y747600D01*
X178567Y747517D01*
Y747350D01*
X178400Y747267D01*
G01X184000Y742600D02*
X183500Y742683D01*
X183000Y743017D01*
X182667Y743600D01*
X182500Y744267D01*
X182667Y744933D01*
X183000Y745517D01*
X183500Y745850D01*
X184000Y745933D01*
X184500Y745850D01*
X185000Y745517D01*
X185333Y744933D01*
X185417Y744267D01*
X185333Y743600D01*
X185000Y743017D01*
X184500Y742683D01*
X184000Y742600D01*
G01X188183D02*
Y745933D01*
G01Y745100D02*
X188517Y745517D01*
X189017Y745850D01*
X189683Y745933D01*
X190267Y745850D01*
X190767Y745517D01*
X191017Y744933D01*
Y742600D01*
G01X200300D02*
Y746850D01*
X200467Y747267D01*
X200800Y747517D01*
X201300Y747600D01*
X201800Y747433D01*
X202050Y747017D01*
G01X201050Y745600D02*
X199383D01*
G01X206400Y742600D02*
X205900Y742683D01*
X205400Y743017D01*
X205067Y743600D01*
X204900Y744267D01*
X205067Y744933D01*
X205400Y745517D01*
X205900Y745850D01*
X206400Y745933D01*
X206900Y745850D01*
X207400Y745517D01*
X207733Y744933D01*
X207817Y744267D01*
X207733Y743600D01*
X207400Y743017D01*
X206900Y742683D01*
X206400Y742600D01*
G01X210833D02*
Y745933D01*
G01Y745267D02*
X211250Y745600D01*
X211667Y745850D01*
X212250Y745933D01*
X212667Y745850D01*
X213167Y745600D01*
G01X223867Y745267D02*
X224200Y745517D01*
X224450Y745933D01*
X224617Y746517D01*
X224450Y747017D01*
X224117Y747350D01*
X223533Y747600D01*
X221283D01*
Y742600D01*
X224033D01*
X224617Y742933D01*
X224950Y743433D01*
X225117Y744017D01*
X224950Y744600D01*
X224450Y745100D01*
X223867Y745267D01*
X221283D01*
G01X230300Y742600D02*
Y745933D01*
G01Y745350D02*
X229967Y745683D01*
X229467Y745850D01*
X228883Y745933D01*
X228300Y745767D01*
X227800Y745433D01*
X227467Y744933D01*
X227300Y744267D01*
X227467Y743600D01*
X227800Y743100D01*
X228300Y742767D01*
X228883Y742600D01*
X229467Y742683D01*
X229967Y742933D01*
X230300Y743267D01*
G01X233150Y743183D02*
X233567Y742850D01*
X234150Y742600D01*
X234650D01*
X235150Y742767D01*
X235483Y743017D01*
X235650Y743350D01*
X235567Y743850D01*
X235233Y744100D01*
X233733Y744600D01*
X233400Y745183D01*
X233567Y745600D01*
X233900Y745850D01*
X234400Y745933D01*
X234900Y745850D01*
X235400Y745600D01*
G01X238750Y744850D02*
X241417D01*
X241167Y745433D01*
X240750Y745767D01*
X240167Y745933D01*
X239583Y745850D01*
X239083Y745600D01*
X238750Y745017D01*
X238583Y744517D01*
Y744017D01*
X238750Y743517D01*
X239167Y743017D01*
X239667Y742683D01*
X240250Y742600D01*
X240833Y742767D01*
X241417Y743267D01*
G01X249033Y742600D02*
Y747600D01*
X251200Y743433D01*
X253367Y747600D01*
Y742600D01*
G01X258300D02*
Y745933D01*
G01Y745350D02*
X257967Y745683D01*
X257467Y745850D01*
X256883Y745933D01*
X256300Y745767D01*
X255800Y745433D01*
X255467Y744933D01*
X255300Y744267D01*
X255467Y743600D01*
X255800Y743100D01*
X256300Y742767D01*
X256883Y742600D01*
X257467Y742683D01*
X257967Y742933D01*
X258300Y743267D01*
G01X262400Y747600D02*
Y742600D01*
G01X261233Y745933D02*
X263567D01*
G01X266750Y744850D02*
X269417D01*
X269167Y745433D01*
X268750Y745767D01*
X268167Y745933D01*
X267583Y745850D01*
X267083Y745600D01*
X266750Y745017D01*
X266583Y744517D01*
Y744017D01*
X266750Y743517D01*
X267167Y743017D01*
X267667Y742683D01*
X268250Y742600D01*
X268833Y742767D01*
X269417Y743267D01*
G01X272433Y742600D02*
Y745933D01*
G01Y745267D02*
X272850Y745600D01*
X273267Y745850D01*
X273850Y745933D01*
X274267Y745850D01*
X274767Y745600D01*
G01X279200Y745933D02*
Y742600D01*
G01Y747267D02*
X279033Y747350D01*
Y747517D01*
X279200Y747600D01*
X279367Y747517D01*
Y747350D01*
X279200Y747267D01*
G01X286300Y742600D02*
Y745933D01*
G01Y745350D02*
X285967Y745683D01*
X285467Y745850D01*
X284883Y745933D01*
X284300Y745767D01*
X283800Y745433D01*
X283467Y744933D01*
X283300Y744267D01*
X283467Y743600D01*
X283800Y743100D01*
X284300Y742767D01*
X284883Y742600D01*
X285467Y742683D01*
X285967Y742933D01*
X286300Y743267D01*
G01X290400Y742600D02*
Y747600D01*
G01X294750Y743183D02*
X295167Y742850D01*
X295750Y742600D01*
X296250D01*
X296750Y742767D01*
X297083Y743017D01*
X297250Y743350D01*
X297167Y743850D01*
X296833Y744100D01*
X295333Y744600D01*
X295000Y745183D01*
X295167Y745600D01*
X295500Y745850D01*
X296000Y745933D01*
X296500Y745850D01*
X297000Y745600D01*
G01X306700Y742600D02*
Y746850D01*
X306867Y747267D01*
X307200Y747517D01*
X307700Y747600D01*
X308200Y747433D01*
X308450Y747017D01*
G01X307450Y745600D02*
X305783D01*
G01X312800Y742600D02*
X312300Y742683D01*
X311800Y743017D01*
X311467Y743600D01*
X311300Y744267D01*
X311467Y744933D01*
X311800Y745517D01*
X312300Y745850D01*
X312800Y745933D01*
X313300Y745850D01*
X313800Y745517D01*
X314133Y744933D01*
X314217Y744267D01*
X314133Y743600D01*
X313800Y743017D01*
X313300Y742683D01*
X312800Y742600D01*
G01X317233D02*
Y745933D01*
G01Y745267D02*
X317650Y745600D01*
X318067Y745850D01*
X318650Y745933D01*
X319067Y745850D01*
X319567Y745600D01*
G01X327933Y742600D02*
Y747600D01*
X330017D01*
X330683Y747350D01*
X331100Y747017D01*
X331267Y746350D01*
X331100Y745683D01*
X330600Y745267D01*
X330017Y745017D01*
X327933D01*
G01X330017D02*
X331267Y742600D01*
G01X335200Y745933D02*
Y742600D01*
G01Y747267D02*
X335033Y747350D01*
Y747517D01*
X335200Y747600D01*
X335367Y747517D01*
Y747350D01*
X335200Y747267D01*
G01X339633Y741350D02*
X340217Y741017D01*
X340883Y740933D01*
X341467Y741017D01*
X341967Y741433D01*
X342300Y742017D01*
Y745933D01*
G01Y745267D02*
X341967Y745600D01*
X341467Y745850D01*
X340883Y745933D01*
X340217Y745767D01*
X339800Y745433D01*
X339467Y744850D01*
X339300Y744267D01*
X339383Y743767D01*
X339717Y743183D01*
X340217Y742767D01*
X340883Y742600D01*
X341383Y742683D01*
X341967Y743017D01*
X342300Y743350D01*
G01X346400Y745933D02*
Y742600D01*
G01Y747267D02*
X346233Y747350D01*
Y747517D01*
X346400Y747600D01*
X346567Y747517D01*
Y747350D01*
X346400Y747267D01*
G01X353500Y747600D02*
Y742600D01*
G01Y743350D02*
X353167Y742933D01*
X352667Y742683D01*
X352083Y742600D01*
X351417Y742767D01*
X350917Y743183D01*
X350583Y743683D01*
X350500Y744267D01*
X350583Y744850D01*
X350917Y745350D01*
X351417Y745767D01*
X352083Y745933D01*
X352667Y745850D01*
X353083Y745683D01*
X353500Y745350D01*
G01X364700Y742600D02*
Y745933D01*
G01Y745350D02*
X364367Y745683D01*
X363867Y745850D01*
X363283Y745933D01*
X362700Y745767D01*
X362200Y745433D01*
X361867Y744933D01*
X361700Y744267D01*
X361867Y743600D01*
X362200Y743100D01*
X362700Y742767D01*
X363283Y742600D01*
X363867Y742683D01*
X364367Y742933D01*
X364700Y743267D01*
G01X367383Y742600D02*
Y745933D01*
G01Y745100D02*
X367717Y745517D01*
X368217Y745850D01*
X368883Y745933D01*
X369467Y745850D01*
X369967Y745517D01*
X370217Y744933D01*
Y742600D01*
G01X375900Y747600D02*
Y742600D01*
G01Y743350D02*
X375567Y742933D01*
X375067Y742683D01*
X374483Y742600D01*
X373817Y742767D01*
X373317Y743183D01*
X372983Y743683D01*
X372900Y744267D01*
X372983Y744850D01*
X373317Y745350D01*
X373817Y745767D01*
X374483Y745933D01*
X375067Y745850D01*
X375483Y745683D01*
X375900Y745350D01*
G01X383433Y742600D02*
Y747600D01*
X385600Y743433D01*
X387767Y747600D01*
Y742600D01*
G01X389783Y745933D02*
Y743600D01*
X390117Y743017D01*
X390617Y742683D01*
X391200Y742600D01*
X391783Y742683D01*
X392283Y743017D01*
X392617Y743600D01*
G01Y742600D02*
Y745933D01*
G01X396800Y742600D02*
Y747600D01*
G01X402400D02*
Y742600D01*
G01X401233Y745933D02*
X403567D01*
G01X408000D02*
Y742600D01*
G01Y747267D02*
X407833Y747350D01*
Y747517D01*
X408000Y747600D01*
X408167Y747517D01*
Y747350D01*
X408000Y747267D01*
G01X413600Y742600D02*
Y747600D01*
G01X420700Y742600D02*
Y745933D01*
G01Y745350D02*
X420367Y745683D01*
X419867Y745850D01*
X419283Y745933D01*
X418700Y745767D01*
X418200Y745433D01*
X417867Y744933D01*
X417700Y744267D01*
X417867Y743600D01*
X418200Y743100D01*
X418700Y742767D01*
X419283Y742600D01*
X419867Y742683D01*
X420367Y742933D01*
X420700Y743267D01*
G01X423050Y741100D02*
X423550Y740933D01*
X424217Y741100D01*
X424633Y741433D01*
X424967Y741850D01*
X425467Y743183D01*
X426550Y745933D01*
G01X423883D02*
X425467Y743183D01*
G01X429150Y744850D02*
X431817D01*
X431567Y745433D01*
X431150Y745767D01*
X430567Y745933D01*
X429983Y745850D01*
X429483Y745600D01*
X429150Y745017D01*
X428983Y744517D01*
Y744017D01*
X429150Y743517D01*
X429567Y743017D01*
X430067Y742683D01*
X430650Y742600D01*
X431233Y742767D01*
X431817Y743267D01*
G01X434833Y742600D02*
Y745933D01*
G01Y745267D02*
X435250Y745600D01*
X435667Y745850D01*
X436250Y745933D01*
X436667Y745850D01*
X437167Y745600D01*
G01X445533Y742600D02*
Y747600D01*
X447533D01*
X448200Y747350D01*
X448700Y746767D01*
X448867Y746100D01*
X448700Y745433D01*
X448283Y744933D01*
X447533Y744683D01*
X445533D01*
G01X451633Y742600D02*
Y745933D01*
G01Y745267D02*
X452050Y745600D01*
X452467Y745850D01*
X453050Y745933D01*
X453467Y745850D01*
X453967Y745600D01*
G01X458400Y745933D02*
Y742600D01*
G01Y747267D02*
X458233Y747350D01*
Y747517D01*
X458400Y747600D01*
X458567Y747517D01*
Y747350D01*
X458400Y747267D01*
G01X462583Y742600D02*
Y745933D01*
G01Y745100D02*
X462917Y745517D01*
X463417Y745850D01*
X464083Y745933D01*
X464667Y745850D01*
X465167Y745517D01*
X465417Y744933D01*
Y742600D01*
G01X469600Y747600D02*
Y742600D01*
G01X468433Y745933D02*
X470767D01*
G01X473950Y744850D02*
X476617D01*
X476367Y745433D01*
X475950Y745767D01*
X475367Y745933D01*
X474783Y745850D01*
X474283Y745600D01*
X473950Y745017D01*
X473783Y744517D01*
Y744017D01*
X473950Y743517D01*
X474367Y743017D01*
X474867Y742683D01*
X475450Y742600D01*
X476033Y742767D01*
X476617Y743267D01*
G01X482300Y747600D02*
Y742600D01*
G01Y743350D02*
X481967Y742933D01*
X481467Y742683D01*
X480883Y742600D01*
X480217Y742767D01*
X479717Y743183D01*
X479383Y743683D01*
X479300Y744267D01*
X479383Y744850D01*
X479717Y745350D01*
X480217Y745767D01*
X480883Y745933D01*
X481467Y745850D01*
X481883Y745683D01*
X482300Y745350D01*
G01X492667Y745267D02*
X493000Y745517D01*
X493250Y745933D01*
X493417Y746517D01*
X493250Y747017D01*
X492917Y747350D01*
X492333Y747600D01*
X490083D01*
Y742600D01*
X492833D01*
X493417Y742933D01*
X493750Y743433D01*
X493917Y744017D01*
X493750Y744600D01*
X493250Y745100D01*
X492667Y745267D01*
X490083D01*
G01X497600Y742600D02*
X497100Y742683D01*
X496600Y743017D01*
X496267Y743600D01*
X496100Y744267D01*
X496267Y744933D01*
X496600Y745517D01*
X497100Y745850D01*
X497600Y745933D01*
X498100Y745850D01*
X498600Y745517D01*
X498933Y744933D01*
X499017Y744267D01*
X498933Y743600D01*
X498600Y743017D01*
X498100Y742683D01*
X497600Y742600D01*
G01X504700D02*
Y745933D01*
G01Y745350D02*
X504367Y745683D01*
X503867Y745850D01*
X503283Y745933D01*
X502700Y745767D01*
X502200Y745433D01*
X501867Y744933D01*
X501700Y744267D01*
X501867Y743600D01*
X502200Y743100D01*
X502700Y742767D01*
X503283Y742600D01*
X503867Y742683D01*
X504367Y742933D01*
X504700Y743267D01*
G01X507633Y742600D02*
Y745933D01*
G01Y745267D02*
X508050Y745600D01*
X508467Y745850D01*
X509050Y745933D01*
X509467Y745850D01*
X509967Y745600D01*
G01X515900Y747600D02*
Y742600D01*
G01Y743350D02*
X515567Y742933D01*
X515067Y742683D01*
X514483Y742600D01*
X513817Y742767D01*
X513317Y743183D01*
X512983Y743683D01*
X512900Y744267D01*
X512983Y744850D01*
X513317Y745350D01*
X513817Y745767D01*
X514483Y745933D01*
X515067Y745850D01*
X515483Y745683D01*
X515900Y745350D01*
G01X518750Y743183D02*
X519167Y742850D01*
X519750Y742600D01*
X520250D01*
X520750Y742767D01*
X521083Y743017D01*
X521250Y743350D01*
X521167Y743850D01*
X520833Y744100D01*
X519333Y744600D01*
X519000Y745183D01*
X519167Y745600D01*
X519500Y745850D01*
X520000Y745933D01*
X520500Y745850D01*
X521000Y745600D01*
G01X71000Y756600D02*
X73000D01*
G01X72000D02*
Y751600D01*
G01X71000D02*
X73000D01*
G01X75933D02*
Y756600D01*
X77933D01*
X78600Y756350D01*
X79100Y755767D01*
X79267Y755100D01*
X79100Y754433D01*
X78683Y753933D01*
X77933Y753683D01*
X75933D01*
G01X85033Y756183D02*
X84533Y756433D01*
X83950Y756600D01*
X83283D01*
X82533Y756350D01*
X81950Y755933D01*
X81533Y755433D01*
X81200Y754600D01*
X81117Y753850D01*
X81283Y753100D01*
X81533Y752600D01*
X82033Y752100D01*
X82617Y751767D01*
X83200Y751600D01*
X83783D01*
X84367Y751767D01*
X84867Y752017D01*
X85283Y752350D01*
G01X87717Y753267D02*
X89883D01*
G01X94400Y756600D02*
Y751600D01*
G01X92483Y756600D02*
X96317D01*
G01X97833Y751600D02*
Y756600D01*
X100000Y752433D01*
X102167Y756600D01*
Y751600D01*
G01X104517Y753267D02*
X106683D01*
G01X109617Y753683D02*
X110200Y754267D01*
X110700Y754600D01*
X111367Y754767D01*
X111950Y754600D01*
X112367Y754267D01*
X112700Y753767D01*
X112783Y753183D01*
X112700Y752683D01*
X112367Y752183D01*
X111867Y751767D01*
X111283Y751600D01*
X110617Y751767D01*
X110033Y752267D01*
X109700Y753017D01*
X109617Y753850D01*
X109783Y754933D01*
X110033Y755517D01*
X110450Y756100D01*
X111033Y756517D01*
X111617Y756600D01*
X112200Y756433D01*
X112617Y756017D01*
G01X114967Y752350D02*
X115467Y751933D01*
X116050Y751683D01*
X116800Y751600D01*
X117550Y751767D01*
X118133Y752100D01*
X118550Y752683D01*
X118633Y753350D01*
X118467Y754017D01*
X118050Y754433D01*
X117467Y754767D01*
X116883Y754850D01*
X116300Y754767D01*
X115550Y754433D01*
X115800Y756600D01*
X118050D01*
G01X122400D02*
X121733Y756433D01*
X121233Y756017D01*
X120900Y755517D01*
X120650Y754850D01*
X120567Y754100D01*
X120650Y753350D01*
X120900Y752683D01*
X121233Y752183D01*
X121733Y751767D01*
X122400Y751600D01*
X123067Y751767D01*
X123567Y752183D01*
X123900Y752683D01*
X124150Y753350D01*
X124233Y754100D01*
X124150Y754850D01*
X123900Y755517D01*
X123567Y756017D01*
X123067Y756433D01*
X122400Y756600D01*
G01X133600D02*
Y751600D01*
G01X131683Y756600D02*
X135517D01*
G01X137950Y753850D02*
X140617D01*
X140367Y754433D01*
X139950Y754767D01*
X139367Y754933D01*
X138783Y754850D01*
X138283Y754600D01*
X137950Y754017D01*
X137783Y753517D01*
Y753017D01*
X137950Y752517D01*
X138367Y752017D01*
X138867Y751683D01*
X139450Y751600D01*
X140033Y751767D01*
X140617Y752267D01*
G01X143550Y752183D02*
X143967Y751850D01*
X144550Y751600D01*
X145050D01*
X145550Y751767D01*
X145883Y752017D01*
X146050Y752350D01*
X145967Y752850D01*
X145633Y753100D01*
X144133Y753600D01*
X143800Y754183D01*
X143967Y754600D01*
X144300Y754850D01*
X144800Y754933D01*
X145300Y754850D01*
X145800Y754600D01*
G01X150400Y756600D02*
Y751600D01*
G01X149233Y754933D02*
X151567D01*
G01X159433Y751600D02*
Y756600D01*
X161600Y752433D01*
X163767Y756600D01*
Y751600D01*
G01X165950Y753850D02*
X168617D01*
X168367Y754433D01*
X167950Y754767D01*
X167367Y754933D01*
X166783Y754850D01*
X166283Y754600D01*
X165950Y754017D01*
X165783Y753517D01*
Y753017D01*
X165950Y752517D01*
X166367Y752017D01*
X166867Y751683D01*
X167450Y751600D01*
X168033Y751767D01*
X168617Y752267D01*
G01X172800Y756600D02*
Y751600D01*
G01X171633Y754933D02*
X173967D01*
G01X176983Y751600D02*
Y756600D01*
G01Y754183D02*
X177400Y754600D01*
X177817Y754850D01*
X178483Y754933D01*
X178983Y754850D01*
X179567Y754517D01*
X179817Y754017D01*
Y751600D01*
G01X184000D02*
X183500Y751683D01*
X183000Y752017D01*
X182667Y752600D01*
X182500Y753267D01*
X182667Y753933D01*
X183000Y754517D01*
X183500Y754850D01*
X184000Y754933D01*
X184500Y754850D01*
X185000Y754517D01*
X185333Y753933D01*
X185417Y753267D01*
X185333Y752600D01*
X185000Y752017D01*
X184500Y751683D01*
X184000Y751600D01*
G01X191100Y756600D02*
Y751600D01*
G01Y752350D02*
X190767Y751933D01*
X190267Y751683D01*
X189683Y751600D01*
X189017Y751767D01*
X188517Y752183D01*
X188183Y752683D01*
X188100Y753267D01*
X188183Y753850D01*
X188517Y754350D01*
X189017Y754767D01*
X189683Y754933D01*
X190267Y754850D01*
X190683Y754683D01*
X191100Y754350D01*
G01X193950Y752183D02*
X194367Y751850D01*
X194950Y751600D01*
X195450D01*
X195950Y751767D01*
X196283Y752017D01*
X196450Y752350D01*
X196367Y752850D01*
X196033Y753100D01*
X194533Y753600D01*
X194200Y754183D01*
X194367Y754600D01*
X194700Y754850D01*
X195200Y754933D01*
X195700Y754850D01*
X196200Y754600D01*
G01X204233Y751600D02*
Y756600D01*
X206400Y752433D01*
X208567Y756600D01*
Y751600D01*
G01X213500D02*
Y754933D01*
G01Y754350D02*
X213167Y754683D01*
X212667Y754850D01*
X212083Y754933D01*
X211500Y754767D01*
X211000Y754433D01*
X210667Y753933D01*
X210500Y753267D01*
X210667Y752600D01*
X211000Y752100D01*
X211500Y751767D01*
X212083Y751600D01*
X212667Y751683D01*
X213167Y751933D01*
X213500Y752267D01*
G01X216183Y751600D02*
Y754933D01*
G01Y754100D02*
X216517Y754517D01*
X217017Y754850D01*
X217683Y754933D01*
X218267Y754850D01*
X218767Y754517D01*
X219017Y753933D01*
Y751600D01*
G01X221783Y754933D02*
Y752600D01*
X222117Y752017D01*
X222617Y751683D01*
X223200Y751600D01*
X223783Y751683D01*
X224283Y752017D01*
X224617Y752600D01*
G01Y751600D02*
Y754933D01*
G01X230300Y751600D02*
Y754933D01*
G01Y754350D02*
X229967Y754683D01*
X229467Y754850D01*
X228883Y754933D01*
X228300Y754767D01*
X227800Y754433D01*
X227467Y753933D01*
X227300Y753267D01*
X227467Y752600D01*
X227800Y752100D01*
X228300Y751767D01*
X228883Y751600D01*
X229467Y751683D01*
X229967Y751933D01*
X230300Y752267D01*
G01X234400Y751600D02*
Y756600D01*
G01X71000Y765600D02*
X73000D01*
G01X72000D02*
Y760600D01*
G01X71000D02*
X73000D01*
G01X75933D02*
Y765600D01*
X77933D01*
X78600Y765350D01*
X79100Y764767D01*
X79267Y764100D01*
X79100Y763433D01*
X78683Y762933D01*
X77933Y762683D01*
X75933D01*
G01X85033Y765183D02*
X84533Y765433D01*
X83950Y765600D01*
X83283D01*
X82533Y765350D01*
X81950Y764933D01*
X81533Y764433D01*
X81200Y763600D01*
X81117Y762850D01*
X81283Y762100D01*
X81533Y761600D01*
X82033Y761100D01*
X82617Y760767D01*
X83200Y760600D01*
X83783D01*
X84367Y760767D01*
X84867Y761017D01*
X85283Y761350D01*
G01X87717Y762267D02*
X89883D01*
G01X92817Y762683D02*
X93400Y763267D01*
X93900Y763600D01*
X94567Y763767D01*
X95150Y763600D01*
X95567Y763267D01*
X95900Y762767D01*
X95983Y762183D01*
X95900Y761683D01*
X95567Y761183D01*
X95067Y760767D01*
X94483Y760600D01*
X93817Y760767D01*
X93233Y761267D01*
X92900Y762017D01*
X92817Y762850D01*
X92983Y763933D01*
X93233Y764517D01*
X93650Y765100D01*
X94233Y765517D01*
X94817Y765600D01*
X95400Y765433D01*
X95817Y765017D01*
G01X100000Y765600D02*
X99333Y765433D01*
X98833Y765017D01*
X98500Y764517D01*
X98250Y763850D01*
X98167Y763100D01*
X98250Y762350D01*
X98500Y761683D01*
X98833Y761183D01*
X99333Y760767D01*
X100000Y760600D01*
X100667Y760767D01*
X101167Y761183D01*
X101500Y761683D01*
X101750Y762350D01*
X101833Y763100D01*
X101750Y763850D01*
X101500Y764517D01*
X101167Y765017D01*
X100667Y765433D01*
X100000Y765600D01*
G01X105600Y760600D02*
Y765600D01*
X104600Y764600D01*
G01Y760600D02*
X106600D01*
G01X109617Y762683D02*
X110200Y763267D01*
X110700Y763600D01*
X111367Y763767D01*
X111950Y763600D01*
X112367Y763267D01*
X112700Y762767D01*
X112783Y762183D01*
X112700Y761683D01*
X112367Y761183D01*
X111867Y760767D01*
X111283Y760600D01*
X110617Y760767D01*
X110033Y761267D01*
X109700Y762017D01*
X109617Y762850D01*
X109783Y763933D01*
X110033Y764517D01*
X110450Y765100D01*
X111033Y765517D01*
X111617Y765600D01*
X112200Y765433D01*
X112617Y765017D01*
G01X122400Y760600D02*
X121733Y760683D01*
X121150Y761017D01*
X120650Y761517D01*
X120317Y762100D01*
X120150Y762767D01*
Y763433D01*
X120317Y764100D01*
X120650Y764683D01*
X121150Y765183D01*
X121733Y765517D01*
X122400Y765600D01*
X123067Y765517D01*
X123650Y765183D01*
X124150Y764683D01*
X124483Y764100D01*
X124650Y763433D01*
Y762767D01*
X124483Y762100D01*
X124150Y761517D01*
X123650Y761017D01*
X123067Y760683D01*
X122400Y760600D01*
G01X123067Y761933D02*
X124067Y760600D01*
G01X126583Y763933D02*
Y761600D01*
X126917Y761017D01*
X127417Y760683D01*
X128000Y760600D01*
X128583Y760683D01*
X129083Y761017D01*
X129417Y761600D01*
G01Y760600D02*
Y763933D01*
G01X135100Y760600D02*
Y763933D01*
G01Y763350D02*
X134767Y763683D01*
X134267Y763850D01*
X133683Y763933D01*
X133100Y763767D01*
X132600Y763433D01*
X132267Y762933D01*
X132100Y762267D01*
X132267Y761600D01*
X132600Y761100D01*
X133100Y760767D01*
X133683Y760600D01*
X134267Y760683D01*
X134767Y760933D01*
X135100Y761267D01*
G01X139200Y760600D02*
Y765600D01*
G01X144800Y763933D02*
Y760600D01*
G01Y765267D02*
X144633Y765350D01*
Y765517D01*
X144800Y765600D01*
X144967Y765517D01*
Y765350D01*
X144800Y765267D01*
G01X149900Y760600D02*
Y764850D01*
X150067Y765267D01*
X150400Y765517D01*
X150900Y765600D01*
X151400Y765433D01*
X151650Y765017D01*
G01X150650Y763600D02*
X148983D01*
G01X156000Y763933D02*
Y760600D01*
G01Y765267D02*
X155833Y765350D01*
Y765517D01*
X156000Y765600D01*
X156167Y765517D01*
Y765350D01*
X156000Y765267D01*
G01X162933Y763517D02*
X162350Y763850D01*
X161850Y763933D01*
X161183Y763767D01*
X160683Y763433D01*
X160350Y762850D01*
X160267Y762267D01*
X160350Y761683D01*
X160683Y761183D01*
X161183Y760767D01*
X161850Y760600D01*
X162433Y760767D01*
X162933Y761100D01*
G01X168700Y760600D02*
Y763933D01*
G01Y763350D02*
X168367Y763683D01*
X167867Y763850D01*
X167283Y763933D01*
X166700Y763767D01*
X166200Y763433D01*
X165867Y762933D01*
X165700Y762267D01*
X165867Y761600D01*
X166200Y761100D01*
X166700Y760767D01*
X167283Y760600D01*
X167867Y760683D01*
X168367Y760933D01*
X168700Y761267D01*
G01X172800Y765600D02*
Y760600D01*
G01X171633Y763933D02*
X173967D01*
G01X178400D02*
Y760600D01*
G01Y765267D02*
X178233Y765350D01*
Y765517D01*
X178400Y765600D01*
X178567Y765517D01*
Y765350D01*
X178400Y765267D01*
G01X184000Y760600D02*
X183500Y760683D01*
X183000Y761017D01*
X182667Y761600D01*
X182500Y762267D01*
X182667Y762933D01*
X183000Y763517D01*
X183500Y763850D01*
X184000Y763933D01*
X184500Y763850D01*
X185000Y763517D01*
X185333Y762933D01*
X185417Y762267D01*
X185333Y761600D01*
X185000Y761017D01*
X184500Y760683D01*
X184000Y760600D01*
G01X188183D02*
Y763933D01*
G01Y763100D02*
X188517Y763517D01*
X189017Y763850D01*
X189683Y763933D01*
X190267Y763850D01*
X190767Y763517D01*
X191017Y762933D01*
Y760600D01*
G01X203300Y758933D02*
X199133Y763933D01*
Y764767D01*
X199967Y765600D01*
X200800D01*
X201633Y764767D01*
Y763933D01*
X200800Y763100D01*
X199133Y762267D01*
X198300Y761433D01*
Y759767D01*
X199133Y758933D01*
X201633D01*
X203300Y760600D01*
G01X210333D02*
Y765600D01*
X212333D01*
X213000Y765350D01*
X213500Y764767D01*
X213667Y764100D01*
X213500Y763433D01*
X213083Y762933D01*
X212333Y762683D01*
X210333D01*
G01X216350Y762850D02*
X219017D01*
X218767Y763433D01*
X218350Y763767D01*
X217767Y763933D01*
X217183Y763850D01*
X216683Y763600D01*
X216350Y763017D01*
X216183Y762517D01*
Y762017D01*
X216350Y761517D01*
X216767Y761017D01*
X217267Y760683D01*
X217850Y760600D01*
X218433Y760767D01*
X219017Y761267D01*
G01X222033Y760600D02*
Y763933D01*
G01Y763267D02*
X222450Y763600D01*
X222867Y763850D01*
X223450Y763933D01*
X223867Y763850D01*
X224367Y763600D01*
G01X228300Y760600D02*
Y764850D01*
X228467Y765267D01*
X228800Y765517D01*
X229300Y765600D01*
X229800Y765433D01*
X230050Y765017D01*
G01X229050Y763600D02*
X227383D01*
G01X234400Y760600D02*
X233900Y760683D01*
X233400Y761017D01*
X233067Y761600D01*
X232900Y762267D01*
X233067Y762933D01*
X233400Y763517D01*
X233900Y763850D01*
X234400Y763933D01*
X234900Y763850D01*
X235400Y763517D01*
X235733Y762933D01*
X235817Y762267D01*
X235733Y761600D01*
X235400Y761017D01*
X234900Y760683D01*
X234400Y760600D01*
G01X238833D02*
Y763933D01*
G01Y763267D02*
X239250Y763600D01*
X239667Y763850D01*
X240250Y763933D01*
X240667Y763850D01*
X241167Y763600D01*
G01X243100Y760600D02*
Y763933D01*
G01Y763017D02*
X243350Y763433D01*
X243767Y763767D01*
X244350Y763933D01*
X244933Y763767D01*
X245350Y763433D01*
X245600Y763017D01*
Y760600D01*
G01Y763017D02*
X245850Y763433D01*
X246267Y763767D01*
X246850Y763933D01*
X247433Y763767D01*
X247850Y763433D01*
X248100Y762933D01*
Y760600D01*
G01X252700D02*
Y763933D01*
G01Y763350D02*
X252367Y763683D01*
X251867Y763850D01*
X251283Y763933D01*
X250700Y763767D01*
X250200Y763433D01*
X249867Y762933D01*
X249700Y762267D01*
X249867Y761600D01*
X250200Y761100D01*
X250700Y760767D01*
X251283Y760600D01*
X251867Y760683D01*
X252367Y760933D01*
X252700Y761267D01*
G01X255383Y760600D02*
Y763933D01*
G01Y763100D02*
X255717Y763517D01*
X256217Y763850D01*
X256883Y763933D01*
X257467Y763850D01*
X257967Y763517D01*
X258217Y762933D01*
Y760600D01*
G01X263733Y763517D02*
X263150Y763850D01*
X262650Y763933D01*
X261983Y763767D01*
X261483Y763433D01*
X261150Y762850D01*
X261067Y762267D01*
X261150Y761683D01*
X261483Y761183D01*
X261983Y760767D01*
X262650Y760600D01*
X263233Y760767D01*
X263733Y761100D01*
G01X266750Y762850D02*
X269417D01*
X269167Y763433D01*
X268750Y763767D01*
X268167Y763933D01*
X267583Y763850D01*
X267083Y763600D01*
X266750Y763017D01*
X266583Y762517D01*
Y762017D01*
X266750Y761517D01*
X267167Y761017D01*
X267667Y760683D01*
X268250Y760600D01*
X268833Y760767D01*
X269417Y761267D01*
G01X277450D02*
X278117Y760850D01*
X278867Y760600D01*
X279533D01*
X280200Y760850D01*
X280700Y761267D01*
X280950Y761850D01*
X280783Y762433D01*
X280367Y762933D01*
X279617Y763267D01*
X278617Y763433D01*
X278033Y763767D01*
X277783Y764350D01*
X277950Y764933D01*
X278367Y765350D01*
X278950Y765600D01*
X279533D01*
X280117Y765433D01*
X280617Y765017D01*
G01X283300Y758933D02*
Y763933D01*
G01Y763183D02*
X283717Y763600D01*
X284133Y763850D01*
X284800Y763933D01*
X285383Y763850D01*
X285967Y763433D01*
X286217Y762850D01*
X286300Y762267D01*
X286217Y761683D01*
X285967Y761100D01*
X285467Y760767D01*
X284800Y760600D01*
X284217Y760683D01*
X283633Y760933D01*
X283300Y761267D01*
G01X289150Y762850D02*
X291817D01*
X291567Y763433D01*
X291150Y763767D01*
X290567Y763933D01*
X289983Y763850D01*
X289483Y763600D01*
X289150Y763017D01*
X288983Y762517D01*
Y762017D01*
X289150Y761517D01*
X289567Y761017D01*
X290067Y760683D01*
X290650Y760600D01*
X291233Y760767D01*
X291817Y761267D01*
G01X297333Y763517D02*
X296750Y763850D01*
X296250Y763933D01*
X295583Y763767D01*
X295083Y763433D01*
X294750Y762850D01*
X294667Y762267D01*
X294750Y761683D01*
X295083Y761183D01*
X295583Y760767D01*
X296250Y760600D01*
X296833Y760767D01*
X297333Y761100D01*
G01X301600Y763933D02*
Y760600D01*
G01Y765267D02*
X301433Y765350D01*
Y765517D01*
X301600Y765600D01*
X301767Y765517D01*
Y765350D01*
X301600Y765267D01*
G01X306700Y760600D02*
Y764850D01*
X306867Y765267D01*
X307200Y765517D01*
X307700Y765600D01*
X308200Y765433D01*
X308450Y765017D01*
G01X307450Y763600D02*
X305783D01*
G01X312800Y763933D02*
Y760600D01*
G01Y765267D02*
X312633Y765350D01*
Y765517D01*
X312800Y765600D01*
X312967Y765517D01*
Y765350D01*
X312800Y765267D01*
G01X319733Y763517D02*
X319150Y763850D01*
X318650Y763933D01*
X317983Y763767D01*
X317483Y763433D01*
X317150Y762850D01*
X317067Y762267D01*
X317150Y761683D01*
X317483Y761183D01*
X317983Y760767D01*
X318650Y760600D01*
X319233Y760767D01*
X319733Y761100D01*
G01X325500Y760600D02*
Y763933D01*
G01Y763350D02*
X325167Y763683D01*
X324667Y763850D01*
X324083Y763933D01*
X323500Y763767D01*
X323000Y763433D01*
X322667Y762933D01*
X322500Y762267D01*
X322667Y761600D01*
X323000Y761100D01*
X323500Y760767D01*
X324083Y760600D01*
X324667Y760683D01*
X325167Y760933D01*
X325500Y761267D01*
G01X329600Y765600D02*
Y760600D01*
G01X328433Y763933D02*
X330767D01*
G01X335200D02*
Y760600D01*
G01Y765267D02*
X335033Y765350D01*
Y765517D01*
X335200Y765600D01*
X335367Y765517D01*
Y765350D01*
X335200Y765267D01*
G01X340800Y760600D02*
X340300Y760683D01*
X339800Y761017D01*
X339467Y761600D01*
X339300Y762267D01*
X339467Y762933D01*
X339800Y763517D01*
X340300Y763850D01*
X340800Y763933D01*
X341300Y763850D01*
X341800Y763517D01*
X342133Y762933D01*
X342217Y762267D01*
X342133Y761600D01*
X341800Y761017D01*
X341300Y760683D01*
X340800Y760600D01*
G01X344983D02*
Y763933D01*
G01Y763100D02*
X345317Y763517D01*
X345817Y763850D01*
X346483Y763933D01*
X347067Y763850D01*
X347567Y763517D01*
X347817Y762933D01*
Y760600D01*
G01X357100D02*
Y764850D01*
X357267Y765267D01*
X357600Y765517D01*
X358100Y765600D01*
X358600Y765433D01*
X358850Y765017D01*
G01X357850Y763600D02*
X356183D01*
G01X363200Y760600D02*
X362700Y760683D01*
X362200Y761017D01*
X361867Y761600D01*
X361700Y762267D01*
X361867Y762933D01*
X362200Y763517D01*
X362700Y763850D01*
X363200Y763933D01*
X363700Y763850D01*
X364200Y763517D01*
X364533Y762933D01*
X364617Y762267D01*
X364533Y761600D01*
X364200Y761017D01*
X363700Y760683D01*
X363200Y760600D01*
G01X367633D02*
Y763933D01*
G01Y763267D02*
X368050Y763600D01*
X368467Y763850D01*
X369050Y763933D01*
X369467Y763850D01*
X369967Y763600D01*
G01X378250Y760600D02*
Y765600D01*
G01X381750D02*
Y760600D01*
G01Y763100D02*
X378250D01*
G01X385600Y763933D02*
Y760600D01*
G01Y765267D02*
X385433Y765350D01*
Y765517D01*
X385600Y765600D01*
X385767Y765517D01*
Y765350D01*
X385600Y765267D01*
G01X390033Y759350D02*
X390617Y759017D01*
X391283Y758933D01*
X391867Y759017D01*
X392367Y759433D01*
X392700Y760017D01*
Y763933D01*
G01Y763267D02*
X392367Y763600D01*
X391867Y763850D01*
X391283Y763933D01*
X390617Y763767D01*
X390200Y763433D01*
X389867Y762850D01*
X389700Y762267D01*
X389783Y761767D01*
X390117Y761183D01*
X390617Y760767D01*
X391283Y760600D01*
X391783Y760683D01*
X392367Y761017D01*
X392700Y761350D01*
G01X395383Y760600D02*
Y765600D01*
G01Y763183D02*
X395800Y763600D01*
X396217Y763850D01*
X396883Y763933D01*
X397383Y763850D01*
X397967Y763517D01*
X398217Y763017D01*
Y760600D01*
G01X406167D02*
Y765600D01*
X407833D01*
X408500Y765350D01*
X409000Y765017D01*
X409417Y764517D01*
X409750Y763933D01*
X409833Y763100D01*
X409750Y762267D01*
X409417Y761683D01*
X409000Y761183D01*
X408500Y760850D01*
X407833Y760600D01*
X406167D01*
G01X412350Y762850D02*
X415017D01*
X414767Y763433D01*
X414350Y763767D01*
X413767Y763933D01*
X413183Y763850D01*
X412683Y763600D01*
X412350Y763017D01*
X412183Y762517D01*
Y762017D01*
X412350Y761517D01*
X412767Y761017D01*
X413267Y760683D01*
X413850Y760600D01*
X414433Y760767D01*
X415017Y761267D01*
G01X417783Y760600D02*
Y763933D01*
G01Y763100D02*
X418117Y763517D01*
X418617Y763850D01*
X419283Y763933D01*
X419867Y763850D01*
X420367Y763517D01*
X420617Y762933D01*
Y760600D01*
G01X423550Y761183D02*
X423967Y760850D01*
X424550Y760600D01*
X425050D01*
X425550Y760767D01*
X425883Y761017D01*
X426050Y761350D01*
X425967Y761850D01*
X425633Y762100D01*
X424133Y762600D01*
X423800Y763183D01*
X423967Y763600D01*
X424300Y763850D01*
X424800Y763933D01*
X425300Y763850D01*
X425800Y763600D01*
G01X430400Y763933D02*
Y760600D01*
G01Y765267D02*
X430233Y765350D01*
Y765517D01*
X430400Y765600D01*
X430567Y765517D01*
Y765350D01*
X430400Y765267D01*
G01X436000Y765600D02*
Y760600D01*
G01X434833Y763933D02*
X437167D01*
G01X439850Y759100D02*
X440350Y758933D01*
X441017Y759100D01*
X441433Y759433D01*
X441767Y759850D01*
X442267Y761183D01*
X443350Y763933D01*
G01X440683D02*
X442267Y761183D01*
G01X451800Y765600D02*
X453800D01*
G01X452800D02*
Y760600D01*
G01X451800D02*
X453800D01*
G01X456983D02*
Y763933D01*
G01Y763100D02*
X457317Y763517D01*
X457817Y763850D01*
X458483Y763933D01*
X459067Y763850D01*
X459567Y763517D01*
X459817Y762933D01*
Y760600D01*
G01X464000Y765600D02*
Y760600D01*
G01X462833Y763933D02*
X465167D01*
G01X468350Y762850D02*
X471017D01*
X470767Y763433D01*
X470350Y763767D01*
X469767Y763933D01*
X469183Y763850D01*
X468683Y763600D01*
X468350Y763017D01*
X468183Y762517D01*
Y762017D01*
X468350Y761517D01*
X468767Y761017D01*
X469267Y760683D01*
X469850Y760600D01*
X470433Y760767D01*
X471017Y761267D01*
G01X474033Y760600D02*
Y763933D01*
G01Y763267D02*
X474450Y763600D01*
X474867Y763850D01*
X475450Y763933D01*
X475867Y763850D01*
X476367Y763600D01*
G01X482133Y763517D02*
X481550Y763850D01*
X481050Y763933D01*
X480383Y763767D01*
X479883Y763433D01*
X479550Y762850D01*
X479467Y762267D01*
X479550Y761683D01*
X479883Y761183D01*
X480383Y760767D01*
X481050Y760600D01*
X481633Y760767D01*
X482133Y761100D01*
G01X486400Y760600D02*
X485900Y760683D01*
X485400Y761017D01*
X485067Y761600D01*
X484900Y762267D01*
X485067Y762933D01*
X485400Y763517D01*
X485900Y763850D01*
X486400Y763933D01*
X486900Y763850D01*
X487400Y763517D01*
X487733Y762933D01*
X487817Y762267D01*
X487733Y761600D01*
X487400Y761017D01*
X486900Y760683D01*
X486400Y760600D01*
G01X490583D02*
Y763933D01*
G01Y763100D02*
X490917Y763517D01*
X491417Y763850D01*
X492083Y763933D01*
X492667Y763850D01*
X493167Y763517D01*
X493417Y762933D01*
Y760600D01*
G01X496183D02*
Y763933D01*
G01Y763100D02*
X496517Y763517D01*
X497017Y763850D01*
X497683Y763933D01*
X498267Y763850D01*
X498767Y763517D01*
X499017Y762933D01*
Y760600D01*
G01X501950Y762850D02*
X504617D01*
X504367Y763433D01*
X503950Y763767D01*
X503367Y763933D01*
X502783Y763850D01*
X502283Y763600D01*
X501950Y763017D01*
X501783Y762517D01*
Y762017D01*
X501950Y761517D01*
X502367Y761017D01*
X502867Y760683D01*
X503450Y760600D01*
X504033Y760767D01*
X504617Y761267D01*
G01X510133Y763517D02*
X509550Y763850D01*
X509050Y763933D01*
X508383Y763767D01*
X507883Y763433D01*
X507550Y762850D01*
X507467Y762267D01*
X507550Y761683D01*
X507883Y761183D01*
X508383Y760767D01*
X509050Y760600D01*
X509633Y760767D01*
X510133Y761100D01*
G01X514400Y765600D02*
Y760600D01*
G01X513233Y763933D02*
X515567D01*
G01X519583Y758933D02*
X518750Y759767D01*
X518333Y760600D01*
Y763933D01*
X518750Y764767D01*
X519583Y765600D01*
G01X523850Y760600D02*
Y765600D01*
G01X527350D02*
Y760600D01*
G01Y763100D02*
X523850D01*
G01X529367Y760600D02*
Y765600D01*
X531033D01*
X531700Y765350D01*
X532200Y765017D01*
X532617Y764517D01*
X532950Y763933D01*
X533033Y763100D01*
X532950Y762267D01*
X532617Y761683D01*
X532200Y761183D01*
X531700Y760850D01*
X531033Y760600D01*
X529367D01*
G01X535800Y765600D02*
X537800D01*
G01X536800D02*
Y760600D01*
G01X535800D02*
X537800D01*
G01X542817Y758933D02*
X543650Y759767D01*
X544067Y760600D01*
Y763933D01*
X543650Y764767D01*
X542817Y765600D01*
G01X551933D02*
Y760600D01*
X555267D01*
G01X560700D02*
Y763933D01*
G01Y763350D02*
X560367Y763683D01*
X559867Y763850D01*
X559283Y763933D01*
X558700Y763767D01*
X558200Y763433D01*
X557867Y762933D01*
X557700Y762267D01*
X557867Y761600D01*
X558200Y761100D01*
X558700Y760767D01*
X559283Y760600D01*
X559867Y760683D01*
X560367Y760933D01*
X560700Y761267D01*
G01X563050Y759100D02*
X563550Y758933D01*
X564217Y759100D01*
X564633Y759433D01*
X564967Y759850D01*
X565467Y761183D01*
X566550Y763933D01*
G01X563883D02*
X565467Y761183D01*
G01X569150Y762850D02*
X571817D01*
X571567Y763433D01*
X571150Y763767D01*
X570567Y763933D01*
X569983Y763850D01*
X569483Y763600D01*
X569150Y763017D01*
X568983Y762517D01*
Y762017D01*
X569150Y761517D01*
X569567Y761017D01*
X570067Y760683D01*
X570650Y760600D01*
X571233Y760767D01*
X571817Y761267D01*
G01X574833Y760600D02*
Y763933D01*
G01Y763267D02*
X575250Y763600D01*
X575667Y763850D01*
X576250Y763933D01*
X576667Y763850D01*
X577167Y763600D01*
G01X580350Y761183D02*
X580767Y760850D01*
X581350Y760600D01*
X581850D01*
X582350Y760767D01*
X582683Y761017D01*
X582850Y761350D01*
X582767Y761850D01*
X582433Y762100D01*
X580933Y762600D01*
X580600Y763183D01*
X580767Y763600D01*
X581100Y763850D01*
X581600Y763933D01*
X582100Y763850D01*
X582600Y763600D01*
G01X592800Y760600D02*
X592300Y760683D01*
X591800Y761017D01*
X591467Y761600D01*
X591300Y762267D01*
X591467Y762933D01*
X591800Y763517D01*
X592300Y763850D01*
X592800Y763933D01*
X593300Y763850D01*
X593800Y763517D01*
X594133Y762933D01*
X594217Y762267D01*
X594133Y761600D01*
X593800Y761017D01*
X593300Y760683D01*
X592800Y760600D01*
G01X597233D02*
Y763933D01*
G01Y763267D02*
X597650Y763600D01*
X598067Y763850D01*
X598650Y763933D01*
X599067Y763850D01*
X599567Y763600D01*
G01X610267Y763267D02*
X610600Y763517D01*
X610850Y763933D01*
X611017Y764517D01*
X610850Y765017D01*
X610517Y765350D01*
X609933Y765600D01*
X607683D01*
Y760600D01*
X610433D01*
X611017Y760933D01*
X611350Y761433D01*
X611517Y762017D01*
X611350Y762600D01*
X610850Y763100D01*
X610267Y763267D01*
X607683D01*
G01X615200Y760600D02*
X614700Y760683D01*
X614200Y761017D01*
X613867Y761600D01*
X613700Y762267D01*
X613867Y762933D01*
X614200Y763517D01*
X614700Y763850D01*
X615200Y763933D01*
X615700Y763850D01*
X616200Y763517D01*
X616533Y762933D01*
X616617Y762267D01*
X616533Y761600D01*
X616200Y761017D01*
X615700Y760683D01*
X615200Y760600D01*
G01X622300D02*
Y763933D01*
G01Y763350D02*
X621967Y763683D01*
X621467Y763850D01*
X620883Y763933D01*
X620300Y763767D01*
X619800Y763433D01*
X619467Y762933D01*
X619300Y762267D01*
X619467Y761600D01*
X619800Y761100D01*
X620300Y760767D01*
X620883Y760600D01*
X621467Y760683D01*
X621967Y760933D01*
X622300Y761267D01*
G01X625233Y760600D02*
Y763933D01*
G01Y763267D02*
X625650Y763600D01*
X626067Y763850D01*
X626650Y763933D01*
X627067Y763850D01*
X627567Y763600D01*
G01X633500Y765600D02*
Y760600D01*
G01Y761350D02*
X633167Y760933D01*
X632667Y760683D01*
X632083Y760600D01*
X631417Y760767D01*
X630917Y761183D01*
X630583Y761683D01*
X630500Y762267D01*
X630583Y762850D01*
X630917Y763350D01*
X631417Y763767D01*
X632083Y763933D01*
X632667Y763850D01*
X633083Y763683D01*
X633500Y763350D01*
G01X636350Y761183D02*
X636767Y760850D01*
X637350Y760600D01*
X637850D01*
X638350Y760767D01*
X638683Y761017D01*
X638850Y761350D01*
X638767Y761850D01*
X638433Y762100D01*
X636933Y762600D01*
X636600Y763183D01*
X636767Y763600D01*
X637100Y763850D01*
X637600Y763933D01*
X638100Y763850D01*
X638600Y763600D01*
G01X643617Y758933D02*
X644450Y759767D01*
X644867Y760600D01*
Y763933D01*
X644450Y764767D01*
X643617Y765600D01*
G01X71000Y774600D02*
X73000D01*
G01X72000D02*
Y769600D01*
G01X71000D02*
X73000D01*
G01X75933D02*
Y774600D01*
X77933D01*
X78600Y774350D01*
X79100Y773767D01*
X79267Y773100D01*
X79100Y772433D01*
X78683Y771933D01*
X77933Y771683D01*
X75933D01*
G01X85033Y774183D02*
X84533Y774433D01*
X83950Y774600D01*
X83283D01*
X82533Y774350D01*
X81950Y773933D01*
X81533Y773433D01*
X81200Y772600D01*
X81117Y771850D01*
X81283Y771100D01*
X81533Y770600D01*
X82033Y770100D01*
X82617Y769767D01*
X83200Y769600D01*
X83783D01*
X84367Y769767D01*
X84867Y770017D01*
X85283Y770350D01*
G01X87717Y771267D02*
X89883D01*
G01X92817Y771683D02*
X93400Y772267D01*
X93900Y772600D01*
X94567Y772767D01*
X95150Y772600D01*
X95567Y772267D01*
X95900Y771767D01*
X95983Y771183D01*
X95900Y770683D01*
X95567Y770183D01*
X95067Y769767D01*
X94483Y769600D01*
X93817Y769767D01*
X93233Y770267D01*
X92900Y771017D01*
X92817Y771850D01*
X92983Y772933D01*
X93233Y773517D01*
X93650Y774100D01*
X94233Y774517D01*
X94817Y774600D01*
X95400Y774433D01*
X95817Y774017D01*
G01X100000Y774600D02*
X99333Y774433D01*
X98833Y774017D01*
X98500Y773517D01*
X98250Y772850D01*
X98167Y772100D01*
X98250Y771350D01*
X98500Y770683D01*
X98833Y770183D01*
X99333Y769767D01*
X100000Y769600D01*
X100667Y769767D01*
X101167Y770183D01*
X101500Y770683D01*
X101750Y771350D01*
X101833Y772100D01*
X101750Y772850D01*
X101500Y773517D01*
X101167Y774017D01*
X100667Y774433D01*
X100000Y774600D01*
G01X105600Y769600D02*
Y774600D01*
X104600Y773600D01*
G01Y769600D02*
X106600D01*
G01X109617Y773767D02*
X110117Y774267D01*
X110700Y774517D01*
X111367Y774600D01*
X112200Y774433D01*
X112783Y774017D01*
X112950Y773517D01*
X112867Y773017D01*
X112533Y772600D01*
X110867Y771767D01*
X110117Y771183D01*
X109617Y770350D01*
X109450Y769600D01*
X112950D01*
G01X122400D02*
X121733Y769683D01*
X121150Y770017D01*
X120650Y770517D01*
X120317Y771100D01*
X120150Y771767D01*
Y772433D01*
X120317Y773100D01*
X120650Y773683D01*
X121150Y774183D01*
X121733Y774517D01*
X122400Y774600D01*
X123067Y774517D01*
X123650Y774183D01*
X124150Y773683D01*
X124483Y773100D01*
X124650Y772433D01*
Y771767D01*
X124483Y771100D01*
X124150Y770517D01*
X123650Y770017D01*
X123067Y769683D01*
X122400Y769600D01*
G01X123067Y770933D02*
X124067Y769600D01*
G01X126583Y772933D02*
Y770600D01*
X126917Y770017D01*
X127417Y769683D01*
X128000Y769600D01*
X128583Y769683D01*
X129083Y770017D01*
X129417Y770600D01*
G01Y769600D02*
Y772933D01*
G01X135100Y769600D02*
Y772933D01*
G01Y772350D02*
X134767Y772683D01*
X134267Y772850D01*
X133683Y772933D01*
X133100Y772767D01*
X132600Y772433D01*
X132267Y771933D01*
X132100Y771267D01*
X132267Y770600D01*
X132600Y770100D01*
X133100Y769767D01*
X133683Y769600D01*
X134267Y769683D01*
X134767Y769933D01*
X135100Y770267D01*
G01X139200Y769600D02*
Y774600D01*
G01X144800Y772933D02*
Y769600D01*
G01Y774267D02*
X144633Y774350D01*
Y774517D01*
X144800Y774600D01*
X144967Y774517D01*
Y774350D01*
X144800Y774267D01*
G01X149900Y769600D02*
Y773850D01*
X150067Y774267D01*
X150400Y774517D01*
X150900Y774600D01*
X151400Y774433D01*
X151650Y774017D01*
G01X150650Y772600D02*
X148983D01*
G01X156000Y772933D02*
Y769600D01*
G01Y774267D02*
X155833Y774350D01*
Y774517D01*
X156000Y774600D01*
X156167Y774517D01*
Y774350D01*
X156000Y774267D01*
G01X162933Y772517D02*
X162350Y772850D01*
X161850Y772933D01*
X161183Y772767D01*
X160683Y772433D01*
X160350Y771850D01*
X160267Y771267D01*
X160350Y770683D01*
X160683Y770183D01*
X161183Y769767D01*
X161850Y769600D01*
X162433Y769767D01*
X162933Y770100D01*
G01X168700Y769600D02*
Y772933D01*
G01Y772350D02*
X168367Y772683D01*
X167867Y772850D01*
X167283Y772933D01*
X166700Y772767D01*
X166200Y772433D01*
X165867Y771933D01*
X165700Y771267D01*
X165867Y770600D01*
X166200Y770100D01*
X166700Y769767D01*
X167283Y769600D01*
X167867Y769683D01*
X168367Y769933D01*
X168700Y770267D01*
G01X172800Y774600D02*
Y769600D01*
G01X171633Y772933D02*
X173967D01*
G01X178400D02*
Y769600D01*
G01Y774267D02*
X178233Y774350D01*
Y774517D01*
X178400Y774600D01*
X178567Y774517D01*
Y774350D01*
X178400Y774267D01*
G01X184000Y769600D02*
X183500Y769683D01*
X183000Y770017D01*
X182667Y770600D01*
X182500Y771267D01*
X182667Y771933D01*
X183000Y772517D01*
X183500Y772850D01*
X184000Y772933D01*
X184500Y772850D01*
X185000Y772517D01*
X185333Y771933D01*
X185417Y771267D01*
X185333Y770600D01*
X185000Y770017D01*
X184500Y769683D01*
X184000Y769600D01*
G01X188183D02*
Y772933D01*
G01Y772100D02*
X188517Y772517D01*
X189017Y772850D01*
X189683Y772933D01*
X190267Y772850D01*
X190767Y772517D01*
X191017Y771933D01*
Y769600D01*
G01X202300D02*
Y772933D01*
G01Y772350D02*
X201967Y772683D01*
X201467Y772850D01*
X200883Y772933D01*
X200300Y772767D01*
X199800Y772433D01*
X199467Y771933D01*
X199300Y771267D01*
X199467Y770600D01*
X199800Y770100D01*
X200300Y769767D01*
X200883Y769600D01*
X201467Y769683D01*
X201967Y769933D01*
X202300Y770267D01*
G01X204983Y769600D02*
Y772933D01*
G01Y772100D02*
X205317Y772517D01*
X205817Y772850D01*
X206483Y772933D01*
X207067Y772850D01*
X207567Y772517D01*
X207817Y771933D01*
Y769600D01*
G01X213500Y774600D02*
Y769600D01*
G01Y770350D02*
X213167Y769933D01*
X212667Y769683D01*
X212083Y769600D01*
X211417Y769767D01*
X210917Y770183D01*
X210583Y770683D01*
X210500Y771267D01*
X210583Y771850D01*
X210917Y772350D01*
X211417Y772767D01*
X212083Y772933D01*
X212667Y772850D01*
X213083Y772683D01*
X213500Y772350D01*
G01X221533Y769600D02*
Y774600D01*
X223533D01*
X224200Y774350D01*
X224700Y773767D01*
X224867Y773100D01*
X224700Y772433D01*
X224283Y771933D01*
X223533Y771683D01*
X221533D01*
G01X227550Y771850D02*
X230217D01*
X229967Y772433D01*
X229550Y772767D01*
X228967Y772933D01*
X228383Y772850D01*
X227883Y772600D01*
X227550Y772017D01*
X227383Y771517D01*
Y771017D01*
X227550Y770517D01*
X227967Y770017D01*
X228467Y769683D01*
X229050Y769600D01*
X229633Y769767D01*
X230217Y770267D01*
G01X233233Y769600D02*
Y772933D01*
G01Y772267D02*
X233650Y772600D01*
X234067Y772850D01*
X234650Y772933D01*
X235067Y772850D01*
X235567Y772600D01*
G01X239500Y769600D02*
Y773850D01*
X239667Y774267D01*
X240000Y774517D01*
X240500Y774600D01*
X241000Y774433D01*
X241250Y774017D01*
G01X240250Y772600D02*
X238583D01*
G01X245600Y769600D02*
X245100Y769683D01*
X244600Y770017D01*
X244267Y770600D01*
X244100Y771267D01*
X244267Y771933D01*
X244600Y772517D01*
X245100Y772850D01*
X245600Y772933D01*
X246100Y772850D01*
X246600Y772517D01*
X246933Y771933D01*
X247017Y771267D01*
X246933Y770600D01*
X246600Y770017D01*
X246100Y769683D01*
X245600Y769600D01*
G01X250033D02*
Y772933D01*
G01Y772267D02*
X250450Y772600D01*
X250867Y772850D01*
X251450Y772933D01*
X251867Y772850D01*
X252367Y772600D01*
G01X254300Y769600D02*
Y772933D01*
G01Y772017D02*
X254550Y772433D01*
X254967Y772767D01*
X255550Y772933D01*
X256133Y772767D01*
X256550Y772433D01*
X256800Y772017D01*
Y769600D01*
G01Y772017D02*
X257050Y772433D01*
X257467Y772767D01*
X258050Y772933D01*
X258633Y772767D01*
X259050Y772433D01*
X259300Y771933D01*
Y769600D01*
G01X263900D02*
Y772933D01*
G01Y772350D02*
X263567Y772683D01*
X263067Y772850D01*
X262483Y772933D01*
X261900Y772767D01*
X261400Y772433D01*
X261067Y771933D01*
X260900Y771267D01*
X261067Y770600D01*
X261400Y770100D01*
X261900Y769767D01*
X262483Y769600D01*
X263067Y769683D01*
X263567Y769933D01*
X263900Y770267D01*
G01X266583Y769600D02*
Y772933D01*
G01Y772100D02*
X266917Y772517D01*
X267417Y772850D01*
X268083Y772933D01*
X268667Y772850D01*
X269167Y772517D01*
X269417Y771933D01*
Y769600D01*
G01X274933Y772517D02*
X274350Y772850D01*
X273850Y772933D01*
X273183Y772767D01*
X272683Y772433D01*
X272350Y771850D01*
X272267Y771267D01*
X272350Y770683D01*
X272683Y770183D01*
X273183Y769767D01*
X273850Y769600D01*
X274433Y769767D01*
X274933Y770100D01*
G01X277950Y771850D02*
X280617D01*
X280367Y772433D01*
X279950Y772767D01*
X279367Y772933D01*
X278783Y772850D01*
X278283Y772600D01*
X277950Y772017D01*
X277783Y771517D01*
Y771017D01*
X277950Y770517D01*
X278367Y770017D01*
X278867Y769683D01*
X279450Y769600D01*
X280033Y769767D01*
X280617Y770267D01*
G01X288650D02*
X289317Y769850D01*
X290067Y769600D01*
X290733D01*
X291400Y769850D01*
X291900Y770267D01*
X292150Y770850D01*
X291983Y771433D01*
X291567Y771933D01*
X290817Y772267D01*
X289817Y772433D01*
X289233Y772767D01*
X288983Y773350D01*
X289150Y773933D01*
X289567Y774350D01*
X290150Y774600D01*
X290733D01*
X291317Y774433D01*
X291817Y774017D01*
G01X294500Y767933D02*
Y772933D01*
G01Y772183D02*
X294917Y772600D01*
X295333Y772850D01*
X296000Y772933D01*
X296583Y772850D01*
X297167Y772433D01*
X297417Y771850D01*
X297500Y771267D01*
X297417Y770683D01*
X297167Y770100D01*
X296667Y769767D01*
X296000Y769600D01*
X295417Y769683D01*
X294833Y769933D01*
X294500Y770267D01*
G01X300350Y771850D02*
X303017D01*
X302767Y772433D01*
X302350Y772767D01*
X301767Y772933D01*
X301183Y772850D01*
X300683Y772600D01*
X300350Y772017D01*
X300183Y771517D01*
Y771017D01*
X300350Y770517D01*
X300767Y770017D01*
X301267Y769683D01*
X301850Y769600D01*
X302433Y769767D01*
X303017Y770267D01*
G01X308533Y772517D02*
X307950Y772850D01*
X307450Y772933D01*
X306783Y772767D01*
X306283Y772433D01*
X305950Y771850D01*
X305867Y771267D01*
X305950Y770683D01*
X306283Y770183D01*
X306783Y769767D01*
X307450Y769600D01*
X308033Y769767D01*
X308533Y770100D01*
G01X312800Y772933D02*
Y769600D01*
G01Y774267D02*
X312633Y774350D01*
Y774517D01*
X312800Y774600D01*
X312967Y774517D01*
Y774350D01*
X312800Y774267D01*
G01X317900Y769600D02*
Y773850D01*
X318067Y774267D01*
X318400Y774517D01*
X318900Y774600D01*
X319400Y774433D01*
X319650Y774017D01*
G01X318650Y772600D02*
X316983D01*
G01X324000Y772933D02*
Y769600D01*
G01Y774267D02*
X323833Y774350D01*
Y774517D01*
X324000Y774600D01*
X324167Y774517D01*
Y774350D01*
X324000Y774267D01*
G01X330933Y772517D02*
X330350Y772850D01*
X329850Y772933D01*
X329183Y772767D01*
X328683Y772433D01*
X328350Y771850D01*
X328267Y771267D01*
X328350Y770683D01*
X328683Y770183D01*
X329183Y769767D01*
X329850Y769600D01*
X330433Y769767D01*
X330933Y770100D01*
G01X336700Y769600D02*
Y772933D01*
G01Y772350D02*
X336367Y772683D01*
X335867Y772850D01*
X335283Y772933D01*
X334700Y772767D01*
X334200Y772433D01*
X333867Y771933D01*
X333700Y771267D01*
X333867Y770600D01*
X334200Y770100D01*
X334700Y769767D01*
X335283Y769600D01*
X335867Y769683D01*
X336367Y769933D01*
X336700Y770267D01*
G01X340800Y774600D02*
Y769600D01*
G01X339633Y772933D02*
X341967D01*
G01X346400D02*
Y769600D01*
G01Y774267D02*
X346233Y774350D01*
Y774517D01*
X346400Y774600D01*
X346567Y774517D01*
Y774350D01*
X346400Y774267D01*
G01X352000Y769600D02*
X351500Y769683D01*
X351000Y770017D01*
X350667Y770600D01*
X350500Y771267D01*
X350667Y771933D01*
X351000Y772517D01*
X351500Y772850D01*
X352000Y772933D01*
X352500Y772850D01*
X353000Y772517D01*
X353333Y771933D01*
X353417Y771267D01*
X353333Y770600D01*
X353000Y770017D01*
X352500Y769683D01*
X352000Y769600D01*
G01X356183D02*
Y772933D01*
G01Y772100D02*
X356517Y772517D01*
X357017Y772850D01*
X357683Y772933D01*
X358267Y772850D01*
X358767Y772517D01*
X359017Y771933D01*
Y769600D01*
G01X368300D02*
Y773850D01*
X368467Y774267D01*
X368800Y774517D01*
X369300Y774600D01*
X369800Y774433D01*
X370050Y774017D01*
G01X369050Y772600D02*
X367383D01*
G01X374400Y769600D02*
X373900Y769683D01*
X373400Y770017D01*
X373067Y770600D01*
X372900Y771267D01*
X373067Y771933D01*
X373400Y772517D01*
X373900Y772850D01*
X374400Y772933D01*
X374900Y772850D01*
X375400Y772517D01*
X375733Y771933D01*
X375817Y771267D01*
X375733Y770600D01*
X375400Y770017D01*
X374900Y769683D01*
X374400Y769600D01*
G01X378833D02*
Y772933D01*
G01Y772267D02*
X379250Y772600D01*
X379667Y772850D01*
X380250Y772933D01*
X380667Y772850D01*
X381167Y772600D01*
G01X389533Y769600D02*
Y774600D01*
X391617D01*
X392283Y774350D01*
X392700Y774017D01*
X392867Y773350D01*
X392700Y772683D01*
X392200Y772267D01*
X391617Y772017D01*
X389533D01*
G01X391617D02*
X392867Y769600D01*
G01X396800Y772933D02*
Y769600D01*
G01Y774267D02*
X396633Y774350D01*
Y774517D01*
X396800Y774600D01*
X396967Y774517D01*
Y774350D01*
X396800Y774267D01*
G01X401233Y768350D02*
X401817Y768017D01*
X402483Y767933D01*
X403067Y768017D01*
X403567Y768433D01*
X403900Y769017D01*
Y772933D01*
G01Y772267D02*
X403567Y772600D01*
X403067Y772850D01*
X402483Y772933D01*
X401817Y772767D01*
X401400Y772433D01*
X401067Y771850D01*
X400900Y771267D01*
X400983Y770767D01*
X401317Y770183D01*
X401817Y769767D01*
X402483Y769600D01*
X402983Y769683D01*
X403567Y770017D01*
X403900Y770350D01*
G01X408000Y772933D02*
Y769600D01*
G01Y774267D02*
X407833Y774350D01*
Y774517D01*
X408000Y774600D01*
X408167Y774517D01*
Y774350D01*
X408000Y774267D01*
G01X415100Y774600D02*
Y769600D01*
G01Y770350D02*
X414767Y769933D01*
X414267Y769683D01*
X413683Y769600D01*
X413017Y769767D01*
X412517Y770183D01*
X412183Y770683D01*
X412100Y771267D01*
X412183Y771850D01*
X412517Y772350D01*
X413017Y772767D01*
X413683Y772933D01*
X414267Y772850D01*
X414683Y772683D01*
X415100Y772350D01*
G01X423133Y769600D02*
Y774600D01*
X425133D01*
X425800Y774350D01*
X426300Y773767D01*
X426467Y773100D01*
X426300Y772433D01*
X425883Y771933D01*
X425133Y771683D01*
X423133D01*
G01X429233Y769600D02*
Y772933D01*
G01Y772267D02*
X429650Y772600D01*
X430067Y772850D01*
X430650Y772933D01*
X431067Y772850D01*
X431567Y772600D01*
G01X436000Y772933D02*
Y769600D01*
G01Y774267D02*
X435833Y774350D01*
Y774517D01*
X436000Y774600D01*
X436167Y774517D01*
Y774350D01*
X436000Y774267D01*
G01X440183Y769600D02*
Y772933D01*
G01Y772100D02*
X440517Y772517D01*
X441017Y772850D01*
X441683Y772933D01*
X442267Y772850D01*
X442767Y772517D01*
X443017Y771933D01*
Y769600D01*
G01X447200Y774600D02*
Y769600D01*
G01X446033Y772933D02*
X448367D01*
G01X451550Y771850D02*
X454217D01*
X453967Y772433D01*
X453550Y772767D01*
X452967Y772933D01*
X452383Y772850D01*
X451883Y772600D01*
X451550Y772017D01*
X451383Y771517D01*
Y771017D01*
X451550Y770517D01*
X451967Y770017D01*
X452467Y769683D01*
X453050Y769600D01*
X453633Y769767D01*
X454217Y770267D01*
G01X459900Y774600D02*
Y769600D01*
G01Y770350D02*
X459567Y769933D01*
X459067Y769683D01*
X458483Y769600D01*
X457817Y769767D01*
X457317Y770183D01*
X456983Y770683D01*
X456900Y771267D01*
X456983Y771850D01*
X457317Y772350D01*
X457817Y772767D01*
X458483Y772933D01*
X459067Y772850D01*
X459483Y772683D01*
X459900Y772350D01*
G01X470267Y772267D02*
X470600Y772517D01*
X470850Y772933D01*
X471017Y773517D01*
X470850Y774017D01*
X470517Y774350D01*
X469933Y774600D01*
X467683D01*
Y769600D01*
X470433D01*
X471017Y769933D01*
X471350Y770433D01*
X471517Y771017D01*
X471350Y771600D01*
X470850Y772100D01*
X470267Y772267D01*
X467683D01*
G01X475200Y769600D02*
X474700Y769683D01*
X474200Y770017D01*
X473867Y770600D01*
X473700Y771267D01*
X473867Y771933D01*
X474200Y772517D01*
X474700Y772850D01*
X475200Y772933D01*
X475700Y772850D01*
X476200Y772517D01*
X476533Y771933D01*
X476617Y771267D01*
X476533Y770600D01*
X476200Y770017D01*
X475700Y769683D01*
X475200Y769600D01*
G01X482300D02*
Y772933D01*
G01Y772350D02*
X481967Y772683D01*
X481467Y772850D01*
X480883Y772933D01*
X480300Y772767D01*
X479800Y772433D01*
X479467Y771933D01*
X479300Y771267D01*
X479467Y770600D01*
X479800Y770100D01*
X480300Y769767D01*
X480883Y769600D01*
X481467Y769683D01*
X481967Y769933D01*
X482300Y770267D01*
G01X485233Y769600D02*
Y772933D01*
G01Y772267D02*
X485650Y772600D01*
X486067Y772850D01*
X486650Y772933D01*
X487067Y772850D01*
X487567Y772600D01*
G01X493500Y774600D02*
Y769600D01*
G01Y770350D02*
X493167Y769933D01*
X492667Y769683D01*
X492083Y769600D01*
X491417Y769767D01*
X490917Y770183D01*
X490583Y770683D01*
X490500Y771267D01*
X490583Y771850D01*
X490917Y772350D01*
X491417Y772767D01*
X492083Y772933D01*
X492667Y772850D01*
X493083Y772683D01*
X493500Y772350D01*
G01X496350Y770183D02*
X496767Y769850D01*
X497350Y769600D01*
X497850D01*
X498350Y769767D01*
X498683Y770017D01*
X498850Y770350D01*
X498767Y770850D01*
X498433Y771100D01*
X496933Y771600D01*
X496600Y772183D01*
X496767Y772600D01*
X497100Y772850D01*
X497600Y772933D01*
X498100Y772850D01*
X498600Y772600D01*
G01X67000Y779433D02*
X66833Y779517D01*
Y779683D01*
X67000Y779767D01*
X67167Y779683D01*
Y779517D01*
X67000Y779433D01*
G01Y786333D02*
X66833Y786417D01*
Y786583D01*
X67000Y786667D01*
X67167Y786583D01*
Y786417D01*
X67000Y786333D01*
G01X71000Y783600D02*
X73000D01*
G01X72000D02*
Y778600D01*
G01X71000D02*
X73000D01*
G01X75933D02*
Y783600D01*
X77933D01*
X78600Y783350D01*
X79100Y782767D01*
X79267Y782100D01*
X79100Y781433D01*
X78683Y780933D01*
X77933Y780683D01*
X75933D01*
G01X85033Y783183D02*
X84533Y783433D01*
X83950Y783600D01*
X83283D01*
X82533Y783350D01*
X81950Y782933D01*
X81533Y782433D01*
X81200Y781600D01*
X81117Y780850D01*
X81283Y780100D01*
X81533Y779600D01*
X82033Y779100D01*
X82617Y778767D01*
X83200Y778600D01*
X83783D01*
X84367Y778767D01*
X84867Y779017D01*
X85283Y779350D01*
G01X87717Y780267D02*
X89883D01*
G01X92817Y780683D02*
X93400Y781267D01*
X93900Y781600D01*
X94567Y781767D01*
X95150Y781600D01*
X95567Y781267D01*
X95900Y780767D01*
X95983Y780183D01*
X95900Y779683D01*
X95567Y779183D01*
X95067Y778767D01*
X94483Y778600D01*
X93817Y778767D01*
X93233Y779267D01*
X92900Y780017D01*
X92817Y780850D01*
X92983Y781933D01*
X93233Y782517D01*
X93650Y783100D01*
X94233Y783517D01*
X94817Y783600D01*
X95400Y783433D01*
X95817Y783017D01*
G01X100000Y783600D02*
X99333Y783433D01*
X98833Y783017D01*
X98500Y782517D01*
X98250Y781850D01*
X98167Y781100D01*
X98250Y780350D01*
X98500Y779683D01*
X98833Y779183D01*
X99333Y778767D01*
X100000Y778600D01*
X100667Y778767D01*
X101167Y779183D01*
X101500Y779683D01*
X101750Y780350D01*
X101833Y781100D01*
X101750Y781850D01*
X101500Y782517D01*
X101167Y783017D01*
X100667Y783433D01*
X100000Y783600D01*
G01X105600Y778600D02*
Y783600D01*
X104600Y782600D01*
G01Y778600D02*
X106600D01*
G01X111200D02*
Y783600D01*
X110200Y782600D01*
G01Y778600D02*
X112200D01*
G01X122900Y781100D02*
X124567D01*
Y779600D01*
X124067Y779100D01*
X123483Y778767D01*
X122650Y778600D01*
X121817Y778767D01*
X121233Y779100D01*
X120733Y779600D01*
X120400Y780183D01*
X120233Y780850D01*
Y781433D01*
X120400Y781933D01*
X120733Y782517D01*
X121233Y783017D01*
X121733Y783350D01*
X122400Y783600D01*
X122983D01*
X123650Y783433D01*
X124150Y783100D01*
G01X126750Y780850D02*
X129417D01*
X129167Y781433D01*
X128750Y781767D01*
X128167Y781933D01*
X127583Y781850D01*
X127083Y781600D01*
X126750Y781017D01*
X126583Y780517D01*
Y780017D01*
X126750Y779517D01*
X127167Y779017D01*
X127667Y778683D01*
X128250Y778600D01*
X128833Y778767D01*
X129417Y779267D01*
G01X132183Y778600D02*
Y781933D01*
G01Y781100D02*
X132517Y781517D01*
X133017Y781850D01*
X133683Y781933D01*
X134267Y781850D01*
X134767Y781517D01*
X135017Y780933D01*
Y778600D01*
G01X137950Y780850D02*
X140617D01*
X140367Y781433D01*
X139950Y781767D01*
X139367Y781933D01*
X138783Y781850D01*
X138283Y781600D01*
X137950Y781017D01*
X137783Y780517D01*
Y780017D01*
X137950Y779517D01*
X138367Y779017D01*
X138867Y778683D01*
X139450Y778600D01*
X140033Y778767D01*
X140617Y779267D01*
G01X143633Y778600D02*
Y781933D01*
G01Y781267D02*
X144050Y781600D01*
X144467Y781850D01*
X145050Y781933D01*
X145467Y781850D01*
X145967Y781600D01*
G01X150400Y781933D02*
Y778600D01*
G01Y783267D02*
X150233Y783350D01*
Y783517D01*
X150400Y783600D01*
X150567Y783517D01*
Y783350D01*
X150400Y783267D01*
G01X157333Y781517D02*
X156750Y781850D01*
X156250Y781933D01*
X155583Y781767D01*
X155083Y781433D01*
X154750Y780850D01*
X154667Y780267D01*
X154750Y779683D01*
X155083Y779183D01*
X155583Y778767D01*
X156250Y778600D01*
X156833Y778767D01*
X157333Y779100D01*
G01X165533Y778600D02*
Y783600D01*
X167533D01*
X168200Y783350D01*
X168700Y782767D01*
X168867Y782100D01*
X168700Y781433D01*
X168283Y780933D01*
X167533Y780683D01*
X165533D01*
G01X171550Y780850D02*
X174217D01*
X173967Y781433D01*
X173550Y781767D01*
X172967Y781933D01*
X172383Y781850D01*
X171883Y781600D01*
X171550Y781017D01*
X171383Y780517D01*
Y780017D01*
X171550Y779517D01*
X171967Y779017D01*
X172467Y778683D01*
X173050Y778600D01*
X173633Y778767D01*
X174217Y779267D01*
G01X177233Y778600D02*
Y781933D01*
G01Y781267D02*
X177650Y781600D01*
X178067Y781850D01*
X178650Y781933D01*
X179067Y781850D01*
X179567Y781600D01*
G01X183500Y778600D02*
Y782850D01*
X183667Y783267D01*
X184000Y783517D01*
X184500Y783600D01*
X185000Y783433D01*
X185250Y783017D01*
G01X184250Y781600D02*
X182583D01*
G01X189600Y778600D02*
X189100Y778683D01*
X188600Y779017D01*
X188267Y779600D01*
X188100Y780267D01*
X188267Y780933D01*
X188600Y781517D01*
X189100Y781850D01*
X189600Y781933D01*
X190100Y781850D01*
X190600Y781517D01*
X190933Y780933D01*
X191017Y780267D01*
X190933Y779600D01*
X190600Y779017D01*
X190100Y778683D01*
X189600Y778600D01*
G01X194033D02*
Y781933D01*
G01Y781267D02*
X194450Y781600D01*
X194867Y781850D01*
X195450Y781933D01*
X195867Y781850D01*
X196367Y781600D01*
G01X198300Y778600D02*
Y781933D01*
G01Y781017D02*
X198550Y781433D01*
X198967Y781767D01*
X199550Y781933D01*
X200133Y781767D01*
X200550Y781433D01*
X200800Y781017D01*
Y778600D01*
G01Y781017D02*
X201050Y781433D01*
X201467Y781767D01*
X202050Y781933D01*
X202633Y781767D01*
X203050Y781433D01*
X203300Y780933D01*
Y778600D01*
G01X207900D02*
Y781933D01*
G01Y781350D02*
X207567Y781683D01*
X207067Y781850D01*
X206483Y781933D01*
X205900Y781767D01*
X205400Y781433D01*
X205067Y780933D01*
X204900Y780267D01*
X205067Y779600D01*
X205400Y779100D01*
X205900Y778767D01*
X206483Y778600D01*
X207067Y778683D01*
X207567Y778933D01*
X207900Y779267D01*
G01X210583Y778600D02*
Y781933D01*
G01Y781100D02*
X210917Y781517D01*
X211417Y781850D01*
X212083Y781933D01*
X212667Y781850D01*
X213167Y781517D01*
X213417Y780933D01*
Y778600D01*
G01X218933Y781517D02*
X218350Y781850D01*
X217850Y781933D01*
X217183Y781767D01*
X216683Y781433D01*
X216350Y780850D01*
X216267Y780267D01*
X216350Y779683D01*
X216683Y779183D01*
X217183Y778767D01*
X217850Y778600D01*
X218433Y778767D01*
X218933Y779100D01*
G01X221950Y780850D02*
X224617D01*
X224367Y781433D01*
X223950Y781767D01*
X223367Y781933D01*
X222783Y781850D01*
X222283Y781600D01*
X221950Y781017D01*
X221783Y780517D01*
Y780017D01*
X221950Y779517D01*
X222367Y779017D01*
X222867Y778683D01*
X223450Y778600D01*
X224033Y778767D01*
X224617Y779267D01*
G01X232650D02*
X233317Y778850D01*
X234067Y778600D01*
X234733D01*
X235400Y778850D01*
X235900Y779267D01*
X236150Y779850D01*
X235983Y780433D01*
X235567Y780933D01*
X234817Y781267D01*
X233817Y781433D01*
X233233Y781767D01*
X232983Y782350D01*
X233150Y782933D01*
X233567Y783350D01*
X234150Y783600D01*
X234733D01*
X235317Y783433D01*
X235817Y783017D01*
G01X238500Y776933D02*
Y781933D01*
G01Y781183D02*
X238917Y781600D01*
X239333Y781850D01*
X240000Y781933D01*
X240583Y781850D01*
X241167Y781433D01*
X241417Y780850D01*
X241500Y780267D01*
X241417Y779683D01*
X241167Y779100D01*
X240667Y778767D01*
X240000Y778600D01*
X239417Y778683D01*
X238833Y778933D01*
X238500Y779267D01*
G01X244350Y780850D02*
X247017D01*
X246767Y781433D01*
X246350Y781767D01*
X245767Y781933D01*
X245183Y781850D01*
X244683Y781600D01*
X244350Y781017D01*
X244183Y780517D01*
Y780017D01*
X244350Y779517D01*
X244767Y779017D01*
X245267Y778683D01*
X245850Y778600D01*
X246433Y778767D01*
X247017Y779267D01*
G01X252533Y781517D02*
X251950Y781850D01*
X251450Y781933D01*
X250783Y781767D01*
X250283Y781433D01*
X249950Y780850D01*
X249867Y780267D01*
X249950Y779683D01*
X250283Y779183D01*
X250783Y778767D01*
X251450Y778600D01*
X252033Y778767D01*
X252533Y779100D01*
G01X256800Y781933D02*
Y778600D01*
G01Y783267D02*
X256633Y783350D01*
Y783517D01*
X256800Y783600D01*
X256967Y783517D01*
Y783350D01*
X256800Y783267D01*
G01X261900Y778600D02*
Y782850D01*
X262067Y783267D01*
X262400Y783517D01*
X262900Y783600D01*
X263400Y783433D01*
X263650Y783017D01*
G01X262650Y781600D02*
X260983D01*
G01X268000Y781933D02*
Y778600D01*
G01Y783267D02*
X267833Y783350D01*
Y783517D01*
X268000Y783600D01*
X268167Y783517D01*
Y783350D01*
X268000Y783267D01*
G01X274933Y781517D02*
X274350Y781850D01*
X273850Y781933D01*
X273183Y781767D01*
X272683Y781433D01*
X272350Y780850D01*
X272267Y780267D01*
X272350Y779683D01*
X272683Y779183D01*
X273183Y778767D01*
X273850Y778600D01*
X274433Y778767D01*
X274933Y779100D01*
G01X280700Y778600D02*
Y781933D01*
G01Y781350D02*
X280367Y781683D01*
X279867Y781850D01*
X279283Y781933D01*
X278700Y781767D01*
X278200Y781433D01*
X277867Y780933D01*
X277700Y780267D01*
X277867Y779600D01*
X278200Y779100D01*
X278700Y778767D01*
X279283Y778600D01*
X279867Y778683D01*
X280367Y778933D01*
X280700Y779267D01*
G01X284800Y783600D02*
Y778600D01*
G01X283633Y781933D02*
X285967D01*
G01X290400D02*
Y778600D01*
G01Y783267D02*
X290233Y783350D01*
Y783517D01*
X290400Y783600D01*
X290567Y783517D01*
Y783350D01*
X290400Y783267D01*
G01X296000Y778600D02*
X295500Y778683D01*
X295000Y779017D01*
X294667Y779600D01*
X294500Y780267D01*
X294667Y780933D01*
X295000Y781517D01*
X295500Y781850D01*
X296000Y781933D01*
X296500Y781850D01*
X297000Y781517D01*
X297333Y780933D01*
X297417Y780267D01*
X297333Y779600D01*
X297000Y779017D01*
X296500Y778683D01*
X296000Y778600D01*
G01X300183D02*
Y781933D01*
G01Y781100D02*
X300517Y781517D01*
X301017Y781850D01*
X301683Y781933D01*
X302267Y781850D01*
X302767Y781517D01*
X303017Y780933D01*
Y778600D01*
G01X312300D02*
Y782850D01*
X312467Y783267D01*
X312800Y783517D01*
X313300Y783600D01*
X313800Y783433D01*
X314050Y783017D01*
G01X313050Y781600D02*
X311383D01*
G01X318400Y778600D02*
X317900Y778683D01*
X317400Y779017D01*
X317067Y779600D01*
X316900Y780267D01*
X317067Y780933D01*
X317400Y781517D01*
X317900Y781850D01*
X318400Y781933D01*
X318900Y781850D01*
X319400Y781517D01*
X319733Y780933D01*
X319817Y780267D01*
X319733Y779600D01*
X319400Y779017D01*
X318900Y778683D01*
X318400Y778600D01*
G01X322833D02*
Y781933D01*
G01Y781267D02*
X323250Y781600D01*
X323667Y781850D01*
X324250Y781933D01*
X324667Y781850D01*
X325167Y781600D01*
G01X333533Y778600D02*
Y783600D01*
X335533D01*
X336200Y783350D01*
X336700Y782767D01*
X336867Y782100D01*
X336700Y781433D01*
X336283Y780933D01*
X335533Y780683D01*
X333533D01*
G01X339633Y778600D02*
Y781933D01*
G01Y781267D02*
X340050Y781600D01*
X340467Y781850D01*
X341050Y781933D01*
X341467Y781850D01*
X341967Y781600D01*
G01X346400Y781933D02*
Y778600D01*
G01Y783267D02*
X346233Y783350D01*
Y783517D01*
X346400Y783600D01*
X346567Y783517D01*
Y783350D01*
X346400Y783267D01*
G01X350583Y778600D02*
Y781933D01*
G01Y781100D02*
X350917Y781517D01*
X351417Y781850D01*
X352083Y781933D01*
X352667Y781850D01*
X353167Y781517D01*
X353417Y780933D01*
Y778600D01*
G01X357600Y783600D02*
Y778600D01*
G01X356433Y781933D02*
X358767D01*
G01X361950Y780850D02*
X364617D01*
X364367Y781433D01*
X363950Y781767D01*
X363367Y781933D01*
X362783Y781850D01*
X362283Y781600D01*
X361950Y781017D01*
X361783Y780517D01*
Y780017D01*
X361950Y779517D01*
X362367Y779017D01*
X362867Y778683D01*
X363450Y778600D01*
X364033Y778767D01*
X364617Y779267D01*
G01X370300Y783600D02*
Y778600D01*
G01Y779350D02*
X369967Y778933D01*
X369467Y778683D01*
X368883Y778600D01*
X368217Y778767D01*
X367717Y779183D01*
X367383Y779683D01*
X367300Y780267D01*
X367383Y780850D01*
X367717Y781350D01*
X368217Y781767D01*
X368883Y781933D01*
X369467Y781850D01*
X369883Y781683D01*
X370300Y781350D01*
G01X380667Y781267D02*
X381000Y781517D01*
X381250Y781933D01*
X381417Y782517D01*
X381250Y783017D01*
X380917Y783350D01*
X380333Y783600D01*
X378083D01*
Y778600D01*
X380833D01*
X381417Y778933D01*
X381750Y779433D01*
X381917Y780017D01*
X381750Y780600D01*
X381250Y781100D01*
X380667Y781267D01*
X378083D01*
G01X385600Y778600D02*
X385100Y778683D01*
X384600Y779017D01*
X384267Y779600D01*
X384100Y780267D01*
X384267Y780933D01*
X384600Y781517D01*
X385100Y781850D01*
X385600Y781933D01*
X386100Y781850D01*
X386600Y781517D01*
X386933Y780933D01*
X387017Y780267D01*
X386933Y779600D01*
X386600Y779017D01*
X386100Y778683D01*
X385600Y778600D01*
G01X392700D02*
Y781933D01*
G01Y781350D02*
X392367Y781683D01*
X391867Y781850D01*
X391283Y781933D01*
X390700Y781767D01*
X390200Y781433D01*
X389867Y780933D01*
X389700Y780267D01*
X389867Y779600D01*
X390200Y779100D01*
X390700Y778767D01*
X391283Y778600D01*
X391867Y778683D01*
X392367Y778933D01*
X392700Y779267D01*
G01X395633Y778600D02*
Y781933D01*
G01Y781267D02*
X396050Y781600D01*
X396467Y781850D01*
X397050Y781933D01*
X397467Y781850D01*
X397967Y781600D01*
G01X403900Y783600D02*
Y778600D01*
G01Y779350D02*
X403567Y778933D01*
X403067Y778683D01*
X402483Y778600D01*
X401817Y778767D01*
X401317Y779183D01*
X400983Y779683D01*
X400900Y780267D01*
X400983Y780850D01*
X401317Y781350D01*
X401817Y781767D01*
X402483Y781933D01*
X403067Y781850D01*
X403483Y781683D01*
X403900Y781350D01*
G01X406750Y779183D02*
X407167Y778850D01*
X407750Y778600D01*
X408250D01*
X408750Y778767D01*
X409083Y779017D01*
X409250Y779350D01*
X409167Y779850D01*
X408833Y780100D01*
X407333Y780600D01*
X407000Y781183D01*
X407167Y781600D01*
X407500Y781850D01*
X408000Y781933D01*
X408500Y781850D01*
X409000Y781600D01*
G01X71000Y791500D02*
X73000D01*
G01X72000D02*
Y786500D01*
G01X71000D02*
X73000D01*
G01X75933D02*
Y791500D01*
X77933D01*
X78600Y791250D01*
X79100Y790667D01*
X79267Y790000D01*
X79100Y789333D01*
X78683Y788833D01*
X77933Y788583D01*
X75933D01*
G01X85033Y791083D02*
X84533Y791333D01*
X83950Y791500D01*
X83283D01*
X82533Y791250D01*
X81950Y790833D01*
X81533Y790333D01*
X81200Y789500D01*
X81117Y788750D01*
X81283Y788000D01*
X81533Y787500D01*
X82033Y787000D01*
X82617Y786667D01*
X83200Y786500D01*
X83783D01*
X84367Y786667D01*
X84867Y786917D01*
X85283Y787250D01*
G01X87717Y788167D02*
X89883D01*
G01X92317Y786500D02*
X94400Y791500D01*
X96483Y786500D01*
G01X95733Y788250D02*
X93067D01*
G01X98917Y788167D02*
X101083D01*
G01X104017Y788583D02*
X104600Y789167D01*
X105100Y789500D01*
X105767Y789667D01*
X106350Y789500D01*
X106767Y789167D01*
X107100Y788667D01*
X107183Y788083D01*
X107100Y787583D01*
X106767Y787083D01*
X106267Y786667D01*
X105683Y786500D01*
X105017Y786667D01*
X104433Y787167D01*
X104100Y787917D01*
X104017Y788750D01*
X104183Y789833D01*
X104433Y790417D01*
X104850Y791000D01*
X105433Y791417D01*
X106017Y791500D01*
X106600Y791333D01*
X107017Y790917D01*
G01X111200Y791500D02*
X110533Y791333D01*
X110033Y790917D01*
X109700Y790417D01*
X109450Y789750D01*
X109367Y789000D01*
X109450Y788250D01*
X109700Y787583D01*
X110033Y787083D01*
X110533Y786667D01*
X111200Y786500D01*
X111867Y786667D01*
X112367Y787083D01*
X112700Y787583D01*
X112950Y788250D01*
X113033Y789000D01*
X112950Y789750D01*
X112700Y790417D01*
X112367Y790917D01*
X111867Y791333D01*
X111200Y791500D01*
G01X116800D02*
X116133Y791333D01*
X115633Y790917D01*
X115300Y790417D01*
X115050Y789750D01*
X114967Y789000D01*
X115050Y788250D01*
X115300Y787583D01*
X115633Y787083D01*
X116133Y786667D01*
X116800Y786500D01*
X117467Y786667D01*
X117967Y787083D01*
X118300Y787583D01*
X118550Y788250D01*
X118633Y789000D01*
X118550Y789750D01*
X118300Y790417D01*
X117967Y790917D01*
X117467Y791333D01*
X116800Y791500D01*
G01X125917Y786500D02*
X128000Y791500D01*
X130083Y786500D01*
G01X129333Y788250D02*
X126667D01*
G01X134933Y789417D02*
X134350Y789750D01*
X133850Y789833D01*
X133183Y789667D01*
X132683Y789333D01*
X132350Y788750D01*
X132267Y788167D01*
X132350Y787583D01*
X132683Y787083D01*
X133183Y786667D01*
X133850Y786500D01*
X134433Y786667D01*
X134933Y787000D01*
G01X140533Y789417D02*
X139950Y789750D01*
X139450Y789833D01*
X138783Y789667D01*
X138283Y789333D01*
X137950Y788750D01*
X137867Y788167D01*
X137950Y787583D01*
X138283Y787083D01*
X138783Y786667D01*
X139450Y786500D01*
X140033Y786667D01*
X140533Y787000D01*
G01X143550Y788750D02*
X146217D01*
X145967Y789333D01*
X145550Y789667D01*
X144967Y789833D01*
X144383Y789750D01*
X143883Y789500D01*
X143550Y788917D01*
X143383Y788417D01*
Y787917D01*
X143550Y787417D01*
X143967Y786917D01*
X144467Y786583D01*
X145050Y786500D01*
X145633Y786667D01*
X146217Y787167D01*
G01X148900Y784833D02*
Y789833D01*
G01Y789083D02*
X149317Y789500D01*
X149733Y789750D01*
X150400Y789833D01*
X150983Y789750D01*
X151567Y789333D01*
X151817Y788750D01*
X151900Y788167D01*
X151817Y787583D01*
X151567Y787000D01*
X151067Y786667D01*
X150400Y786500D01*
X149817Y786583D01*
X149233Y786833D01*
X148900Y787167D01*
G01X156000Y791500D02*
Y786500D01*
G01X154833Y789833D02*
X157167D01*
G01X163100Y786500D02*
Y789833D01*
G01Y789250D02*
X162767Y789583D01*
X162267Y789750D01*
X161683Y789833D01*
X161100Y789667D01*
X160600Y789333D01*
X160267Y788833D01*
X160100Y788167D01*
X160267Y787500D01*
X160600Y787000D01*
X161100Y786667D01*
X161683Y786500D01*
X162267Y786583D01*
X162767Y786833D01*
X163100Y787167D01*
G01X165700Y786500D02*
Y791500D01*
G01Y789000D02*
X166117Y789500D01*
X166617Y789750D01*
X167117Y789833D01*
X167867Y789667D01*
X168367Y789333D01*
X168700Y788750D01*
Y788083D01*
X168533Y787417D01*
X168200Y786917D01*
X167617Y786583D01*
X167117Y786500D01*
X166617Y786583D01*
X166117Y786833D01*
X165700Y787250D01*
G01X172800Y789833D02*
Y786500D01*
G01Y791167D02*
X172633Y791250D01*
Y791417D01*
X172800Y791500D01*
X172967Y791417D01*
Y791250D01*
X172800Y791167D01*
G01X178400Y786500D02*
Y791500D01*
G01X184000Y789833D02*
Y786500D01*
G01Y791167D02*
X183833Y791250D01*
Y791417D01*
X184000Y791500D01*
X184167Y791417D01*
Y791250D01*
X184000Y791167D01*
G01X189600Y791500D02*
Y786500D01*
G01X188433Y789833D02*
X190767D01*
G01X193450Y785000D02*
X193950Y784833D01*
X194617Y785000D01*
X195033Y785333D01*
X195367Y785750D01*
X195867Y787083D01*
X196950Y789833D01*
G01X194283D02*
X195867Y787083D01*
G01X206400Y786500D02*
X205900Y786583D01*
X205400Y786917D01*
X205067Y787500D01*
X204900Y788167D01*
X205067Y788833D01*
X205400Y789417D01*
X205900Y789750D01*
X206400Y789833D01*
X206900Y789750D01*
X207400Y789417D01*
X207733Y788833D01*
X207817Y788167D01*
X207733Y787500D01*
X207400Y786917D01*
X206900Y786583D01*
X206400Y786500D01*
G01X211500D02*
Y790750D01*
X211667Y791167D01*
X212000Y791417D01*
X212500Y791500D01*
X213000Y791333D01*
X213250Y790917D01*
G01X212250Y789500D02*
X210583D01*
G01X221533Y786500D02*
Y791500D01*
X223533D01*
X224200Y791250D01*
X224700Y790667D01*
X224867Y790000D01*
X224700Y789333D01*
X224283Y788833D01*
X223533Y788583D01*
X221533D01*
G01X227633Y786500D02*
Y789833D01*
G01Y789167D02*
X228050Y789500D01*
X228467Y789750D01*
X229050Y789833D01*
X229467Y789750D01*
X229967Y789500D01*
G01X234400Y789833D02*
Y786500D01*
G01Y791167D02*
X234233Y791250D01*
Y791417D01*
X234400Y791500D01*
X234567Y791417D01*
Y791250D01*
X234400Y791167D01*
G01X238583Y786500D02*
Y789833D01*
G01Y789000D02*
X238917Y789417D01*
X239417Y789750D01*
X240083Y789833D01*
X240667Y789750D01*
X241167Y789417D01*
X241417Y788833D01*
Y786500D01*
G01X245600Y791500D02*
Y786500D01*
G01X244433Y789833D02*
X246767D01*
G01X249950Y788750D02*
X252617D01*
X252367Y789333D01*
X251950Y789667D01*
X251367Y789833D01*
X250783Y789750D01*
X250283Y789500D01*
X249950Y788917D01*
X249783Y788417D01*
Y787917D01*
X249950Y787417D01*
X250367Y786917D01*
X250867Y786583D01*
X251450Y786500D01*
X252033Y786667D01*
X252617Y787167D01*
G01X258300Y791500D02*
Y786500D01*
G01Y787250D02*
X257967Y786833D01*
X257467Y786583D01*
X256883Y786500D01*
X256217Y786667D01*
X255717Y787083D01*
X255383Y787583D01*
X255300Y788167D01*
X255383Y788750D01*
X255717Y789250D01*
X256217Y789667D01*
X256883Y789833D01*
X257467Y789750D01*
X257883Y789583D01*
X258300Y789250D01*
G01X268667Y789167D02*
X269000Y789417D01*
X269250Y789833D01*
X269417Y790417D01*
X269250Y790917D01*
X268917Y791250D01*
X268333Y791500D01*
X266083D01*
Y786500D01*
X268833D01*
X269417Y786833D01*
X269750Y787333D01*
X269917Y787917D01*
X269750Y788500D01*
X269250Y789000D01*
X268667Y789167D01*
X266083D01*
G01X273600Y786500D02*
X273100Y786583D01*
X272600Y786917D01*
X272267Y787500D01*
X272100Y788167D01*
X272267Y788833D01*
X272600Y789417D01*
X273100Y789750D01*
X273600Y789833D01*
X274100Y789750D01*
X274600Y789417D01*
X274933Y788833D01*
X275017Y788167D01*
X274933Y787500D01*
X274600Y786917D01*
X274100Y786583D01*
X273600Y786500D01*
G01X280700D02*
Y789833D01*
G01Y789250D02*
X280367Y789583D01*
X279867Y789750D01*
X279283Y789833D01*
X278700Y789667D01*
X278200Y789333D01*
X277867Y788833D01*
X277700Y788167D01*
X277867Y787500D01*
X278200Y787000D01*
X278700Y786667D01*
X279283Y786500D01*
X279867Y786583D01*
X280367Y786833D01*
X280700Y787167D01*
G01X283633Y786500D02*
Y789833D01*
G01Y789167D02*
X284050Y789500D01*
X284467Y789750D01*
X285050Y789833D01*
X285467Y789750D01*
X285967Y789500D01*
G01X291900Y791500D02*
Y786500D01*
G01Y787250D02*
X291567Y786833D01*
X291067Y786583D01*
X290483Y786500D01*
X289817Y786667D01*
X289317Y787083D01*
X288983Y787583D01*
X288900Y788167D01*
X288983Y788750D01*
X289317Y789250D01*
X289817Y789667D01*
X290483Y789833D01*
X291067Y789750D01*
X291483Y789583D01*
X291900Y789250D01*
G01X294750Y787083D02*
X295167Y786750D01*
X295750Y786500D01*
X296250D01*
X296750Y786667D01*
X297083Y786917D01*
X297250Y787250D01*
X297167Y787750D01*
X296833Y788000D01*
X295333Y788500D01*
X295000Y789083D01*
X295167Y789500D01*
X295500Y789750D01*
X296000Y789833D01*
X296500Y789750D01*
X297000Y789500D01*
G01X57833Y806500D02*
Y811500D01*
X59833D01*
X60500Y811250D01*
X61000Y810667D01*
X61167Y810000D01*
X61000Y809333D01*
X60583Y808833D01*
X59833Y808583D01*
X57833D01*
G01X65100Y806500D02*
Y811500D01*
G01X69450Y808750D02*
X72117D01*
X71867Y809333D01*
X71450Y809667D01*
X70867Y809833D01*
X70283Y809750D01*
X69783Y809500D01*
X69450Y808917D01*
X69283Y808417D01*
Y807917D01*
X69450Y807417D01*
X69867Y806917D01*
X70367Y806583D01*
X70950Y806500D01*
X71533Y806667D01*
X72117Y807167D01*
G01X77800Y806500D02*
Y809833D01*
G01Y809250D02*
X77467Y809583D01*
X76967Y809750D01*
X76383Y809833D01*
X75800Y809667D01*
X75300Y809333D01*
X74967Y808833D01*
X74800Y808167D01*
X74967Y807500D01*
X75300Y807000D01*
X75800Y806667D01*
X76383Y806500D01*
X76967Y806583D01*
X77467Y806833D01*
X77800Y807167D01*
G01X80650Y807083D02*
X81067Y806750D01*
X81650Y806500D01*
X82150D01*
X82650Y806667D01*
X82983Y806917D01*
X83150Y807250D01*
X83067Y807750D01*
X82733Y808000D01*
X81233Y808500D01*
X80900Y809083D01*
X81067Y809500D01*
X81400Y809750D01*
X81900Y809833D01*
X82400Y809750D01*
X82900Y809500D01*
G01X86250Y808750D02*
X88917D01*
X88667Y809333D01*
X88250Y809667D01*
X87667Y809833D01*
X87083Y809750D01*
X86583Y809500D01*
X86250Y808917D01*
X86083Y808417D01*
Y807917D01*
X86250Y807417D01*
X86667Y806917D01*
X87167Y806583D01*
X87750Y806500D01*
X88333Y806667D01*
X88917Y807167D01*
G01X98200Y806500D02*
Y810750D01*
X98367Y811167D01*
X98700Y811417D01*
X99200Y811500D01*
X99700Y811333D01*
X99950Y810917D01*
G01X98950Y809500D02*
X97283D01*
G01X104300Y806500D02*
X103800Y806583D01*
X103300Y806917D01*
X102967Y807500D01*
X102800Y808167D01*
X102967Y808833D01*
X103300Y809417D01*
X103800Y809750D01*
X104300Y809833D01*
X104800Y809750D01*
X105300Y809417D01*
X105633Y808833D01*
X105717Y808167D01*
X105633Y807500D01*
X105300Y806917D01*
X104800Y806583D01*
X104300Y806500D01*
G01X109900D02*
Y811500D01*
G01X115500Y806500D02*
Y811500D01*
G01X121100Y806500D02*
X120600Y806583D01*
X120100Y806917D01*
X119767Y807500D01*
X119600Y808167D01*
X119767Y808833D01*
X120100Y809417D01*
X120600Y809750D01*
X121100Y809833D01*
X121600Y809750D01*
X122100Y809417D01*
X122433Y808833D01*
X122517Y808167D01*
X122433Y807500D01*
X122100Y806917D01*
X121600Y806583D01*
X121100Y806500D01*
G01X124617Y809833D02*
X125617Y806500D01*
X126700Y809833D01*
X127783Y806500D01*
X128783Y809833D01*
G01X137900Y811500D02*
Y806500D01*
G01X136733Y809833D02*
X139067D01*
G01X142083Y806500D02*
Y811500D01*
G01Y809083D02*
X142500Y809500D01*
X142917Y809750D01*
X143583Y809833D01*
X144083Y809750D01*
X144667Y809417D01*
X144917Y808917D01*
Y806500D01*
G01X147850Y808750D02*
X150517D01*
X150267Y809333D01*
X149850Y809667D01*
X149267Y809833D01*
X148683Y809750D01*
X148183Y809500D01*
X147850Y808917D01*
X147683Y808417D01*
Y807917D01*
X147850Y807417D01*
X148267Y806917D01*
X148767Y806583D01*
X149350Y806500D01*
X149933Y806667D01*
X150517Y807167D01*
G01X159050Y807083D02*
X159467Y806750D01*
X160050Y806500D01*
X160550D01*
X161050Y806667D01*
X161383Y806917D01*
X161550Y807250D01*
X161467Y807750D01*
X161133Y808000D01*
X159633Y808500D01*
X159300Y809083D01*
X159467Y809500D01*
X159800Y809750D01*
X160300Y809833D01*
X160800Y809750D01*
X161300Y809500D01*
G01X164400Y804833D02*
Y809833D01*
G01Y809083D02*
X164817Y809500D01*
X165233Y809750D01*
X165900Y809833D01*
X166483Y809750D01*
X167067Y809333D01*
X167317Y808750D01*
X167400Y808167D01*
X167317Y807583D01*
X167067Y807000D01*
X166567Y806667D01*
X165900Y806500D01*
X165317Y806583D01*
X164733Y806833D01*
X164400Y807167D01*
G01X170250Y808750D02*
X172917D01*
X172667Y809333D01*
X172250Y809667D01*
X171667Y809833D01*
X171083Y809750D01*
X170583Y809500D01*
X170250Y808917D01*
X170083Y808417D01*
Y807917D01*
X170250Y807417D01*
X170667Y806917D01*
X171167Y806583D01*
X171750Y806500D01*
X172333Y806667D01*
X172917Y807167D01*
G01X178433Y809417D02*
X177850Y809750D01*
X177350Y809833D01*
X176683Y809667D01*
X176183Y809333D01*
X175850Y808750D01*
X175767Y808167D01*
X175850Y807583D01*
X176183Y807083D01*
X176683Y806667D01*
X177350Y806500D01*
X177933Y806667D01*
X178433Y807000D01*
G01X182700Y809833D02*
Y806500D01*
G01Y811167D02*
X182533Y811250D01*
Y811417D01*
X182700Y811500D01*
X182867Y811417D01*
Y811250D01*
X182700Y811167D01*
G01X187800Y806500D02*
Y810750D01*
X187967Y811167D01*
X188300Y811417D01*
X188800Y811500D01*
X189300Y811333D01*
X189550Y810917D01*
G01X188550Y809500D02*
X186883D01*
G01X193900Y809833D02*
Y806500D01*
G01Y811167D02*
X193733Y811250D01*
Y811417D01*
X193900Y811500D01*
X194067Y811417D01*
Y811250D01*
X193900Y811167D01*
G01X200833Y809417D02*
X200250Y809750D01*
X199750Y809833D01*
X199083Y809667D01*
X198583Y809333D01*
X198250Y808750D01*
X198167Y808167D01*
X198250Y807583D01*
X198583Y807083D01*
X199083Y806667D01*
X199750Y806500D01*
X200333Y806667D01*
X200833Y807000D01*
G01X206600Y806500D02*
Y809833D01*
G01Y809250D02*
X206267Y809583D01*
X205767Y809750D01*
X205183Y809833D01*
X204600Y809667D01*
X204100Y809333D01*
X203767Y808833D01*
X203600Y808167D01*
X203767Y807500D01*
X204100Y807000D01*
X204600Y806667D01*
X205183Y806500D01*
X205767Y806583D01*
X206267Y806833D01*
X206600Y807167D01*
G01X210700Y811500D02*
Y806500D01*
G01X209533Y809833D02*
X211867D01*
G01X216300D02*
Y806500D01*
G01Y811167D02*
X216133Y811250D01*
Y811417D01*
X216300Y811500D01*
X216467Y811417D01*
Y811250D01*
X216300Y811167D01*
G01X221900Y806500D02*
X221400Y806583D01*
X220900Y806917D01*
X220567Y807500D01*
X220400Y808167D01*
X220567Y808833D01*
X220900Y809417D01*
X221400Y809750D01*
X221900Y809833D01*
X222400Y809750D01*
X222900Y809417D01*
X223233Y808833D01*
X223317Y808167D01*
X223233Y807500D01*
X222900Y806917D01*
X222400Y806583D01*
X221900Y806500D01*
G01X226083D02*
Y809833D01*
G01Y809000D02*
X226417Y809417D01*
X226917Y809750D01*
X227583Y809833D01*
X228167Y809750D01*
X228667Y809417D01*
X228917Y808833D01*
Y806500D01*
G01X240200Y811500D02*
Y806500D01*
G01Y807250D02*
X239867Y806833D01*
X239367Y806583D01*
X238783Y806500D01*
X238117Y806667D01*
X237617Y807083D01*
X237283Y807583D01*
X237200Y808167D01*
X237283Y808750D01*
X237617Y809250D01*
X238117Y809667D01*
X238783Y809833D01*
X239367Y809750D01*
X239783Y809583D01*
X240200Y809250D01*
G01X244300Y806500D02*
X243800Y806583D01*
X243300Y806917D01*
X242967Y807500D01*
X242800Y808167D01*
X242967Y808833D01*
X243300Y809417D01*
X243800Y809750D01*
X244300Y809833D01*
X244800Y809750D01*
X245300Y809417D01*
X245633Y808833D01*
X245717Y808167D01*
X245633Y807500D01*
X245300Y806917D01*
X244800Y806583D01*
X244300Y806500D01*
G01X251233Y809417D02*
X250650Y809750D01*
X250150Y809833D01*
X249483Y809667D01*
X248983Y809333D01*
X248650Y808750D01*
X248567Y808167D01*
X248650Y807583D01*
X248983Y807083D01*
X249483Y806667D01*
X250150Y806500D01*
X250733Y806667D01*
X251233Y807000D01*
G01X254083Y809833D02*
Y807500D01*
X254417Y806917D01*
X254917Y806583D01*
X255500Y806500D01*
X256083Y806583D01*
X256583Y806917D01*
X256917Y807500D01*
G01Y806500D02*
Y809833D01*
G01X258600Y806500D02*
Y809833D01*
G01Y808917D02*
X258850Y809333D01*
X259267Y809667D01*
X259850Y809833D01*
X260433Y809667D01*
X260850Y809333D01*
X261100Y808917D01*
Y806500D01*
G01Y808917D02*
X261350Y809333D01*
X261767Y809667D01*
X262350Y809833D01*
X262933Y809667D01*
X263350Y809333D01*
X263600Y808833D01*
Y806500D01*
G01X265450Y808750D02*
X268117D01*
X267867Y809333D01*
X267450Y809667D01*
X266867Y809833D01*
X266283Y809750D01*
X265783Y809500D01*
X265450Y808917D01*
X265283Y808417D01*
Y807917D01*
X265450Y807417D01*
X265867Y806917D01*
X266367Y806583D01*
X266950Y806500D01*
X267533Y806667D01*
X268117Y807167D01*
G01X270883Y806500D02*
Y809833D01*
G01Y809000D02*
X271217Y809417D01*
X271717Y809750D01*
X272383Y809833D01*
X272967Y809750D01*
X273467Y809417D01*
X273717Y808833D01*
Y806500D01*
G01X277900Y811500D02*
Y806500D01*
G01X276733Y809833D02*
X279067D01*
G01X282250Y807083D02*
X282667Y806750D01*
X283250Y806500D01*
X283750D01*
X284250Y806667D01*
X284583Y806917D01*
X284750Y807250D01*
X284667Y807750D01*
X284333Y808000D01*
X282833Y808500D01*
X282500Y809083D01*
X282667Y809500D01*
X283000Y809750D01*
X283500Y809833D01*
X284000Y809750D01*
X284500Y809500D01*
G01X294700Y809833D02*
Y806500D01*
G01Y811167D02*
X294533Y811250D01*
Y811417D01*
X294700Y811500D01*
X294867Y811417D01*
Y811250D01*
X294700Y811167D01*
G01X298883Y806500D02*
Y809833D01*
G01Y809000D02*
X299217Y809417D01*
X299717Y809750D01*
X300383Y809833D01*
X300967Y809750D01*
X301467Y809417D01*
X301717Y808833D01*
Y806500D01*
G01X312833Y809417D02*
X312250Y809750D01*
X311750Y809833D01*
X311083Y809667D01*
X310583Y809333D01*
X310250Y808750D01*
X310167Y808167D01*
X310250Y807583D01*
X310583Y807083D01*
X311083Y806667D01*
X311750Y806500D01*
X312333Y806667D01*
X312833Y807000D01*
G01X317100Y806500D02*
Y811500D01*
G01X324200Y806500D02*
Y809833D01*
G01Y809250D02*
X323867Y809583D01*
X323367Y809750D01*
X322783Y809833D01*
X322200Y809667D01*
X321700Y809333D01*
X321367Y808833D01*
X321200Y808167D01*
X321367Y807500D01*
X321700Y807000D01*
X322200Y806667D01*
X322783Y806500D01*
X323367Y806583D01*
X323867Y806833D01*
X324200Y807167D01*
G01X327050Y807083D02*
X327467Y806750D01*
X328050Y806500D01*
X328550D01*
X329050Y806667D01*
X329383Y806917D01*
X329550Y807250D01*
X329467Y807750D01*
X329133Y808000D01*
X327633Y808500D01*
X327300Y809083D01*
X327467Y809500D01*
X327800Y809750D01*
X328300Y809833D01*
X328800Y809750D01*
X329300Y809500D01*
G01X332650Y807083D02*
X333067Y806750D01*
X333650Y806500D01*
X334150D01*
X334650Y806667D01*
X334983Y806917D01*
X335150Y807250D01*
X335067Y807750D01*
X334733Y808000D01*
X333233Y808500D01*
X332900Y809083D01*
X333067Y809500D01*
X333400Y809750D01*
X333900Y809833D01*
X334400Y809750D01*
X334900Y809500D01*
G01X343517Y810667D02*
X344017Y811167D01*
X344600Y811417D01*
X345267Y811500D01*
X346100Y811333D01*
X346683Y810917D01*
X346850Y810417D01*
X346767Y809917D01*
X346433Y809500D01*
X344767Y808667D01*
X344017Y808083D01*
X343517Y807250D01*
X343350Y806500D01*
X346850D01*
G01X357800D02*
Y809833D01*
G01Y809250D02*
X357467Y809583D01*
X356967Y809750D01*
X356383Y809833D01*
X355800Y809667D01*
X355300Y809333D01*
X354967Y808833D01*
X354800Y808167D01*
X354967Y807500D01*
X355300Y807000D01*
X355800Y806667D01*
X356383Y806500D01*
X356967Y806583D01*
X357467Y806833D01*
X357800Y807167D01*
G01X360483Y806500D02*
Y809833D01*
G01Y809000D02*
X360817Y809417D01*
X361317Y809750D01*
X361983Y809833D01*
X362567Y809750D01*
X363067Y809417D01*
X363317Y808833D01*
Y806500D01*
G01X369000Y811500D02*
Y806500D01*
G01Y807250D02*
X368667Y806833D01*
X368167Y806583D01*
X367583Y806500D01*
X366917Y806667D01*
X366417Y807083D01*
X366083Y807583D01*
X366000Y808167D01*
X366083Y808750D01*
X366417Y809250D01*
X366917Y809667D01*
X367583Y809833D01*
X368167Y809750D01*
X368583Y809583D01*
X369000Y809250D01*
G01X378700Y811500D02*
Y806500D01*
G01X377533Y809833D02*
X379867D01*
G01X382883Y806500D02*
Y811500D01*
G01Y809083D02*
X383300Y809500D01*
X383717Y809750D01*
X384383Y809833D01*
X384883Y809750D01*
X385467Y809417D01*
X385717Y808917D01*
Y806500D01*
G01X388650Y808750D02*
X391317D01*
X391067Y809333D01*
X390650Y809667D01*
X390067Y809833D01*
X389483Y809750D01*
X388983Y809500D01*
X388650Y808917D01*
X388483Y808417D01*
Y807917D01*
X388650Y807417D01*
X389067Y806917D01*
X389567Y806583D01*
X390150Y806500D01*
X390733Y806667D01*
X391317Y807167D01*
G01X401100Y806500D02*
Y811500D01*
G01X408200Y806500D02*
Y809833D01*
G01Y809250D02*
X407867Y809583D01*
X407367Y809750D01*
X406783Y809833D01*
X406200Y809667D01*
X405700Y809333D01*
X405367Y808833D01*
X405200Y808167D01*
X405367Y807500D01*
X405700Y807000D01*
X406200Y806667D01*
X406783Y806500D01*
X407367Y806583D01*
X407867Y806833D01*
X408200Y807167D01*
G01X412300Y811500D02*
Y806500D01*
G01X411133Y809833D02*
X413467D01*
G01X416650Y808750D02*
X419317D01*
X419067Y809333D01*
X418650Y809667D01*
X418067Y809833D01*
X417483Y809750D01*
X416983Y809500D01*
X416650Y808917D01*
X416483Y808417D01*
Y807917D01*
X416650Y807417D01*
X417067Y806917D01*
X417567Y806583D01*
X418150Y806500D01*
X418733Y806667D01*
X419317Y807167D01*
G01X422250Y807083D02*
X422667Y806750D01*
X423250Y806500D01*
X423750D01*
X424250Y806667D01*
X424583Y806917D01*
X424750Y807250D01*
X424667Y807750D01*
X424333Y808000D01*
X422833Y808500D01*
X422500Y809083D01*
X422667Y809500D01*
X423000Y809750D01*
X423500Y809833D01*
X424000Y809750D01*
X424500Y809500D01*
G01X429100Y811500D02*
Y806500D01*
G01X427933Y809833D02*
X430267D01*
G01X438800D02*
X440300Y806500D01*
X441800Y809833D01*
G01X444650Y808750D02*
X447317D01*
X447067Y809333D01*
X446650Y809667D01*
X446067Y809833D01*
X445483Y809750D01*
X444983Y809500D01*
X444650Y808917D01*
X444483Y808417D01*
Y807917D01*
X444650Y807417D01*
X445067Y806917D01*
X445567Y806583D01*
X446150Y806500D01*
X446733Y806667D01*
X447317Y807167D01*
G01X450333Y806500D02*
Y809833D01*
G01Y809167D02*
X450750Y809500D01*
X451167Y809750D01*
X451750Y809833D01*
X452167Y809750D01*
X452667Y809500D01*
G01X455850Y807083D02*
X456267Y806750D01*
X456850Y806500D01*
X457350D01*
X457850Y806667D01*
X458183Y806917D01*
X458350Y807250D01*
X458267Y807750D01*
X457933Y808000D01*
X456433Y808500D01*
X456100Y809083D01*
X456267Y809500D01*
X456600Y809750D01*
X457100Y809833D01*
X457600Y809750D01*
X458100Y809500D01*
G01X462700Y809833D02*
Y806500D01*
G01Y811167D02*
X462533Y811250D01*
Y811417D01*
X462700Y811500D01*
X462867Y811417D01*
Y811250D01*
X462700Y811167D01*
G01X468300Y806500D02*
X467800Y806583D01*
X467300Y806917D01*
X466967Y807500D01*
X466800Y808167D01*
X466967Y808833D01*
X467300Y809417D01*
X467800Y809750D01*
X468300Y809833D01*
X468800Y809750D01*
X469300Y809417D01*
X469633Y808833D01*
X469717Y808167D01*
X469633Y807500D01*
X469300Y806917D01*
X468800Y806583D01*
X468300Y806500D01*
G01X472483D02*
Y809833D01*
G01Y809000D02*
X472817Y809417D01*
X473317Y809750D01*
X473983Y809833D01*
X474567Y809750D01*
X475067Y809417D01*
X475317Y808833D01*
Y806500D01*
G01X485100Y809833D02*
Y806500D01*
G01Y811167D02*
X484933Y811250D01*
Y811417D01*
X485100Y811500D01*
X485267Y811417D01*
Y811250D01*
X485100Y811167D01*
G01X489450Y807083D02*
X489867Y806750D01*
X490450Y806500D01*
X490950D01*
X491450Y806667D01*
X491783Y806917D01*
X491950Y807250D01*
X491867Y807750D01*
X491533Y808000D01*
X490033Y808500D01*
X489700Y809083D01*
X489867Y809500D01*
X490200Y809750D01*
X490700Y809833D01*
X491200Y809750D01*
X491700Y809500D01*
G01X500733Y806500D02*
Y809833D01*
G01Y809167D02*
X501150Y809500D01*
X501567Y809750D01*
X502150Y809833D01*
X502567Y809750D01*
X503067Y809500D01*
G01X506250Y808750D02*
X508917D01*
X508667Y809333D01*
X508250Y809667D01*
X507667Y809833D01*
X507083Y809750D01*
X506583Y809500D01*
X506250Y808917D01*
X506083Y808417D01*
Y807917D01*
X506250Y807417D01*
X506667Y806917D01*
X507167Y806583D01*
X507750Y806500D01*
X508333Y806667D01*
X508917Y807167D01*
G01X514600Y804833D02*
Y809833D01*
G01Y809083D02*
X514183Y809500D01*
X513683Y809750D01*
X513100Y809833D01*
X512600Y809750D01*
X512017Y809333D01*
X511683Y808750D01*
X511600Y808167D01*
X511683Y807583D01*
X512017Y807000D01*
X512600Y806583D01*
X513100Y806500D01*
X513683Y806583D01*
X514183Y806833D01*
X514600Y807250D01*
G01X517283Y809833D02*
Y807500D01*
X517617Y806917D01*
X518117Y806583D01*
X518700Y806500D01*
X519283Y806583D01*
X519783Y806917D01*
X520117Y807500D01*
G01Y806500D02*
Y809833D01*
G01X524300D02*
Y806500D01*
G01Y811167D02*
X524133Y811250D01*
Y811417D01*
X524300Y811500D01*
X524467Y811417D01*
Y811250D01*
X524300Y811167D01*
G01X528733Y806500D02*
Y809833D01*
G01Y809167D02*
X529150Y809500D01*
X529567Y809750D01*
X530150Y809833D01*
X530567Y809750D01*
X531067Y809500D01*
G01X534250Y808750D02*
X536917D01*
X536667Y809333D01*
X536250Y809667D01*
X535667Y809833D01*
X535083Y809750D01*
X534583Y809500D01*
X534250Y808917D01*
X534083Y808417D01*
Y807917D01*
X534250Y807417D01*
X534667Y806917D01*
X535167Y806583D01*
X535750Y806500D01*
X536333Y806667D01*
X536917Y807167D01*
G01X542600Y811500D02*
Y806500D01*
G01Y807250D02*
X542267Y806833D01*
X541767Y806583D01*
X541183Y806500D01*
X540517Y806667D01*
X540017Y807083D01*
X539683Y807583D01*
X539600Y808167D01*
X539683Y808750D01*
X540017Y809250D01*
X540517Y809667D01*
X541183Y809833D01*
X541767Y809750D01*
X542183Y809583D01*
X542600Y809250D01*
G01X546533Y805583D02*
X546867Y806667D01*
G01X112333Y-60000D02*
Y-65000D01*
X115667D01*
G01X119600D02*
X119100Y-64917D01*
X118600Y-64583D01*
X118267Y-64000D01*
X118100Y-63333D01*
X118267Y-62667D01*
X118600Y-62083D01*
X119100Y-61750D01*
X119600Y-61667D01*
X120100Y-61750D01*
X120600Y-62083D01*
X120933Y-62667D01*
X121017Y-63333D01*
X120933Y-64000D01*
X120600Y-64583D01*
X120100Y-64917D01*
X119600Y-65000D01*
G01X124033Y-66250D02*
X124617Y-66583D01*
X125283Y-66667D01*
X125867Y-66583D01*
X126367Y-66167D01*
X126700Y-65583D01*
Y-61667D01*
G01Y-62333D02*
X126367Y-62000D01*
X125867Y-61750D01*
X125283Y-61667D01*
X124617Y-61833D01*
X124200Y-62167D01*
X123867Y-62750D01*
X123700Y-63333D01*
X123783Y-63833D01*
X124117Y-64417D01*
X124617Y-64833D01*
X125283Y-65000D01*
X125783Y-64917D01*
X126367Y-64583D01*
X126700Y-64250D01*
G01X130800Y-65000D02*
X130300Y-64917D01*
X129800Y-64583D01*
X129467Y-64000D01*
X129300Y-63333D01*
X129467Y-62667D01*
X129800Y-62083D01*
X130300Y-61750D01*
X130800Y-61667D01*
X131300Y-61750D01*
X131800Y-62083D01*
X132133Y-62667D01*
X132217Y-63333D01*
X132133Y-64000D01*
X131800Y-64583D01*
X131300Y-64917D01*
X130800Y-65000D01*
G01X114000Y-36000D02*
Y-41000D01*
G01X112833Y-37667D02*
X115167D01*
G01X118183Y-41000D02*
Y-36000D01*
G01Y-38417D02*
X118600Y-38000D01*
X119017Y-37750D01*
X119683Y-37667D01*
X120183Y-37750D01*
X120767Y-38083D01*
X121017Y-38583D01*
Y-41000D01*
G01X125200Y-37667D02*
Y-41000D01*
G01Y-36333D02*
X125033Y-36250D01*
Y-36083D01*
X125200Y-36000D01*
X125367Y-36083D01*
Y-36250D01*
X125200Y-36333D01*
G01X132133Y-38083D02*
X131550Y-37750D01*
X131050Y-37667D01*
X130383Y-37833D01*
X129883Y-38167D01*
X129550Y-38750D01*
X129467Y-39333D01*
X129550Y-39917D01*
X129883Y-40417D01*
X130383Y-40833D01*
X131050Y-41000D01*
X131633Y-40833D01*
X132133Y-40500D01*
G01X134983Y-41000D02*
Y-36000D01*
G01X137650Y-37667D02*
X134983Y-39583D01*
G01X136067Y-38833D02*
X137817Y-41000D01*
G01X140583D02*
Y-37667D01*
G01Y-38500D02*
X140917Y-38083D01*
X141417Y-37750D01*
X142083Y-37667D01*
X142667Y-37750D01*
X143167Y-38083D01*
X143417Y-38667D01*
Y-41000D01*
G01X146350Y-38750D02*
X149017D01*
X148767Y-38167D01*
X148350Y-37833D01*
X147767Y-37667D01*
X147183Y-37750D01*
X146683Y-38000D01*
X146350Y-38583D01*
X146183Y-39083D01*
Y-39583D01*
X146350Y-40083D01*
X146767Y-40583D01*
X147267Y-40917D01*
X147850Y-41000D01*
X148433Y-40833D01*
X149017Y-40333D01*
G01X151950Y-40417D02*
X152367Y-40750D01*
X152950Y-41000D01*
X153450D01*
X153950Y-40833D01*
X154283Y-40583D01*
X154450Y-40250D01*
X154367Y-39750D01*
X154033Y-39500D01*
X152533Y-39000D01*
X152200Y-38417D01*
X152367Y-38000D01*
X152700Y-37750D01*
X153200Y-37667D01*
X153700Y-37750D01*
X154200Y-38000D01*
G01X157550Y-40417D02*
X157967Y-40750D01*
X158550Y-41000D01*
X159050D01*
X159550Y-40833D01*
X159883Y-40583D01*
X160050Y-40250D01*
X159967Y-39750D01*
X159633Y-39500D01*
X158133Y-39000D01*
X157800Y-38417D01*
X157967Y-38000D01*
X158300Y-37750D01*
X158800Y-37667D01*
X159300Y-37750D01*
X159800Y-38000D01*
G01X114000Y-15000D02*
Y-20000D01*
G01X112833Y-16667D02*
X115167D01*
G01X118183Y-20000D02*
Y-15000D01*
G01Y-17417D02*
X118600Y-17000D01*
X119017Y-16750D01*
X119683Y-16667D01*
X120183Y-16750D01*
X120767Y-17083D01*
X121017Y-17583D01*
Y-20000D01*
G01X125200Y-16667D02*
Y-20000D01*
G01Y-15333D02*
X125033Y-15250D01*
Y-15083D01*
X125200Y-15000D01*
X125367Y-15083D01*
Y-15250D01*
X125200Y-15333D01*
G01X132133Y-17083D02*
X131550Y-16750D01*
X131050Y-16667D01*
X130383Y-16833D01*
X129883Y-17167D01*
X129550Y-17750D01*
X129467Y-18333D01*
X129550Y-18917D01*
X129883Y-19417D01*
X130383Y-19833D01*
X131050Y-20000D01*
X131633Y-19833D01*
X132133Y-19500D01*
G01X134983Y-20000D02*
Y-15000D01*
G01X137650Y-16667D02*
X134983Y-18583D01*
G01X136067Y-17833D02*
X137817Y-20000D01*
G01X140583D02*
Y-16667D01*
G01Y-17500D02*
X140917Y-17083D01*
X141417Y-16750D01*
X142083Y-16667D01*
X142667Y-16750D01*
X143167Y-17083D01*
X143417Y-17667D01*
Y-20000D01*
G01X146350Y-17750D02*
X149017D01*
X148767Y-17167D01*
X148350Y-16833D01*
X147767Y-16667D01*
X147183Y-16750D01*
X146683Y-17000D01*
X146350Y-17583D01*
X146183Y-18083D01*
Y-18583D01*
X146350Y-19083D01*
X146767Y-19583D01*
X147267Y-19917D01*
X147850Y-20000D01*
X148433Y-19833D01*
X149017Y-19333D01*
G01X151950Y-19417D02*
X152367Y-19750D01*
X152950Y-20000D01*
X153450D01*
X153950Y-19833D01*
X154283Y-19583D01*
X154450Y-19250D01*
X154367Y-18750D01*
X154033Y-18500D01*
X152533Y-18000D01*
X152200Y-17417D01*
X152367Y-17000D01*
X152700Y-16750D01*
X153200Y-16667D01*
X153700Y-16750D01*
X154200Y-17000D01*
G01X157550Y-19417D02*
X157967Y-19750D01*
X158550Y-20000D01*
X159050D01*
X159550Y-19833D01*
X159883Y-19583D01*
X160050Y-19250D01*
X159967Y-18750D01*
X159633Y-18500D01*
X158133Y-18000D01*
X157800Y-17417D01*
X157967Y-17000D01*
X158300Y-16750D01*
X158800Y-16667D01*
X159300Y-16750D01*
X159800Y-17000D01*
G01X103500Y679000D02*
Y-69500D01*
G01Y-54500D02*
X694500D01*
G01X112483Y24700D02*
Y29700D01*
X114650Y25533D01*
X116817Y29700D01*
Y24700D01*
G01X121750D02*
Y28033D01*
G01Y27450D02*
X121417Y27783D01*
X120917Y27950D01*
X120333Y28033D01*
X119750Y27867D01*
X119250Y27533D01*
X118917Y27033D01*
X118750Y26367D01*
X118917Y25700D01*
X119250Y25200D01*
X119750Y24867D01*
X120333Y24700D01*
X120917Y24783D01*
X121417Y25033D01*
X121750Y25367D01*
G01X124683Y24700D02*
Y28033D01*
G01Y27367D02*
X125100Y27700D01*
X125517Y27950D01*
X126100Y28033D01*
X126517Y27950D01*
X127017Y27700D01*
G01X130033Y24700D02*
Y29700D01*
G01X132700Y28033D02*
X130033Y26117D01*
G01X131117Y26867D02*
X132867Y24700D01*
G01X137467Y23033D02*
X138300Y23867D01*
X138717Y24700D01*
Y28033D01*
X138300Y28867D01*
X137467Y29700D01*
G01X113070Y36130D02*
X114737D01*
Y34630D01*
X114237Y34130D01*
X113653Y33797D01*
X112820Y33630D01*
X111987Y33797D01*
X111403Y34130D01*
X110903Y34630D01*
X110570Y35213D01*
X110403Y35880D01*
Y36463D01*
X110570Y36963D01*
X110903Y37547D01*
X111403Y38047D01*
X111903Y38380D01*
X112570Y38630D01*
X113153D01*
X113820Y38463D01*
X114320Y38130D01*
G01X118170Y33630D02*
X117670Y33713D01*
X117170Y34047D01*
X116837Y34630D01*
X116670Y35297D01*
X116837Y35963D01*
X117170Y36547D01*
X117670Y36880D01*
X118170Y36963D01*
X118670Y36880D01*
X119170Y36547D01*
X119503Y35963D01*
X119587Y35297D01*
X119503Y34630D01*
X119170Y34047D01*
X118670Y33713D01*
X118170Y33630D01*
G01X123770D02*
Y38630D01*
G01X130870D02*
Y33630D01*
G01Y34380D02*
X130537Y33963D01*
X130037Y33713D01*
X129453Y33630D01*
X128787Y33797D01*
X128287Y34213D01*
X127953Y34713D01*
X127870Y35297D01*
X127953Y35880D01*
X128287Y36380D01*
X128787Y36797D01*
X129453Y36963D01*
X130037Y36880D01*
X130453Y36713D01*
X130870Y36380D01*
G01X133720Y35880D02*
X136387D01*
X136137Y36463D01*
X135720Y36797D01*
X135137Y36963D01*
X134553Y36880D01*
X134053Y36630D01*
X133720Y36047D01*
X133553Y35547D01*
Y35047D01*
X133720Y34547D01*
X134137Y34047D01*
X134637Y33713D01*
X135220Y33630D01*
X135803Y33797D01*
X136387Y34297D01*
G01X139153Y33630D02*
Y36963D01*
G01Y36130D02*
X139487Y36547D01*
X139987Y36880D01*
X140653Y36963D01*
X141237Y36880D01*
X141737Y36547D01*
X141987Y35963D01*
Y33630D01*
G01X151270D02*
Y37880D01*
X151437Y38297D01*
X151770Y38547D01*
X152270Y38630D01*
X152770Y38463D01*
X153020Y38047D01*
G01X152020Y36630D02*
X150353D01*
G01X157370Y36963D02*
Y33630D01*
G01Y38297D02*
X157203Y38380D01*
Y38547D01*
X157370Y38630D01*
X157537Y38547D01*
Y38380D01*
X157370Y38297D01*
G01X161553Y33630D02*
Y36963D01*
G01Y36130D02*
X161887Y36547D01*
X162387Y36880D01*
X163053Y36963D01*
X163637Y36880D01*
X164137Y36547D01*
X164387Y35963D01*
Y33630D01*
G01X167403Y32380D02*
X167987Y32047D01*
X168653Y31963D01*
X169237Y32047D01*
X169737Y32463D01*
X170070Y33047D01*
Y36963D01*
G01Y36297D02*
X169737Y36630D01*
X169237Y36880D01*
X168653Y36963D01*
X167987Y36797D01*
X167570Y36463D01*
X167237Y35880D01*
X167070Y35297D01*
X167153Y34797D01*
X167487Y34213D01*
X167987Y33797D01*
X168653Y33630D01*
X169153Y33713D01*
X169737Y34047D01*
X170070Y34380D01*
G01X172920Y35880D02*
X175587D01*
X175337Y36463D01*
X174920Y36797D01*
X174337Y36963D01*
X173753Y36880D01*
X173253Y36630D01*
X172920Y36047D01*
X172753Y35547D01*
Y35047D01*
X172920Y34547D01*
X173337Y34047D01*
X173837Y33713D01*
X174420Y33630D01*
X175003Y33797D01*
X175587Y34297D01*
G01X178603Y33630D02*
Y36963D01*
G01Y36297D02*
X179020Y36630D01*
X179437Y36880D01*
X180020Y36963D01*
X180437Y36880D01*
X180937Y36630D01*
G01X189303Y33630D02*
Y38630D01*
X191303D01*
X191970Y38380D01*
X192470Y37797D01*
X192637Y37130D01*
X192470Y36463D01*
X192053Y35963D01*
X191303Y35713D01*
X189303D01*
G01X194487Y33630D02*
X196570Y38630D01*
X198653Y33630D01*
G01X197903Y35380D02*
X195237D01*
G01X200337Y33630D02*
Y38630D01*
X202003D01*
X202670Y38380D01*
X203170Y38047D01*
X203587Y37547D01*
X203920Y36963D01*
X204003Y36130D01*
X203920Y35297D01*
X203587Y34713D01*
X203170Y34213D01*
X202670Y33880D01*
X202003Y33630D01*
X200337D01*
G01X211870Y33463D02*
X214870Y38630D01*
G01X217387Y33630D02*
Y38630D01*
X220553D01*
G01X219387Y36213D02*
X217387D01*
G01X224570Y36963D02*
Y33630D01*
G01Y38297D02*
X224403Y38380D01*
Y38547D01*
X224570Y38630D01*
X224737Y38547D01*
Y38380D01*
X224570Y38297D01*
G01X231670Y38630D02*
Y33630D01*
G01Y34380D02*
X231337Y33963D01*
X230837Y33713D01*
X230253Y33630D01*
X229587Y33797D01*
X229087Y34213D01*
X228753Y34713D01*
X228670Y35297D01*
X228753Y35880D01*
X229087Y36380D01*
X229587Y36797D01*
X230253Y36963D01*
X230837Y36880D01*
X231253Y36713D01*
X231670Y36380D01*
G01X234353Y36963D02*
Y34630D01*
X234687Y34047D01*
X235187Y33713D01*
X235770Y33630D01*
X236353Y33713D01*
X236853Y34047D01*
X237187Y34630D01*
G01Y33630D02*
Y36963D01*
G01X242703Y36547D02*
X242120Y36880D01*
X241620Y36963D01*
X240953Y36797D01*
X240453Y36463D01*
X240120Y35880D01*
X240037Y35297D01*
X240120Y34713D01*
X240453Y34213D01*
X240953Y33797D01*
X241620Y33630D01*
X242203Y33797D01*
X242703Y34130D01*
G01X246970Y36963D02*
Y33630D01*
G01Y38297D02*
X246803Y38380D01*
Y38547D01*
X246970Y38630D01*
X247137Y38547D01*
Y38380D01*
X246970Y38297D01*
G01X254070Y33630D02*
Y36963D01*
G01Y36380D02*
X253737Y36713D01*
X253237Y36880D01*
X252653Y36963D01*
X252070Y36797D01*
X251570Y36463D01*
X251237Y35963D01*
X251070Y35297D01*
X251237Y34630D01*
X251570Y34130D01*
X252070Y33797D01*
X252653Y33630D01*
X253237Y33713D01*
X253737Y33963D01*
X254070Y34297D01*
G01X258170Y33630D02*
Y38630D01*
G01X112743Y42673D02*
X111910Y43507D01*
X111493Y44340D01*
Y47673D01*
X111910Y48507D01*
X112743Y49340D01*
G01X116260Y44340D02*
Y47673D01*
G01Y46757D02*
X116510Y47173D01*
X116927Y47507D01*
X117510Y47673D01*
X118093Y47507D01*
X118510Y47173D01*
X118760Y46757D01*
Y44340D01*
G01Y46757D02*
X119010Y47173D01*
X119427Y47507D01*
X120010Y47673D01*
X120593Y47507D01*
X121010Y47173D01*
X121260Y46673D01*
Y44340D01*
G01X123110Y46590D02*
X125777D01*
X125527Y47173D01*
X125110Y47507D01*
X124527Y47673D01*
X123943Y47590D01*
X123443Y47340D01*
X123110Y46757D01*
X122943Y46257D01*
Y45757D01*
X123110Y45257D01*
X123527Y44757D01*
X124027Y44423D01*
X124610Y44340D01*
X125193Y44507D01*
X125777Y45007D01*
G01X131460Y44340D02*
Y47673D01*
G01Y47090D02*
X131127Y47423D01*
X130627Y47590D01*
X130043Y47673D01*
X129460Y47507D01*
X128960Y47173D01*
X128627Y46673D01*
X128460Y46007D01*
X128627Y45340D01*
X128960Y44840D01*
X129460Y44507D01*
X130043Y44340D01*
X130627Y44423D01*
X131127Y44673D01*
X131460Y45007D01*
G01X134310Y44923D02*
X134727Y44590D01*
X135310Y44340D01*
X135810D01*
X136310Y44507D01*
X136643Y44757D01*
X136810Y45090D01*
X136727Y45590D01*
X136393Y45840D01*
X134893Y46340D01*
X134560Y46923D01*
X134727Y47340D01*
X135060Y47590D01*
X135560Y47673D01*
X136060Y47590D01*
X136560Y47340D01*
G01X139743Y47673D02*
Y45340D01*
X140077Y44757D01*
X140577Y44423D01*
X141160Y44340D01*
X141743Y44423D01*
X142243Y44757D01*
X142577Y45340D01*
G01Y44340D02*
Y47673D01*
G01X145593Y44340D02*
Y47673D01*
G01Y47007D02*
X146010Y47340D01*
X146427Y47590D01*
X147010Y47673D01*
X147427Y47590D01*
X147927Y47340D01*
G01X151110Y46590D02*
X153777D01*
X153527Y47173D01*
X153110Y47507D01*
X152527Y47673D01*
X151943Y47590D01*
X151443Y47340D01*
X151110Y46757D01*
X150943Y46257D01*
Y45757D01*
X151110Y45257D01*
X151527Y44757D01*
X152027Y44423D01*
X152610Y44340D01*
X153193Y44507D01*
X153777Y45007D01*
G01X163560Y49340D02*
Y44340D01*
G01X162393Y47673D02*
X164727D01*
G01X169160Y44340D02*
X168660Y44423D01*
X168160Y44757D01*
X167827Y45340D01*
X167660Y46007D01*
X167827Y46673D01*
X168160Y47257D01*
X168660Y47590D01*
X169160Y47673D01*
X169660Y47590D01*
X170160Y47257D01*
X170493Y46673D01*
X170577Y46007D01*
X170493Y45340D01*
X170160Y44757D01*
X169660Y44423D01*
X169160Y44340D01*
G01X173260Y42673D02*
Y47673D01*
G01Y46923D02*
X173677Y47340D01*
X174093Y47590D01*
X174760Y47673D01*
X175343Y47590D01*
X175927Y47173D01*
X176177Y46590D01*
X176260Y46007D01*
X176177Y45423D01*
X175927Y44840D01*
X175427Y44507D01*
X174760Y44340D01*
X174177Y44423D01*
X173593Y44673D01*
X173260Y45007D01*
G01X184710Y44923D02*
X185127Y44590D01*
X185710Y44340D01*
X186210D01*
X186710Y44507D01*
X187043Y44757D01*
X187210Y45090D01*
X187127Y45590D01*
X186793Y45840D01*
X185293Y46340D01*
X184960Y46923D01*
X185127Y47340D01*
X185460Y47590D01*
X185960Y47673D01*
X186460Y47590D01*
X186960Y47340D01*
G01X191560Y47673D02*
Y44340D01*
G01Y49007D02*
X191393Y49090D01*
Y49257D01*
X191560Y49340D01*
X191727Y49257D01*
Y49090D01*
X191560Y49007D01*
G01X195910Y47673D02*
X198410D01*
X195910Y44340D01*
X198410D01*
G01X201510Y46590D02*
X204177D01*
X203927Y47173D01*
X203510Y47507D01*
X202927Y47673D01*
X202343Y47590D01*
X201843Y47340D01*
X201510Y46757D01*
X201343Y46257D01*
Y45757D01*
X201510Y45257D01*
X201927Y44757D01*
X202427Y44423D01*
X203010Y44340D01*
X203593Y44507D01*
X204177Y45007D01*
G01X213960Y44340D02*
X213460Y44423D01*
X212960Y44757D01*
X212627Y45340D01*
X212460Y46007D01*
X212627Y46673D01*
X212960Y47257D01*
X213460Y47590D01*
X213960Y47673D01*
X214460Y47590D01*
X214960Y47257D01*
X215293Y46673D01*
X215377Y46007D01*
X215293Y45340D01*
X214960Y44757D01*
X214460Y44423D01*
X213960Y44340D01*
G01X219060D02*
Y48590D01*
X219227Y49007D01*
X219560Y49257D01*
X220060Y49340D01*
X220560Y49173D01*
X220810Y48757D01*
G01X219810Y47340D02*
X218143D01*
G01X229093Y44340D02*
Y49340D01*
X231093D01*
X231760Y49090D01*
X232260Y48507D01*
X232427Y47840D01*
X232260Y47173D01*
X231843Y46673D01*
X231093Y46423D01*
X229093D01*
G01X234277Y44340D02*
X236360Y49340D01*
X238443Y44340D01*
G01X237693Y46090D02*
X235027D01*
G01X240127Y44340D02*
Y49340D01*
X241793D01*
X242460Y49090D01*
X242960Y48757D01*
X243377Y48257D01*
X243710Y47673D01*
X243793Y46840D01*
X243710Y46007D01*
X243377Y45423D01*
X242960Y44923D01*
X242460Y44590D01*
X241793Y44340D01*
X240127D01*
G01X251660Y44173D02*
X254660Y49340D01*
G01X119183Y-2167D02*
X118350Y-1333D01*
X117933Y-500D01*
Y2833D01*
X118350Y3667D01*
X119183Y4500D01*
G01X123450Y167D02*
X124117Y-250D01*
X124867Y-500D01*
X125533D01*
X126200Y-250D01*
X126700Y167D01*
X126950Y750D01*
X126783Y1333D01*
X126367Y1833D01*
X125617Y2167D01*
X124617Y2333D01*
X124033Y2667D01*
X123783Y3250D01*
X123950Y3833D01*
X124367Y4250D01*
X124950Y4500D01*
X125533D01*
X126117Y4333D01*
X126617Y3917D01*
G01X128633Y-500D02*
Y4500D01*
X130800Y333D01*
X132967Y4500D01*
Y-500D01*
G01X134567D02*
Y4500D01*
X136233D01*
X136900Y4250D01*
X137400Y3917D01*
X137817Y3417D01*
X138150Y2833D01*
X138233Y2000D01*
X138150Y1167D01*
X137817Y583D01*
X137400Y83D01*
X136900Y-250D01*
X136233Y-500D01*
X134567D01*
G01X142417Y-2167D02*
X143250Y-1333D01*
X143667Y-500D01*
Y2833D01*
X143250Y3667D01*
X142417Y4500D01*
G01X112250Y12167D02*
X112917Y11750D01*
X113667Y11500D01*
X114333D01*
X115000Y11750D01*
X115500Y12167D01*
X115750Y12750D01*
X115583Y13333D01*
X115167Y13833D01*
X114417Y14167D01*
X113417Y14333D01*
X112833Y14667D01*
X112583Y15250D01*
X112750Y15833D01*
X113167Y16250D01*
X113750Y16500D01*
X114333D01*
X114917Y16333D01*
X115417Y15917D01*
G01X119600Y11500D02*
X119100Y11583D01*
X118600Y11917D01*
X118267Y12500D01*
X118100Y13167D01*
X118267Y13833D01*
X118600Y14417D01*
X119100Y14750D01*
X119600Y14833D01*
X120100Y14750D01*
X120600Y14417D01*
X120933Y13833D01*
X121017Y13167D01*
X120933Y12500D01*
X120600Y11917D01*
X120100Y11583D01*
X119600Y11500D01*
G01X125200D02*
Y16500D01*
G01X132300D02*
Y11500D01*
G01Y12250D02*
X131967Y11833D01*
X131467Y11583D01*
X130883Y11500D01*
X130217Y11667D01*
X129717Y12083D01*
X129383Y12583D01*
X129300Y13167D01*
X129383Y13750D01*
X129717Y14250D01*
X130217Y14667D01*
X130883Y14833D01*
X131467Y14750D01*
X131883Y14583D01*
X132300Y14250D01*
G01X135150Y13750D02*
X137817D01*
X137567Y14333D01*
X137150Y14667D01*
X136567Y14833D01*
X135983Y14750D01*
X135483Y14500D01*
X135150Y13917D01*
X134983Y13417D01*
Y12917D01*
X135150Y12417D01*
X135567Y11917D01*
X136067Y11583D01*
X136650Y11500D01*
X137233Y11667D01*
X137817Y12167D01*
G01X140833Y11500D02*
Y14833D01*
G01Y14167D02*
X141250Y14500D01*
X141667Y14750D01*
X142250Y14833D01*
X142667Y14750D01*
X143167Y14500D01*
G01X150700Y11500D02*
Y14833D01*
G01Y13917D02*
X150950Y14333D01*
X151367Y14667D01*
X151950Y14833D01*
X152533Y14667D01*
X152950Y14333D01*
X153200Y13917D01*
Y11500D01*
G01Y13917D02*
X153450Y14333D01*
X153867Y14667D01*
X154450Y14833D01*
X155033Y14667D01*
X155450Y14333D01*
X155700Y13833D01*
Y11500D01*
G01X160300D02*
Y14833D01*
G01Y14250D02*
X159967Y14583D01*
X159467Y14750D01*
X158883Y14833D01*
X158300Y14667D01*
X157800Y14333D01*
X157467Y13833D01*
X157300Y13167D01*
X157467Y12500D01*
X157800Y12000D01*
X158300Y11667D01*
X158883Y11500D01*
X159467Y11583D01*
X159967Y11833D01*
X160300Y12167D01*
G01X163150Y12083D02*
X163567Y11750D01*
X164150Y11500D01*
X164650D01*
X165150Y11667D01*
X165483Y11917D01*
X165650Y12250D01*
X165567Y12750D01*
X165233Y13000D01*
X163733Y13500D01*
X163400Y14083D01*
X163567Y14500D01*
X163900Y14750D01*
X164400Y14833D01*
X164900Y14750D01*
X165400Y14500D01*
G01X168583Y11500D02*
Y16500D01*
G01X171250Y14833D02*
X168583Y12917D01*
G01X169667Y13667D02*
X171417Y11500D01*
G01X182700Y16500D02*
Y11500D01*
G01Y12250D02*
X182367Y11833D01*
X181867Y11583D01*
X181283Y11500D01*
X180617Y11667D01*
X180117Y12083D01*
X179783Y12583D01*
X179700Y13167D01*
X179783Y13750D01*
X180117Y14250D01*
X180617Y14667D01*
X181283Y14833D01*
X181867Y14750D01*
X182283Y14583D01*
X182700Y14250D01*
G01X185550Y13750D02*
X188217D01*
X187967Y14333D01*
X187550Y14667D01*
X186967Y14833D01*
X186383Y14750D01*
X185883Y14500D01*
X185550Y13917D01*
X185383Y13417D01*
Y12917D01*
X185550Y12417D01*
X185967Y11917D01*
X186467Y11583D01*
X187050Y11500D01*
X187633Y11667D01*
X188217Y12167D01*
G01X191900Y11500D02*
Y15750D01*
X192067Y16167D01*
X192400Y16417D01*
X192900Y16500D01*
X193400Y16333D01*
X193650Y15917D01*
G01X192650Y14500D02*
X190983D01*
G01X198000Y14833D02*
Y11500D01*
G01Y16167D02*
X197833Y16250D01*
Y16417D01*
X198000Y16500D01*
X198167Y16417D01*
Y16250D01*
X198000Y16167D01*
G01X202183Y11500D02*
Y14833D01*
G01Y14000D02*
X202517Y14417D01*
X203017Y14750D01*
X203683Y14833D01*
X204267Y14750D01*
X204767Y14417D01*
X205017Y13833D01*
Y11500D01*
G01X207950Y13750D02*
X210617D01*
X210367Y14333D01*
X209950Y14667D01*
X209367Y14833D01*
X208783Y14750D01*
X208283Y14500D01*
X207950Y13917D01*
X207783Y13417D01*
Y12917D01*
X207950Y12417D01*
X208367Y11917D01*
X208867Y11583D01*
X209450Y11500D01*
X210033Y11667D01*
X210617Y12167D01*
G01X218900Y9833D02*
Y14833D01*
G01Y14083D02*
X219317Y14500D01*
X219733Y14750D01*
X220400Y14833D01*
X220983Y14750D01*
X221567Y14333D01*
X221817Y13750D01*
X221900Y13167D01*
X221817Y12583D01*
X221567Y12000D01*
X221067Y11667D01*
X220400Y11500D01*
X219817Y11583D01*
X219233Y11833D01*
X218900Y12167D01*
G01X227500Y11500D02*
Y14833D01*
G01Y14250D02*
X227167Y14583D01*
X226667Y14750D01*
X226083Y14833D01*
X225500Y14667D01*
X225000Y14333D01*
X224667Y13833D01*
X224500Y13167D01*
X224667Y12500D01*
X225000Y12000D01*
X225500Y11667D01*
X226083Y11500D01*
X226667Y11583D01*
X227167Y11833D01*
X227500Y12167D01*
G01X233100Y16500D02*
Y11500D01*
G01Y12250D02*
X232767Y11833D01*
X232267Y11583D01*
X231683Y11500D01*
X231017Y11667D01*
X230517Y12083D01*
X230183Y12583D01*
X230100Y13167D01*
X230183Y13750D01*
X230517Y14250D01*
X231017Y14667D01*
X231683Y14833D01*
X232267Y14750D01*
X232683Y14583D01*
X233100Y14250D01*
G01X112333Y51500D02*
Y56500D01*
X114333D01*
X115000Y56250D01*
X115500Y55667D01*
X115667Y55000D01*
X115500Y54333D01*
X115083Y53833D01*
X114333Y53583D01*
X112333D01*
G01X117517Y51500D02*
X119600Y56500D01*
X121683Y51500D01*
G01X120933Y53250D02*
X118267D01*
G01X123367Y51500D02*
Y56500D01*
X125033D01*
X125700Y56250D01*
X126200Y55917D01*
X126617Y55417D01*
X126950Y54833D01*
X127033Y54000D01*
X126950Y53167D01*
X126617Y52583D01*
X126200Y52083D01*
X125700Y51750D01*
X125033Y51500D01*
X123367D01*
G01X135150Y52083D02*
X135567Y51750D01*
X136150Y51500D01*
X136650D01*
X137150Y51667D01*
X137483Y51917D01*
X137650Y52250D01*
X137567Y52750D01*
X137233Y53000D01*
X135733Y53500D01*
X135400Y54083D01*
X135567Y54500D01*
X135900Y54750D01*
X136400Y54833D01*
X136900Y54750D01*
X137400Y54500D01*
G01X142000Y54833D02*
Y51500D01*
G01Y56167D02*
X141833Y56250D01*
Y56417D01*
X142000Y56500D01*
X142167Y56417D01*
Y56250D01*
X142000Y56167D01*
G01X146350Y54833D02*
X148850D01*
X146350Y51500D01*
X148850D01*
G01X151950Y53750D02*
X154617D01*
X154367Y54333D01*
X153950Y54667D01*
X153367Y54833D01*
X152783Y54750D01*
X152283Y54500D01*
X151950Y53917D01*
X151783Y53417D01*
Y52917D01*
X151950Y52417D01*
X152367Y51917D01*
X152867Y51583D01*
X153450Y51500D01*
X154033Y51667D01*
X154617Y52167D01*
G01X103500Y-9500D02*
X694500D01*
G01X114000Y85000D02*
Y80000D01*
G01X112083Y85000D02*
X115917D01*
G01X118433Y80000D02*
Y83333D01*
G01Y82667D02*
X118850Y83000D01*
X119267Y83250D01*
X119850Y83333D01*
X120267Y83250D01*
X120767Y83000D01*
G01X126700Y80000D02*
Y83333D01*
G01Y82750D02*
X126367Y83083D01*
X125867Y83250D01*
X125283Y83333D01*
X124700Y83167D01*
X124200Y82833D01*
X123867Y82333D01*
X123700Y81667D01*
X123867Y81000D01*
X124200Y80500D01*
X124700Y80167D01*
X125283Y80000D01*
X125867Y80083D01*
X126367Y80333D01*
X126700Y80667D01*
G01X132133Y82917D02*
X131550Y83250D01*
X131050Y83333D01*
X130383Y83167D01*
X129883Y82833D01*
X129550Y82250D01*
X129467Y81667D01*
X129550Y81083D01*
X129883Y80583D01*
X130383Y80167D01*
X131050Y80000D01*
X131633Y80167D01*
X132133Y80500D01*
G01X135150Y82250D02*
X137817D01*
X137567Y82833D01*
X137150Y83167D01*
X136567Y83333D01*
X135983Y83250D01*
X135483Y83000D01*
X135150Y82417D01*
X134983Y81917D01*
Y81417D01*
X135150Y80917D01*
X135567Y80417D01*
X136067Y80083D01*
X136650Y80000D01*
X137233Y80167D01*
X137817Y80667D01*
G01X145517Y83333D02*
X146517Y80000D01*
X147600Y83333D01*
X148683Y80000D01*
X149683Y83333D01*
G01X153200D02*
Y80000D01*
G01Y84667D02*
X153033Y84750D01*
Y84917D01*
X153200Y85000D01*
X153367Y84917D01*
Y84750D01*
X153200Y84667D01*
G01X160300Y85000D02*
Y80000D01*
G01Y80750D02*
X159967Y80333D01*
X159467Y80083D01*
X158883Y80000D01*
X158217Y80167D01*
X157717Y80583D01*
X157383Y81083D01*
X157300Y81667D01*
X157383Y82250D01*
X157717Y82750D01*
X158217Y83167D01*
X158883Y83333D01*
X159467Y83250D01*
X159883Y83083D01*
X160300Y82750D01*
G01X164400Y85000D02*
Y80000D01*
G01X163233Y83333D02*
X165567D01*
G01X168583Y80000D02*
Y85000D01*
G01Y82583D02*
X169000Y83000D01*
X169417Y83250D01*
X170083Y83333D01*
X170583Y83250D01*
X171167Y82917D01*
X171417Y82417D01*
Y80000D01*
G01X112333Y111500D02*
Y116500D01*
X114417D01*
X115083Y116250D01*
X115500Y115917D01*
X115667Y115250D01*
X115500Y114583D01*
X115000Y114167D01*
X114417Y113917D01*
X112333D01*
G01X114417D02*
X115667Y111500D01*
G01X118350Y113750D02*
X121017D01*
X120767Y114333D01*
X120350Y114667D01*
X119767Y114833D01*
X119183Y114750D01*
X118683Y114500D01*
X118350Y113917D01*
X118183Y113417D01*
Y112917D01*
X118350Y112417D01*
X118767Y111917D01*
X119267Y111583D01*
X119850Y111500D01*
X120433Y111667D01*
X121017Y112167D01*
G01X125200Y111500D02*
Y116500D01*
G01X132300Y111500D02*
Y114833D01*
G01Y114250D02*
X131967Y114583D01*
X131467Y114750D01*
X130883Y114833D01*
X130300Y114667D01*
X129800Y114333D01*
X129467Y113833D01*
X129300Y113167D01*
X129467Y112500D01*
X129800Y112000D01*
X130300Y111667D01*
X130883Y111500D01*
X131467Y111583D01*
X131967Y111833D01*
X132300Y112167D01*
G01X136400Y116500D02*
Y111500D01*
G01X135233Y114833D02*
X137567D01*
G01X142000D02*
Y111500D01*
G01Y116167D02*
X141833Y116250D01*
Y116417D01*
X142000Y116500D01*
X142167Y116417D01*
Y116250D01*
X142000Y116167D01*
G01X146100Y114833D02*
X147600Y111500D01*
X149100Y114833D01*
G01X151950Y113750D02*
X154617D01*
X154367Y114333D01*
X153950Y114667D01*
X153367Y114833D01*
X152783Y114750D01*
X152283Y114500D01*
X151950Y113917D01*
X151783Y113417D01*
Y112917D01*
X151950Y112417D01*
X152367Y111917D01*
X152867Y111583D01*
X153450Y111500D01*
X154033Y111667D01*
X154617Y112167D01*
G01X162900Y109833D02*
Y114833D01*
G01Y114083D02*
X163317Y114500D01*
X163733Y114750D01*
X164400Y114833D01*
X164983Y114750D01*
X165567Y114333D01*
X165817Y113750D01*
X165900Y113167D01*
X165817Y112583D01*
X165567Y112000D01*
X165067Y111667D01*
X164400Y111500D01*
X163817Y111583D01*
X163233Y111833D01*
X162900Y112167D01*
G01X170000Y111500D02*
X169500Y111583D01*
X169000Y111917D01*
X168667Y112500D01*
X168500Y113167D01*
X168667Y113833D01*
X169000Y114417D01*
X169500Y114750D01*
X170000Y114833D01*
X170500Y114750D01*
X171000Y114417D01*
X171333Y113833D01*
X171417Y113167D01*
X171333Y112500D01*
X171000Y111917D01*
X170500Y111583D01*
X170000Y111500D01*
G01X174350Y112083D02*
X174767Y111750D01*
X175350Y111500D01*
X175850D01*
X176350Y111667D01*
X176683Y111917D01*
X176850Y112250D01*
X176767Y112750D01*
X176433Y113000D01*
X174933Y113500D01*
X174600Y114083D01*
X174767Y114500D01*
X175100Y114750D01*
X175600Y114833D01*
X176100Y114750D01*
X176600Y114500D01*
G01X181200Y114833D02*
Y111500D01*
G01Y116167D02*
X181033Y116250D01*
Y116417D01*
X181200Y116500D01*
X181367Y116417D01*
Y116250D01*
X181200Y116167D01*
G01X186800Y116500D02*
Y111500D01*
G01X185633Y114833D02*
X187967D01*
G01X192400D02*
Y111500D01*
G01Y116167D02*
X192233Y116250D01*
Y116417D01*
X192400Y116500D01*
X192567Y116417D01*
Y116250D01*
X192400Y116167D01*
G01X198000Y111500D02*
X197500Y111583D01*
X197000Y111917D01*
X196667Y112500D01*
X196500Y113167D01*
X196667Y113833D01*
X197000Y114417D01*
X197500Y114750D01*
X198000Y114833D01*
X198500Y114750D01*
X199000Y114417D01*
X199333Y113833D01*
X199417Y113167D01*
X199333Y112500D01*
X199000Y111917D01*
X198500Y111583D01*
X198000Y111500D01*
G01X202183D02*
Y114833D01*
G01Y114000D02*
X202517Y114417D01*
X203017Y114750D01*
X203683Y114833D01*
X204267Y114750D01*
X204767Y114417D01*
X205017Y113833D01*
Y111500D01*
G01X103500Y60500D02*
X694500D01*
G01X114000Y143500D02*
Y138500D01*
G01X112833Y141833D02*
X115167D01*
G01X118183Y138500D02*
Y143500D01*
G01Y141083D02*
X118600Y141500D01*
X119017Y141750D01*
X119683Y141833D01*
X120183Y141750D01*
X120767Y141417D01*
X121017Y140917D01*
Y138500D01*
G01X125200Y141833D02*
Y138500D01*
G01Y143167D02*
X125033Y143250D01*
Y143417D01*
X125200Y143500D01*
X125367Y143417D01*
Y143250D01*
X125200Y143167D01*
G01X132133Y141417D02*
X131550Y141750D01*
X131050Y141833D01*
X130383Y141667D01*
X129883Y141333D01*
X129550Y140750D01*
X129467Y140167D01*
X129550Y139583D01*
X129883Y139083D01*
X130383Y138667D01*
X131050Y138500D01*
X131633Y138667D01*
X132133Y139000D01*
G01X134983Y138500D02*
Y143500D01*
G01X137650Y141833D02*
X134983Y139917D01*
G01X136067Y140667D02*
X137817Y138500D01*
G01X140583D02*
Y141833D01*
G01Y141000D02*
X140917Y141417D01*
X141417Y141750D01*
X142083Y141833D01*
X142667Y141750D01*
X143167Y141417D01*
X143417Y140833D01*
Y138500D01*
G01X146350Y140750D02*
X149017D01*
X148767Y141333D01*
X148350Y141667D01*
X147767Y141833D01*
X147183Y141750D01*
X146683Y141500D01*
X146350Y140917D01*
X146183Y140417D01*
Y139917D01*
X146350Y139417D01*
X146767Y138917D01*
X147267Y138583D01*
X147850Y138500D01*
X148433Y138667D01*
X149017Y139167D01*
G01X151950Y139083D02*
X152367Y138750D01*
X152950Y138500D01*
X153450D01*
X153950Y138667D01*
X154283Y138917D01*
X154450Y139250D01*
X154367Y139750D01*
X154033Y140000D01*
X152533Y140500D01*
X152200Y141083D01*
X152367Y141500D01*
X152700Y141750D01*
X153200Y141833D01*
X153700Y141750D01*
X154200Y141500D01*
G01X157550Y139083D02*
X157967Y138750D01*
X158550Y138500D01*
X159050D01*
X159550Y138667D01*
X159883Y138917D01*
X160050Y139250D01*
X159967Y139750D01*
X159633Y140000D01*
X158133Y140500D01*
X157800Y141083D01*
X157967Y141500D01*
X158300Y141750D01*
X158800Y141833D01*
X159300Y141750D01*
X159800Y141500D01*
G01X171500Y138500D02*
Y141833D01*
G01Y141250D02*
X171167Y141583D01*
X170667Y141750D01*
X170083Y141833D01*
X169500Y141667D01*
X169000Y141333D01*
X168667Y140833D01*
X168500Y140167D01*
X168667Y139500D01*
X169000Y139000D01*
X169500Y138667D01*
X170083Y138500D01*
X170667Y138583D01*
X171167Y138833D01*
X171500Y139167D01*
G01X175100Y138500D02*
Y142750D01*
X175267Y143167D01*
X175600Y143417D01*
X176100Y143500D01*
X176600Y143333D01*
X176850Y142917D01*
G01X175850Y141500D02*
X174183D01*
G01X181200Y143500D02*
Y138500D01*
G01X180033Y141833D02*
X182367D01*
G01X185550Y140750D02*
X188217D01*
X187967Y141333D01*
X187550Y141667D01*
X186967Y141833D01*
X186383Y141750D01*
X185883Y141500D01*
X185550Y140917D01*
X185383Y140417D01*
Y139917D01*
X185550Y139417D01*
X185967Y138917D01*
X186467Y138583D01*
X187050Y138500D01*
X187633Y138667D01*
X188217Y139167D01*
G01X191233Y138500D02*
Y141833D01*
G01Y141167D02*
X191650Y141500D01*
X192067Y141750D01*
X192650Y141833D01*
X193067Y141750D01*
X193567Y141500D01*
G01X202100Y136833D02*
Y141833D01*
G01Y141083D02*
X202517Y141500D01*
X202933Y141750D01*
X203600Y141833D01*
X204183Y141750D01*
X204767Y141333D01*
X205017Y140750D01*
X205100Y140167D01*
X205017Y139583D01*
X204767Y139000D01*
X204267Y138667D01*
X203600Y138500D01*
X203017Y138583D01*
X202433Y138833D01*
X202100Y139167D01*
G01X209200Y138500D02*
Y143500D01*
G01X216300Y138500D02*
Y141833D01*
G01Y141250D02*
X215967Y141583D01*
X215467Y141750D01*
X214883Y141833D01*
X214300Y141667D01*
X213800Y141333D01*
X213467Y140833D01*
X213300Y140167D01*
X213467Y139500D01*
X213800Y139000D01*
X214300Y138667D01*
X214883Y138500D01*
X215467Y138583D01*
X215967Y138833D01*
X216300Y139167D01*
G01X220400Y143500D02*
Y138500D01*
G01X219233Y141833D02*
X221567D01*
G01X226000D02*
Y138500D01*
G01Y143167D02*
X225833Y143250D01*
Y143417D01*
X226000Y143500D01*
X226167Y143417D01*
Y143250D01*
X226000Y143167D01*
G01X230183Y138500D02*
Y141833D01*
G01Y141000D02*
X230517Y141417D01*
X231017Y141750D01*
X231683Y141833D01*
X232267Y141750D01*
X232767Y141417D01*
X233017Y140833D01*
Y138500D01*
G01X236033Y137250D02*
X236617Y136917D01*
X237283Y136833D01*
X237867Y136917D01*
X238367Y137333D01*
X238700Y137917D01*
Y141833D01*
G01Y141167D02*
X238367Y141500D01*
X237867Y141750D01*
X237283Y141833D01*
X236617Y141667D01*
X236200Y141333D01*
X235867Y140750D01*
X235700Y140167D01*
X235783Y139667D01*
X236117Y139083D01*
X236617Y138667D01*
X237283Y138500D01*
X237783Y138583D01*
X238367Y138917D01*
X238700Y139250D01*
G01X115667Y148500D02*
X112333D01*
Y153500D01*
X115667D01*
G01X114333Y151083D02*
X112333D01*
G01X118350Y151833D02*
X120850Y148500D01*
G01Y151833D02*
X118350Y148500D01*
G01X125200Y153500D02*
Y148500D01*
G01X124033Y151833D02*
X126367D01*
G01X129550Y150750D02*
X132217D01*
X131967Y151333D01*
X131550Y151667D01*
X130967Y151833D01*
X130383Y151750D01*
X129883Y151500D01*
X129550Y150917D01*
X129383Y150417D01*
Y149917D01*
X129550Y149417D01*
X129967Y148917D01*
X130467Y148583D01*
X131050Y148500D01*
X131633Y148667D01*
X132217Y149167D01*
G01X135233Y148500D02*
Y151833D01*
G01Y151167D02*
X135650Y151500D01*
X136067Y151750D01*
X136650Y151833D01*
X137067Y151750D01*
X137567Y151500D01*
G01X140583Y148500D02*
Y151833D01*
G01Y151000D02*
X140917Y151417D01*
X141417Y151750D01*
X142083Y151833D01*
X142667Y151750D01*
X143167Y151417D01*
X143417Y150833D01*
Y148500D01*
G01X149100D02*
Y151833D01*
G01Y151250D02*
X148767Y151583D01*
X148267Y151750D01*
X147683Y151833D01*
X147100Y151667D01*
X146600Y151333D01*
X146267Y150833D01*
X146100Y150167D01*
X146267Y149500D01*
X146600Y149000D01*
X147100Y148667D01*
X147683Y148500D01*
X148267Y148583D01*
X148767Y148833D01*
X149100Y149167D01*
G01X153200Y148500D02*
Y153500D01*
G01X165733Y151417D02*
X165150Y151750D01*
X164650Y151833D01*
X163983Y151667D01*
X163483Y151333D01*
X163150Y150750D01*
X163067Y150167D01*
X163150Y149583D01*
X163483Y149083D01*
X163983Y148667D01*
X164650Y148500D01*
X165233Y148667D01*
X165733Y149000D01*
G01X170000Y148500D02*
X169500Y148583D01*
X169000Y148917D01*
X168667Y149500D01*
X168500Y150167D01*
X168667Y150833D01*
X169000Y151417D01*
X169500Y151750D01*
X170000Y151833D01*
X170500Y151750D01*
X171000Y151417D01*
X171333Y150833D01*
X171417Y150167D01*
X171333Y149500D01*
X171000Y148917D01*
X170500Y148583D01*
X170000Y148500D01*
G01X174183D02*
Y151833D01*
G01Y151000D02*
X174517Y151417D01*
X175017Y151750D01*
X175683Y151833D01*
X176267Y151750D01*
X176767Y151417D01*
X177017Y150833D01*
Y148500D01*
G01X182700Y153500D02*
Y148500D01*
G01Y149250D02*
X182367Y148833D01*
X181867Y148583D01*
X181283Y148500D01*
X180617Y148667D01*
X180117Y149083D01*
X179783Y149583D01*
X179700Y150167D01*
X179783Y150750D01*
X180117Y151250D01*
X180617Y151667D01*
X181283Y151833D01*
X181867Y151750D01*
X182283Y151583D01*
X182700Y151250D01*
G01X185383Y151833D02*
Y149500D01*
X185717Y148917D01*
X186217Y148583D01*
X186800Y148500D01*
X187383Y148583D01*
X187883Y148917D01*
X188217Y149500D01*
G01Y148500D02*
Y151833D01*
G01X193733Y151417D02*
X193150Y151750D01*
X192650Y151833D01*
X191983Y151667D01*
X191483Y151333D01*
X191150Y150750D01*
X191067Y150167D01*
X191150Y149583D01*
X191483Y149083D01*
X191983Y148667D01*
X192650Y148500D01*
X193233Y148667D01*
X193733Y149000D01*
G01X198000Y153500D02*
Y148500D01*
G01X196833Y151833D02*
X199167D01*
G01X203600Y148500D02*
X203100Y148583D01*
X202600Y148917D01*
X202267Y149500D01*
X202100Y150167D01*
X202267Y150833D01*
X202600Y151417D01*
X203100Y151750D01*
X203600Y151833D01*
X204100Y151750D01*
X204600Y151417D01*
X204933Y150833D01*
X205017Y150167D01*
X204933Y149500D01*
X204600Y148917D01*
X204100Y148583D01*
X203600Y148500D01*
G01X208033D02*
Y151833D01*
G01Y151167D02*
X208450Y151500D01*
X208867Y151750D01*
X209450Y151833D01*
X209867Y151750D01*
X210367Y151500D01*
G01X112333Y356500D02*
Y351500D01*
X115667D01*
G01X121100D02*
Y354833D01*
G01Y354250D02*
X120767Y354583D01*
X120267Y354750D01*
X119683Y354833D01*
X119100Y354667D01*
X118600Y354333D01*
X118267Y353833D01*
X118100Y353167D01*
X118267Y352500D01*
X118600Y352000D01*
X119100Y351667D01*
X119683Y351500D01*
X120267Y351583D01*
X120767Y351833D01*
X121100Y352167D01*
G01X123950Y352083D02*
X124367Y351750D01*
X124950Y351500D01*
X125450D01*
X125950Y351667D01*
X126283Y351917D01*
X126450Y352250D01*
X126367Y352750D01*
X126033Y353000D01*
X124533Y353500D01*
X124200Y354083D01*
X124367Y354500D01*
X124700Y354750D01*
X125200Y354833D01*
X125700Y354750D01*
X126200Y354500D01*
G01X129550Y353750D02*
X132217D01*
X131967Y354333D01*
X131550Y354667D01*
X130967Y354833D01*
X130383Y354750D01*
X129883Y354500D01*
X129550Y353917D01*
X129383Y353417D01*
Y352917D01*
X129550Y352417D01*
X129967Y351917D01*
X130467Y351583D01*
X131050Y351500D01*
X131633Y351667D01*
X132217Y352167D01*
G01X135233Y351500D02*
Y354833D01*
G01Y354167D02*
X135650Y354500D01*
X136067Y354750D01*
X136650Y354833D01*
X137067Y354750D01*
X137567Y354500D01*
G01X146100Y354833D02*
X147600Y351500D01*
X149100Y354833D01*
G01X153200D02*
Y351500D01*
G01Y356167D02*
X153033Y356250D01*
Y356417D01*
X153200Y356500D01*
X153367Y356417D01*
Y356250D01*
X153200Y356167D01*
G01X160300Y351500D02*
Y354833D01*
G01Y354250D02*
X159967Y354583D01*
X159467Y354750D01*
X158883Y354833D01*
X158300Y354667D01*
X157800Y354333D01*
X157467Y353833D01*
X157300Y353167D01*
X157467Y352500D01*
X157800Y352000D01*
X158300Y351667D01*
X158883Y351500D01*
X159467Y351583D01*
X159967Y351833D01*
X160300Y352167D01*
G01X168167Y351333D02*
X171833Y355000D01*
G01X170000Y355667D02*
Y350667D01*
G01X171833Y351333D02*
X168167Y355000D01*
G01X167500Y353167D02*
X172500D01*
G01X175183Y349833D02*
X174350Y350667D01*
X173933Y351500D01*
Y354833D01*
X174350Y355667D01*
X175183Y356500D01*
G01X179367Y352250D02*
X179867Y351833D01*
X180450Y351583D01*
X181200Y351500D01*
X181950Y351667D01*
X182533Y352000D01*
X182950Y352583D01*
X183033Y353250D01*
X182867Y353917D01*
X182450Y354333D01*
X181867Y354667D01*
X181283Y354750D01*
X180700Y354667D01*
X179950Y354333D01*
X180200Y356500D01*
X182450D01*
G01X186800Y351333D02*
X186633Y351417D01*
Y351583D01*
X186800Y351667D01*
X186967Y351583D01*
Y351417D01*
X186800Y351333D01*
G01X192400Y351500D02*
Y356500D01*
X191400Y355500D01*
G01Y351500D02*
X193400D01*
G01X198417Y349833D02*
X199250Y350667D01*
X199667Y351500D01*
Y354833D01*
X199250Y355667D01*
X198417Y356500D01*
G01X112333Y406500D02*
Y411500D01*
X114333D01*
X115000Y411250D01*
X115500Y410667D01*
X115667Y410000D01*
X115500Y409333D01*
X115083Y408833D01*
X114333Y408583D01*
X112333D01*
G01X119600Y411500D02*
Y406500D01*
G01X117683Y411500D02*
X121517D01*
G01X123450Y406500D02*
Y411500D01*
G01X126950D02*
Y406500D01*
G01Y409000D02*
X123450D01*
G01X135233Y406500D02*
Y409833D01*
G01Y409167D02*
X135650Y409500D01*
X136067Y409750D01*
X136650Y409833D01*
X137067Y409750D01*
X137567Y409500D01*
G01X140750Y408750D02*
X143417D01*
X143167Y409333D01*
X142750Y409667D01*
X142167Y409833D01*
X141583Y409750D01*
X141083Y409500D01*
X140750Y408917D01*
X140583Y408417D01*
Y407917D01*
X140750Y407417D01*
X141167Y406917D01*
X141667Y406583D01*
X142250Y406500D01*
X142833Y406667D01*
X143417Y407167D01*
G01X146433Y405250D02*
X147017Y404917D01*
X147683Y404833D01*
X148267Y404917D01*
X148767Y405333D01*
X149100Y405917D01*
Y409833D01*
G01Y409167D02*
X148767Y409500D01*
X148267Y409750D01*
X147683Y409833D01*
X147017Y409667D01*
X146600Y409333D01*
X146267Y408750D01*
X146100Y408167D01*
X146183Y407667D01*
X146517Y407083D01*
X147017Y406667D01*
X147683Y406500D01*
X148183Y406583D01*
X148767Y406917D01*
X149100Y407250D01*
G01X153200Y409833D02*
Y406500D01*
G01Y411167D02*
X153033Y411250D01*
Y411417D01*
X153200Y411500D01*
X153367Y411417D01*
Y411250D01*
X153200Y411167D01*
G01X157550Y407083D02*
X157967Y406750D01*
X158550Y406500D01*
X159050D01*
X159550Y406667D01*
X159883Y406917D01*
X160050Y407250D01*
X159967Y407750D01*
X159633Y408000D01*
X158133Y408500D01*
X157800Y409083D01*
X157967Y409500D01*
X158300Y409750D01*
X158800Y409833D01*
X159300Y409750D01*
X159800Y409500D01*
G01X164400Y411500D02*
Y406500D01*
G01X163233Y409833D02*
X165567D01*
G01X168833Y406500D02*
Y409833D01*
G01Y409167D02*
X169250Y409500D01*
X169667Y409750D01*
X170250Y409833D01*
X170667Y409750D01*
X171167Y409500D01*
G01X177100Y406500D02*
Y409833D01*
G01Y409250D02*
X176767Y409583D01*
X176267Y409750D01*
X175683Y409833D01*
X175100Y409667D01*
X174600Y409333D01*
X174267Y408833D01*
X174100Y408167D01*
X174267Y407500D01*
X174600Y407000D01*
X175100Y406667D01*
X175683Y406500D01*
X176267Y406583D01*
X176767Y406833D01*
X177100Y407167D01*
G01X181200Y411500D02*
Y406500D01*
G01X180033Y409833D02*
X182367D01*
G01X186800D02*
Y406500D01*
G01Y411167D02*
X186633Y411250D01*
Y411417D01*
X186800Y411500D01*
X186967Y411417D01*
Y411250D01*
X186800Y411167D01*
G01X192400Y406500D02*
X191900Y406583D01*
X191400Y406917D01*
X191067Y407500D01*
X190900Y408167D01*
X191067Y408833D01*
X191400Y409417D01*
X191900Y409750D01*
X192400Y409833D01*
X192900Y409750D01*
X193400Y409417D01*
X193733Y408833D01*
X193817Y408167D01*
X193733Y407500D01*
X193400Y406917D01*
X192900Y406583D01*
X192400Y406500D01*
G01X196583D02*
Y409833D01*
G01Y409000D02*
X196917Y409417D01*
X197417Y409750D01*
X198083Y409833D01*
X198667Y409750D01*
X199167Y409417D01*
X199417Y408833D01*
Y406500D01*
G01X105000Y364500D02*
X694500D01*
G01X112167Y433000D02*
Y438000D01*
X113833D01*
X114500Y437750D01*
X115000Y437417D01*
X115417Y436917D01*
X115750Y436333D01*
X115833Y435500D01*
X115750Y434667D01*
X115417Y434083D01*
X115000Y433583D01*
X114500Y433250D01*
X113833Y433000D01*
X112167D01*
G01X118350Y435250D02*
X121017D01*
X120767Y435833D01*
X120350Y436167D01*
X119767Y436333D01*
X119183Y436250D01*
X118683Y436000D01*
X118350Y435417D01*
X118183Y434917D01*
Y434417D01*
X118350Y433917D01*
X118767Y433417D01*
X119267Y433083D01*
X119850Y433000D01*
X120433Y433167D01*
X121017Y433667D01*
G01X123700Y431333D02*
Y436333D01*
G01Y435583D02*
X124117Y436000D01*
X124533Y436250D01*
X125200Y436333D01*
X125783Y436250D01*
X126367Y435833D01*
X126617Y435250D01*
X126700Y434667D01*
X126617Y434083D01*
X126367Y433500D01*
X125867Y433167D01*
X125200Y433000D01*
X124617Y433083D01*
X124033Y433333D01*
X123700Y433667D01*
G01X130800Y438000D02*
Y433000D01*
G01X129633Y436333D02*
X131967D01*
G01X134983Y433000D02*
Y438000D01*
G01Y435583D02*
X135400Y436000D01*
X135817Y436250D01*
X136483Y436333D01*
X136983Y436250D01*
X137567Y435917D01*
X137817Y435417D01*
Y433000D01*
G01X148933Y435917D02*
X148350Y436250D01*
X147850Y436333D01*
X147183Y436167D01*
X146683Y435833D01*
X146350Y435250D01*
X146267Y434667D01*
X146350Y434083D01*
X146683Y433583D01*
X147183Y433167D01*
X147850Y433000D01*
X148433Y433167D01*
X148933Y433500D01*
G01X153200Y433000D02*
X152700Y433083D01*
X152200Y433417D01*
X151867Y434000D01*
X151700Y434667D01*
X151867Y435333D01*
X152200Y435917D01*
X152700Y436250D01*
X153200Y436333D01*
X153700Y436250D01*
X154200Y435917D01*
X154533Y435333D01*
X154617Y434667D01*
X154533Y434000D01*
X154200Y433417D01*
X153700Y433083D01*
X153200Y433000D01*
G01X157383D02*
Y436333D01*
G01Y435500D02*
X157717Y435917D01*
X158217Y436250D01*
X158883Y436333D01*
X159467Y436250D01*
X159967Y435917D01*
X160217Y435333D01*
Y433000D01*
G01X164400Y438000D02*
Y433000D01*
G01X163233Y436333D02*
X165567D01*
G01X168833Y433000D02*
Y436333D01*
G01Y435667D02*
X169250Y436000D01*
X169667Y436250D01*
X170250Y436333D01*
X170667Y436250D01*
X171167Y436000D01*
G01X175600Y433000D02*
X175100Y433083D01*
X174600Y433417D01*
X174267Y434000D01*
X174100Y434667D01*
X174267Y435333D01*
X174600Y435917D01*
X175100Y436250D01*
X175600Y436333D01*
X176100Y436250D01*
X176600Y435917D01*
X176933Y435333D01*
X177017Y434667D01*
X176933Y434000D01*
X176600Y433417D01*
X176100Y433083D01*
X175600Y433000D01*
G01X181200D02*
Y438000D01*
G01X190983Y433000D02*
Y438000D01*
G01Y435583D02*
X191400Y436000D01*
X191817Y436250D01*
X192483Y436333D01*
X192983Y436250D01*
X193567Y435917D01*
X193817Y435417D01*
Y433000D01*
G01X198000D02*
X197500Y433083D01*
X197000Y433417D01*
X196667Y434000D01*
X196500Y434667D01*
X196667Y435333D01*
X197000Y435917D01*
X197500Y436250D01*
X198000Y436333D01*
X198500Y436250D01*
X199000Y435917D01*
X199333Y435333D01*
X199417Y434667D01*
X199333Y434000D01*
X199000Y433417D01*
X198500Y433083D01*
X198000Y433000D01*
G01X203600D02*
Y438000D01*
G01X207950Y435250D02*
X210617D01*
X210367Y435833D01*
X209950Y436167D01*
X209367Y436333D01*
X208783Y436250D01*
X208283Y436000D01*
X207950Y435417D01*
X207783Y434917D01*
Y434417D01*
X207950Y433917D01*
X208367Y433417D01*
X208867Y433083D01*
X209450Y433000D01*
X210033Y433167D01*
X210617Y433667D01*
G01X112333Y455000D02*
Y460000D01*
X114417D01*
X115083Y459750D01*
X115500Y459417D01*
X115667Y458750D01*
X115500Y458083D01*
X115000Y457667D01*
X114417Y457417D01*
X112333D01*
G01X114417D02*
X115667Y455000D01*
G01X119600D02*
X119100Y455083D01*
X118600Y455417D01*
X118267Y456000D01*
X118100Y456667D01*
X118267Y457333D01*
X118600Y457917D01*
X119100Y458250D01*
X119600Y458333D01*
X120100Y458250D01*
X120600Y457917D01*
X120933Y457333D01*
X121017Y456667D01*
X120933Y456000D01*
X120600Y455417D01*
X120100Y455083D01*
X119600Y455000D01*
G01X123783Y458333D02*
Y456000D01*
X124117Y455417D01*
X124617Y455083D01*
X125200Y455000D01*
X125783Y455083D01*
X126283Y455417D01*
X126617Y456000D01*
G01Y455000D02*
Y458333D01*
G01X129633Y453750D02*
X130217Y453417D01*
X130883Y453333D01*
X131467Y453417D01*
X131967Y453833D01*
X132300Y454417D01*
Y458333D01*
G01Y457667D02*
X131967Y458000D01*
X131467Y458250D01*
X130883Y458333D01*
X130217Y458167D01*
X129800Y457833D01*
X129467Y457250D01*
X129300Y456667D01*
X129383Y456167D01*
X129717Y455583D01*
X130217Y455167D01*
X130883Y455000D01*
X131383Y455083D01*
X131967Y455417D01*
X132300Y455750D01*
G01X134983Y455000D02*
Y460000D01*
G01Y457583D02*
X135400Y458000D01*
X135817Y458250D01*
X136483Y458333D01*
X136983Y458250D01*
X137567Y457917D01*
X137817Y457417D01*
Y455000D01*
G01X140583D02*
Y458333D01*
G01Y457500D02*
X140917Y457917D01*
X141417Y458250D01*
X142083Y458333D01*
X142667Y458250D01*
X143167Y457917D01*
X143417Y457333D01*
Y455000D01*
G01X146350Y457250D02*
X149017D01*
X148767Y457833D01*
X148350Y458167D01*
X147767Y458333D01*
X147183Y458250D01*
X146683Y458000D01*
X146350Y457417D01*
X146183Y456917D01*
Y456417D01*
X146350Y455917D01*
X146767Y455417D01*
X147267Y455083D01*
X147850Y455000D01*
X148433Y455167D01*
X149017Y455667D01*
G01X151950Y455583D02*
X152367Y455250D01*
X152950Y455000D01*
X153450D01*
X153950Y455167D01*
X154283Y455417D01*
X154450Y455750D01*
X154367Y456250D01*
X154033Y456500D01*
X152533Y457000D01*
X152200Y457583D01*
X152367Y458000D01*
X152700Y458250D01*
X153200Y458333D01*
X153700Y458250D01*
X154200Y458000D01*
G01X157550Y455583D02*
X157967Y455250D01*
X158550Y455000D01*
X159050D01*
X159550Y455167D01*
X159883Y455417D01*
X160050Y455750D01*
X159967Y456250D01*
X159633Y456500D01*
X158133Y457000D01*
X157800Y457583D01*
X157967Y458000D01*
X158300Y458250D01*
X158800Y458333D01*
X159300Y458250D01*
X159800Y458000D01*
G01X103500Y449000D02*
X694500D01*
G01X104000Y464000D02*
X694500D01*
G01X103500Y424000D02*
X694500D01*
G01X112250Y513500D02*
Y518500D01*
G01X115750D02*
Y513500D01*
G01Y516000D02*
X112250D01*
G01X119600Y513500D02*
X119100Y513583D01*
X118600Y513917D01*
X118267Y514500D01*
X118100Y515167D01*
X118267Y515833D01*
X118600Y516417D01*
X119100Y516750D01*
X119600Y516833D01*
X120100Y516750D01*
X120600Y516417D01*
X120933Y515833D01*
X121017Y515167D01*
X120933Y514500D01*
X120600Y513917D01*
X120100Y513583D01*
X119600Y513500D01*
G01X125200D02*
Y518500D01*
G01X129550Y515750D02*
X132217D01*
X131967Y516333D01*
X131550Y516667D01*
X130967Y516833D01*
X130383Y516750D01*
X129883Y516500D01*
X129550Y515917D01*
X129383Y515417D01*
Y514917D01*
X129550Y514417D01*
X129967Y513917D01*
X130467Y513583D01*
X131050Y513500D01*
X131633Y513667D01*
X132217Y514167D01*
G01X140750Y514083D02*
X141167Y513750D01*
X141750Y513500D01*
X142250D01*
X142750Y513667D01*
X143083Y513917D01*
X143250Y514250D01*
X143167Y514750D01*
X142833Y515000D01*
X141333Y515500D01*
X141000Y516083D01*
X141167Y516500D01*
X141500Y516750D01*
X142000Y516833D01*
X142500Y516750D01*
X143000Y516500D01*
G01X147600Y516833D02*
Y513500D01*
G01Y518167D02*
X147433Y518250D01*
Y518417D01*
X147600Y518500D01*
X147767Y518417D01*
Y518250D01*
X147600Y518167D01*
G01X151950Y516833D02*
X154450D01*
X151950Y513500D01*
X154450D01*
G01X157550Y515750D02*
X160217D01*
X159967Y516333D01*
X159550Y516667D01*
X158967Y516833D01*
X158383Y516750D01*
X157883Y516500D01*
X157550Y515917D01*
X157383Y515417D01*
Y514917D01*
X157550Y514417D01*
X157967Y513917D01*
X158467Y513583D01*
X159050Y513500D01*
X159633Y513667D01*
X160217Y514167D01*
G01X111917Y610000D02*
X114000Y605000D01*
X116083Y610000D01*
G01X119600Y608333D02*
Y605000D01*
G01Y609667D02*
X119433Y609750D01*
Y609917D01*
X119600Y610000D01*
X119767Y609917D01*
Y609750D01*
X119600Y609667D01*
G01X126700Y605000D02*
Y608333D01*
G01Y607750D02*
X126367Y608083D01*
X125867Y608250D01*
X125283Y608333D01*
X124700Y608167D01*
X124200Y607833D01*
X123867Y607333D01*
X123700Y606667D01*
X123867Y606000D01*
X124200Y605500D01*
X124700Y605167D01*
X125283Y605000D01*
X125867Y605083D01*
X126367Y605333D01*
X126700Y605667D01*
G01X134983Y605000D02*
Y610000D01*
G01Y607583D02*
X135400Y608000D01*
X135817Y608250D01*
X136483Y608333D01*
X136983Y608250D01*
X137567Y607917D01*
X137817Y607417D01*
Y605000D01*
G01X142000D02*
X141500Y605083D01*
X141000Y605417D01*
X140667Y606000D01*
X140500Y606667D01*
X140667Y607333D01*
X141000Y607917D01*
X141500Y608250D01*
X142000Y608333D01*
X142500Y608250D01*
X143000Y607917D01*
X143333Y607333D01*
X143417Y606667D01*
X143333Y606000D01*
X143000Y605417D01*
X142500Y605083D01*
X142000Y605000D01*
G01X147600D02*
Y610000D01*
G01X151950Y607250D02*
X154617D01*
X154367Y607833D01*
X153950Y608167D01*
X153367Y608333D01*
X152783Y608250D01*
X152283Y608000D01*
X151950Y607417D01*
X151783Y606917D01*
Y606417D01*
X151950Y605917D01*
X152367Y605417D01*
X152867Y605083D01*
X153450Y605000D01*
X154033Y605167D01*
X154617Y605667D01*
G01X164400Y610000D02*
Y605000D01*
G01X163233Y608333D02*
X165567D01*
G01X168583Y605000D02*
Y610000D01*
G01Y607583D02*
X169000Y608000D01*
X169417Y608250D01*
X170083Y608333D01*
X170583Y608250D01*
X171167Y607917D01*
X171417Y607417D01*
Y605000D01*
G01X174350Y607250D02*
X177017D01*
X176767Y607833D01*
X176350Y608167D01*
X175767Y608333D01*
X175183Y608250D01*
X174683Y608000D01*
X174350Y607417D01*
X174183Y606917D01*
Y606417D01*
X174350Y605917D01*
X174767Y605417D01*
X175267Y605083D01*
X175850Y605000D01*
X176433Y605167D01*
X177017Y605667D01*
G01X180033Y605000D02*
Y608333D01*
G01Y607667D02*
X180450Y608000D01*
X180867Y608250D01*
X181450Y608333D01*
X181867Y608250D01*
X182367Y608000D01*
G01X184300Y605000D02*
Y608333D01*
G01Y607417D02*
X184550Y607833D01*
X184967Y608167D01*
X185550Y608333D01*
X186133Y608167D01*
X186550Y607833D01*
X186800Y607417D01*
Y605000D01*
G01Y607417D02*
X187050Y607833D01*
X187467Y608167D01*
X188050Y608333D01*
X188633Y608167D01*
X189050Y607833D01*
X189300Y607333D01*
Y605000D01*
G01X193900D02*
Y608333D01*
G01Y607750D02*
X193567Y608083D01*
X193067Y608250D01*
X192483Y608333D01*
X191900Y608167D01*
X191400Y607833D01*
X191067Y607333D01*
X190900Y606667D01*
X191067Y606000D01*
X191400Y605500D01*
X191900Y605167D01*
X192483Y605000D01*
X193067Y605083D01*
X193567Y605333D01*
X193900Y605667D01*
G01X198000Y605000D02*
Y610000D01*
G01X207700Y603333D02*
Y608333D01*
G01Y607583D02*
X208117Y608000D01*
X208533Y608250D01*
X209200Y608333D01*
X209783Y608250D01*
X210367Y607833D01*
X210617Y607250D01*
X210700Y606667D01*
X210617Y606083D01*
X210367Y605500D01*
X209867Y605167D01*
X209200Y605000D01*
X208617Y605083D01*
X208033Y605333D01*
X207700Y605667D01*
G01X216300Y605000D02*
Y608333D01*
G01Y607750D02*
X215967Y608083D01*
X215467Y608250D01*
X214883Y608333D01*
X214300Y608167D01*
X213800Y607833D01*
X213467Y607333D01*
X213300Y606667D01*
X213467Y606000D01*
X213800Y605500D01*
X214300Y605167D01*
X214883Y605000D01*
X215467Y605083D01*
X215967Y605333D01*
X216300Y605667D01*
G01X221900Y610000D02*
Y605000D01*
G01Y605750D02*
X221567Y605333D01*
X221067Y605083D01*
X220483Y605000D01*
X219817Y605167D01*
X219317Y605583D01*
X218983Y606083D01*
X218900Y606667D01*
X218983Y607250D01*
X219317Y607750D01*
X219817Y608167D01*
X220483Y608333D01*
X221067Y608250D01*
X221483Y608083D01*
X221900Y607750D01*
G01X112250Y588500D02*
Y593500D01*
G01X115750D02*
Y588500D01*
G01Y591000D02*
X112250D01*
G01X119600Y588500D02*
X119100Y588583D01*
X118600Y588917D01*
X118267Y589500D01*
X118100Y590167D01*
X118267Y590833D01*
X118600Y591417D01*
X119100Y591750D01*
X119600Y591833D01*
X120100Y591750D01*
X120600Y591417D01*
X120933Y590833D01*
X121017Y590167D01*
X120933Y589500D01*
X120600Y588917D01*
X120100Y588583D01*
X119600Y588500D01*
G01X125200D02*
Y593500D01*
G01X129550Y590750D02*
X132217D01*
X131967Y591333D01*
X131550Y591667D01*
X130967Y591833D01*
X130383Y591750D01*
X129883Y591500D01*
X129550Y590917D01*
X129383Y590417D01*
Y589917D01*
X129550Y589417D01*
X129967Y588917D01*
X130467Y588583D01*
X131050Y588500D01*
X131633Y588667D01*
X132217Y589167D01*
G01X140500Y586833D02*
Y591833D01*
G01Y591083D02*
X140917Y591500D01*
X141333Y591750D01*
X142000Y591833D01*
X142583Y591750D01*
X143167Y591333D01*
X143417Y590750D01*
X143500Y590167D01*
X143417Y589583D01*
X143167Y589000D01*
X142667Y588667D01*
X142000Y588500D01*
X141417Y588583D01*
X140833Y588833D01*
X140500Y589167D01*
G01X147600Y588500D02*
X147100Y588583D01*
X146600Y588917D01*
X146267Y589500D01*
X146100Y590167D01*
X146267Y590833D01*
X146600Y591417D01*
X147100Y591750D01*
X147600Y591833D01*
X148100Y591750D01*
X148600Y591417D01*
X148933Y590833D01*
X149017Y590167D01*
X148933Y589500D01*
X148600Y588917D01*
X148100Y588583D01*
X147600Y588500D01*
G01X151950Y589083D02*
X152367Y588750D01*
X152950Y588500D01*
X153450D01*
X153950Y588667D01*
X154283Y588917D01*
X154450Y589250D01*
X154367Y589750D01*
X154033Y590000D01*
X152533Y590500D01*
X152200Y591083D01*
X152367Y591500D01*
X152700Y591750D01*
X153200Y591833D01*
X153700Y591750D01*
X154200Y591500D01*
G01X158800Y591833D02*
Y588500D01*
G01Y593167D02*
X158633Y593250D01*
Y593417D01*
X158800Y593500D01*
X158967Y593417D01*
Y593250D01*
X158800Y593167D01*
G01X164400Y593500D02*
Y588500D01*
G01X163233Y591833D02*
X165567D01*
G01X170000D02*
Y588500D01*
G01Y593167D02*
X169833Y593250D01*
Y593417D01*
X170000Y593500D01*
X170167Y593417D01*
Y593250D01*
X170000Y593167D01*
G01X175600Y588500D02*
X175100Y588583D01*
X174600Y588917D01*
X174267Y589500D01*
X174100Y590167D01*
X174267Y590833D01*
X174600Y591417D01*
X175100Y591750D01*
X175600Y591833D01*
X176100Y591750D01*
X176600Y591417D01*
X176933Y590833D01*
X177017Y590167D01*
X176933Y589500D01*
X176600Y588917D01*
X176100Y588583D01*
X175600Y588500D01*
G01X179783D02*
Y591833D01*
G01Y591000D02*
X180117Y591417D01*
X180617Y591750D01*
X181283Y591833D01*
X181867Y591750D01*
X182367Y591417D01*
X182617Y590833D01*
Y588500D01*
G01X192400Y593500D02*
Y588500D01*
G01X191233Y591833D02*
X193567D01*
G01X198000Y588500D02*
X197500Y588583D01*
X197000Y588917D01*
X196667Y589500D01*
X196500Y590167D01*
X196667Y590833D01*
X197000Y591417D01*
X197500Y591750D01*
X198000Y591833D01*
X198500Y591750D01*
X199000Y591417D01*
X199333Y590833D01*
X199417Y590167D01*
X199333Y589500D01*
X199000Y588917D01*
X198500Y588583D01*
X198000Y588500D01*
G01X203600D02*
Y593500D01*
G01X207950Y590750D02*
X210617D01*
X210367Y591333D01*
X209950Y591667D01*
X209367Y591833D01*
X208783Y591750D01*
X208283Y591500D01*
X207950Y590917D01*
X207783Y590417D01*
Y589917D01*
X207950Y589417D01*
X208367Y588917D01*
X208867Y588583D01*
X209450Y588500D01*
X210033Y588667D01*
X210617Y589167D01*
G01X213633Y588500D02*
Y591833D01*
G01Y591167D02*
X214050Y591500D01*
X214467Y591750D01*
X215050Y591833D01*
X215467Y591750D01*
X215967Y591500D01*
G01X221900Y588500D02*
Y591833D01*
G01Y591250D02*
X221567Y591583D01*
X221067Y591750D01*
X220483Y591833D01*
X219900Y591667D01*
X219400Y591333D01*
X219067Y590833D01*
X218900Y590167D01*
X219067Y589500D01*
X219400Y589000D01*
X219900Y588667D01*
X220483Y588500D01*
X221067Y588583D01*
X221567Y588833D01*
X221900Y589167D01*
G01X224583Y588500D02*
Y591833D01*
G01Y591000D02*
X224917Y591417D01*
X225417Y591750D01*
X226083Y591833D01*
X226667Y591750D01*
X227167Y591417D01*
X227417Y590833D01*
Y588500D01*
G01X232933Y591417D02*
X232350Y591750D01*
X231850Y591833D01*
X231183Y591667D01*
X230683Y591333D01*
X230350Y590750D01*
X230267Y590167D01*
X230350Y589583D01*
X230683Y589083D01*
X231183Y588667D01*
X231850Y588500D01*
X232433Y588667D01*
X232933Y589000D01*
G01X235950Y590750D02*
X238617D01*
X238367Y591333D01*
X237950Y591667D01*
X237367Y591833D01*
X236783Y591750D01*
X236283Y591500D01*
X235950Y590917D01*
X235783Y590417D01*
Y589917D01*
X235950Y589417D01*
X236367Y588917D01*
X236867Y588583D01*
X237450Y588500D01*
X238033Y588667D01*
X238617Y589167D01*
G01X103500Y584000D02*
X694500D01*
G01X111917Y620000D02*
X114000Y625000D01*
X116083Y620000D01*
G01X115333Y621750D02*
X112667D01*
G01X118183Y620000D02*
Y623333D01*
G01Y622500D02*
X118517Y622917D01*
X119017Y623250D01*
X119683Y623333D01*
X120267Y623250D01*
X120767Y622917D01*
X121017Y622333D01*
Y620000D01*
G01X125200Y625000D02*
Y620000D01*
G01X124033Y623333D02*
X126367D01*
G01X130800D02*
Y620000D01*
G01Y624667D02*
X130633Y624750D01*
Y624917D01*
X130800Y625000D01*
X130967Y624917D01*
Y624750D01*
X130800Y624667D01*
G01X135317Y621667D02*
X137483D01*
G01X146100Y618333D02*
Y623333D01*
G01Y622583D02*
X146517Y623000D01*
X146933Y623250D01*
X147600Y623333D01*
X148183Y623250D01*
X148767Y622833D01*
X149017Y622250D01*
X149100Y621667D01*
X149017Y621083D01*
X148767Y620500D01*
X148267Y620167D01*
X147600Y620000D01*
X147017Y620083D01*
X146433Y620333D01*
X146100Y620667D01*
G01X154700Y620000D02*
Y623333D01*
G01Y622750D02*
X154367Y623083D01*
X153867Y623250D01*
X153283Y623333D01*
X152700Y623167D01*
X152200Y622833D01*
X151867Y622333D01*
X151700Y621667D01*
X151867Y621000D01*
X152200Y620500D01*
X152700Y620167D01*
X153283Y620000D01*
X153867Y620083D01*
X154367Y620333D01*
X154700Y620667D01*
G01X160300Y625000D02*
Y620000D01*
G01Y620750D02*
X159967Y620333D01*
X159467Y620083D01*
X158883Y620000D01*
X158217Y620167D01*
X157717Y620583D01*
X157383Y621083D01*
X157300Y621667D01*
X157383Y622250D01*
X157717Y622750D01*
X158217Y623167D01*
X158883Y623333D01*
X159467Y623250D01*
X159883Y623083D01*
X160300Y622750D01*
G01X111843Y639590D02*
Y644590D01*
X115677Y639590D01*
Y644590D01*
G01X119360Y639590D02*
X118860Y639673D01*
X118360Y640007D01*
X118027Y640590D01*
X117860Y641257D01*
X118027Y641923D01*
X118360Y642507D01*
X118860Y642840D01*
X119360Y642923D01*
X119860Y642840D01*
X120360Y642507D01*
X120693Y641923D01*
X120777Y641257D01*
X120693Y640590D01*
X120360Y640007D01*
X119860Y639673D01*
X119360Y639590D01*
G01X123543D02*
Y642923D01*
G01Y642090D02*
X123877Y642507D01*
X124377Y642840D01*
X125043Y642923D01*
X125627Y642840D01*
X126127Y642507D01*
X126377Y641923D01*
Y639590D01*
G01X129477Y641257D02*
X131643D01*
G01X135660Y639590D02*
Y643840D01*
X135827Y644257D01*
X136160Y644507D01*
X136660Y644590D01*
X137160Y644423D01*
X137410Y644007D01*
G01X136410Y642590D02*
X134743D01*
G01X140343Y642923D02*
Y640590D01*
X140677Y640007D01*
X141177Y639673D01*
X141760Y639590D01*
X142343Y639673D01*
X142843Y640007D01*
X143177Y640590D01*
G01Y639590D02*
Y642923D01*
G01X145943Y639590D02*
Y642923D01*
G01Y642090D02*
X146277Y642507D01*
X146777Y642840D01*
X147443Y642923D01*
X148027Y642840D01*
X148527Y642507D01*
X148777Y641923D01*
Y639590D01*
G01X154293Y642507D02*
X153710Y642840D01*
X153210Y642923D01*
X152543Y642757D01*
X152043Y642423D01*
X151710Y641840D01*
X151627Y641257D01*
X151710Y640673D01*
X152043Y640173D01*
X152543Y639757D01*
X153210Y639590D01*
X153793Y639757D01*
X154293Y640090D01*
G01X158560Y644590D02*
Y639590D01*
G01X157393Y642923D02*
X159727D01*
G01X164160D02*
Y639590D01*
G01Y644257D02*
X163993Y644340D01*
Y644507D01*
X164160Y644590D01*
X164327Y644507D01*
Y644340D01*
X164160Y644257D01*
G01X169760Y639590D02*
X169260Y639673D01*
X168760Y640007D01*
X168427Y640590D01*
X168260Y641257D01*
X168427Y641923D01*
X168760Y642507D01*
X169260Y642840D01*
X169760Y642923D01*
X170260Y642840D01*
X170760Y642507D01*
X171093Y641923D01*
X171177Y641257D01*
X171093Y640590D01*
X170760Y640007D01*
X170260Y639673D01*
X169760Y639590D01*
G01X173943D02*
Y642923D01*
G01Y642090D02*
X174277Y642507D01*
X174777Y642840D01*
X175443Y642923D01*
X176027Y642840D01*
X176527Y642507D01*
X176777Y641923D01*
Y639590D01*
G01X182460D02*
Y642923D01*
G01Y642340D02*
X182127Y642673D01*
X181627Y642840D01*
X181043Y642923D01*
X180460Y642757D01*
X179960Y642423D01*
X179627Y641923D01*
X179460Y641257D01*
X179627Y640590D01*
X179960Y640090D01*
X180460Y639757D01*
X181043Y639590D01*
X181627Y639673D01*
X182127Y639923D01*
X182460Y640257D01*
G01X186560Y639590D02*
Y644590D01*
G01X196260Y637923D02*
Y642923D01*
G01Y642173D02*
X196677Y642590D01*
X197093Y642840D01*
X197760Y642923D01*
X198343Y642840D01*
X198927Y642423D01*
X199177Y641840D01*
X199260Y641257D01*
X199177Y640673D01*
X198927Y640090D01*
X198427Y639757D01*
X197760Y639590D01*
X197177Y639673D01*
X196593Y639923D01*
X196260Y640257D01*
G01X204860Y639590D02*
Y642923D01*
G01Y642340D02*
X204527Y642673D01*
X204027Y642840D01*
X203443Y642923D01*
X202860Y642757D01*
X202360Y642423D01*
X202027Y641923D01*
X201860Y641257D01*
X202027Y640590D01*
X202360Y640090D01*
X202860Y639757D01*
X203443Y639590D01*
X204027Y639673D01*
X204527Y639923D01*
X204860Y640257D01*
G01X210460Y644590D02*
Y639590D01*
G01Y640340D02*
X210127Y639923D01*
X209627Y639673D01*
X209043Y639590D01*
X208377Y639757D01*
X207877Y640173D01*
X207543Y640673D01*
X207460Y641257D01*
X207543Y641840D01*
X207877Y642340D01*
X208377Y642757D01*
X209043Y642923D01*
X209627Y642840D01*
X210043Y642673D01*
X210460Y642340D01*
G01X103500Y614000D02*
X694500D01*
G01X103500Y629000D02*
X694500D01*
G01X160333Y668083D02*
X159833Y668333D01*
X159250Y668500D01*
X158583D01*
X157833Y668250D01*
X157250Y667833D01*
X156833Y667333D01*
X156500Y666500D01*
X156417Y665750D01*
X156583Y665000D01*
X156833Y664500D01*
X157333Y664000D01*
X157917Y663667D01*
X158500Y663500D01*
X159083D01*
X159667Y663667D01*
X160167Y663917D01*
X160583Y664250D01*
G01X164100Y663500D02*
Y668500D01*
G01X171200Y663500D02*
Y666833D01*
G01Y666250D02*
X170867Y666583D01*
X170367Y666750D01*
X169783Y666833D01*
X169200Y666667D01*
X168700Y666333D01*
X168367Y665833D01*
X168200Y665167D01*
X168367Y664500D01*
X168700Y664000D01*
X169200Y663667D01*
X169783Y663500D01*
X170367Y663583D01*
X170867Y663833D01*
X171200Y664167D01*
G01X174050Y664083D02*
X174467Y663750D01*
X175050Y663500D01*
X175550D01*
X176050Y663667D01*
X176383Y663917D01*
X176550Y664250D01*
X176467Y664750D01*
X176133Y665000D01*
X174633Y665500D01*
X174300Y666083D01*
X174467Y666500D01*
X174800Y666750D01*
X175300Y666833D01*
X175800Y666750D01*
X176300Y666500D01*
G01X179650Y664083D02*
X180067Y663750D01*
X180650Y663500D01*
X181150D01*
X181650Y663667D01*
X181983Y663917D01*
X182150Y664250D01*
X182067Y664750D01*
X181733Y665000D01*
X180233Y665500D01*
X179900Y666083D01*
X180067Y666500D01*
X180400Y666750D01*
X180900Y666833D01*
X181400Y666750D01*
X181900Y666500D01*
G01X186500Y666833D02*
Y663500D01*
G01Y668167D02*
X186333Y668250D01*
Y668417D01*
X186500Y668500D01*
X186667Y668417D01*
Y668250D01*
X186500Y668167D01*
G01X191600Y663500D02*
Y667750D01*
X191767Y668167D01*
X192100Y668417D01*
X192600Y668500D01*
X193100Y668333D01*
X193350Y667917D01*
G01X192350Y666500D02*
X190683D01*
G01X195950Y662000D02*
X196450Y661833D01*
X197117Y662000D01*
X197533Y662333D01*
X197867Y662750D01*
X198367Y664083D01*
X199450Y666833D01*
G01X196783D02*
X198367Y664083D01*
G01X262500Y-69500D02*
Y439000D01*
G01Y237500D02*
X694500D01*
G01X262500Y290500D02*
X694500D01*
G01X262500Y397000D02*
Y679000D01*
G01Y479000D02*
X694500D01*
G01X262500Y494000D02*
X694500D01*
G01X262500Y509000D02*
X694500D01*
G01X262500Y524000D02*
X694500D01*
G01X262500Y539000D02*
X694500D01*
G01X262500Y554000D02*
X694500D01*
G01X262500Y569000D02*
X694500D01*
G01X274000Y-63500D02*
Y-60167D01*
G01Y-60750D02*
X273667Y-60417D01*
X273167Y-60250D01*
X272583Y-60167D01*
X272000Y-60333D01*
X271500Y-60667D01*
X271167Y-61167D01*
X271000Y-61833D01*
X271167Y-62500D01*
X271500Y-63000D01*
X272000Y-63333D01*
X272583Y-63500D01*
X273167Y-63417D01*
X273667Y-63167D01*
X274000Y-62833D01*
G01X279600Y-58500D02*
Y-63500D01*
G01Y-62750D02*
X279267Y-63167D01*
X278767Y-63417D01*
X278183Y-63500D01*
X277517Y-63333D01*
X277017Y-62917D01*
X276683Y-62417D01*
X276600Y-61833D01*
X276683Y-61250D01*
X277017Y-60750D01*
X277517Y-60333D01*
X278183Y-60167D01*
X278767Y-60250D01*
X279183Y-60417D01*
X279600Y-60750D01*
G01X285200Y-58500D02*
Y-63500D01*
G01Y-62750D02*
X284867Y-63167D01*
X284367Y-63417D01*
X283783Y-63500D01*
X283117Y-63333D01*
X282617Y-62917D01*
X282283Y-62417D01*
X282200Y-61833D01*
X282283Y-61250D01*
X282617Y-60750D01*
X283117Y-60333D01*
X283783Y-60167D01*
X284367Y-60250D01*
X284783Y-60417D01*
X285200Y-60750D01*
G01X293650Y-62917D02*
X294067Y-63250D01*
X294650Y-63500D01*
X295150D01*
X295650Y-63333D01*
X295983Y-63083D01*
X296150Y-62750D01*
X296067Y-62250D01*
X295733Y-62000D01*
X294233Y-61500D01*
X293900Y-60917D01*
X294067Y-60500D01*
X294400Y-60250D01*
X294900Y-60167D01*
X295400Y-60250D01*
X295900Y-60500D01*
G01X299083Y-60167D02*
Y-62500D01*
X299417Y-63083D01*
X299917Y-63417D01*
X300500Y-63500D01*
X301083Y-63417D01*
X301583Y-63083D01*
X301917Y-62500D01*
G01Y-63500D02*
Y-60167D01*
G01X304600Y-65167D02*
Y-60167D01*
G01Y-60917D02*
X305017Y-60500D01*
X305433Y-60250D01*
X306100Y-60167D01*
X306683Y-60250D01*
X307267Y-60667D01*
X307517Y-61250D01*
X307600Y-61833D01*
X307517Y-62417D01*
X307267Y-63000D01*
X306767Y-63333D01*
X306100Y-63500D01*
X305517Y-63417D01*
X304933Y-63167D01*
X304600Y-62833D01*
G01X310200Y-65167D02*
Y-60167D01*
G01Y-60917D02*
X310617Y-60500D01*
X311033Y-60250D01*
X311700Y-60167D01*
X312283Y-60250D01*
X312867Y-60667D01*
X313117Y-61250D01*
X313200Y-61833D01*
X313117Y-62417D01*
X312867Y-63000D01*
X312367Y-63333D01*
X311700Y-63500D01*
X311117Y-63417D01*
X310533Y-63167D01*
X310200Y-62833D01*
G01X317300Y-63500D02*
Y-58500D01*
G01X322900Y-60167D02*
Y-63500D01*
G01Y-58833D02*
X322733Y-58750D01*
Y-58583D01*
X322900Y-58500D01*
X323067Y-58583D01*
Y-58750D01*
X322900Y-58833D01*
G01X327250Y-61250D02*
X329917D01*
X329667Y-60667D01*
X329250Y-60333D01*
X328667Y-60167D01*
X328083Y-60250D01*
X327583Y-60500D01*
X327250Y-61083D01*
X327083Y-61583D01*
Y-62083D01*
X327250Y-62583D01*
X327667Y-63083D01*
X328167Y-63417D01*
X328750Y-63500D01*
X329333Y-63333D01*
X329917Y-62833D01*
G01X332933Y-63500D02*
Y-60167D01*
G01Y-60833D02*
X333350Y-60500D01*
X333767Y-60250D01*
X334350Y-60167D01*
X334767Y-60250D01*
X335267Y-60500D01*
G01X339700Y-60167D02*
X340533Y-59125D01*
Y-58500D01*
X339908D01*
Y-59125D01*
X340533D01*
G01X344050Y-62917D02*
X344467Y-63250D01*
X345050Y-63500D01*
X345550D01*
X346050Y-63333D01*
X346383Y-63083D01*
X346550Y-62750D01*
X346467Y-62250D01*
X346133Y-62000D01*
X344633Y-61500D01*
X344300Y-60917D01*
X344467Y-60500D01*
X344800Y-60250D01*
X345300Y-60167D01*
X345800Y-60250D01*
X346300Y-60500D01*
G01X354833Y-58500D02*
Y-63500D01*
X358167D01*
G01X362100D02*
X361600Y-63417D01*
X361100Y-63083D01*
X360767Y-62500D01*
X360600Y-61833D01*
X360767Y-61167D01*
X361100Y-60583D01*
X361600Y-60250D01*
X362100Y-60167D01*
X362600Y-60250D01*
X363100Y-60583D01*
X363433Y-61167D01*
X363517Y-61833D01*
X363433Y-62500D01*
X363100Y-63083D01*
X362600Y-63417D01*
X362100Y-63500D01*
G01X366533Y-64750D02*
X367117Y-65083D01*
X367783Y-65167D01*
X368367Y-65083D01*
X368867Y-64667D01*
X369200Y-64083D01*
Y-60167D01*
G01Y-60833D02*
X368867Y-60500D01*
X368367Y-60250D01*
X367783Y-60167D01*
X367117Y-60333D01*
X366700Y-60667D01*
X366367Y-61250D01*
X366200Y-61833D01*
X366283Y-62333D01*
X366617Y-62917D01*
X367117Y-63333D01*
X367783Y-63500D01*
X368283Y-63417D01*
X368867Y-63083D01*
X369200Y-62750D01*
G01X373300Y-63500D02*
X372800Y-63417D01*
X372300Y-63083D01*
X371967Y-62500D01*
X371800Y-61833D01*
X371967Y-61167D01*
X372300Y-60583D01*
X372800Y-60250D01*
X373300Y-60167D01*
X373800Y-60250D01*
X374300Y-60583D01*
X374633Y-61167D01*
X374717Y-61833D01*
X374633Y-62500D01*
X374300Y-63083D01*
X373800Y-63417D01*
X373300Y-63500D01*
G01X386000D02*
Y-60167D01*
G01Y-60750D02*
X385667Y-60417D01*
X385167Y-60250D01*
X384583Y-60167D01*
X384000Y-60333D01*
X383500Y-60667D01*
X383167Y-61167D01*
X383000Y-61833D01*
X383167Y-62500D01*
X383500Y-63000D01*
X384000Y-63333D01*
X384583Y-63500D01*
X385167Y-63417D01*
X385667Y-63167D01*
X386000Y-62833D01*
G01X388683Y-63500D02*
Y-60167D01*
G01Y-61000D02*
X389017Y-60583D01*
X389517Y-60250D01*
X390183Y-60167D01*
X390767Y-60250D01*
X391267Y-60583D01*
X391517Y-61167D01*
Y-63500D01*
G01X397200Y-58500D02*
Y-63500D01*
G01Y-62750D02*
X396867Y-63167D01*
X396367Y-63417D01*
X395783Y-63500D01*
X395117Y-63333D01*
X394617Y-62917D01*
X394283Y-62417D01*
X394200Y-61833D01*
X394283Y-61250D01*
X394617Y-60750D01*
X395117Y-60333D01*
X395783Y-60167D01*
X396367Y-60250D01*
X396783Y-60417D01*
X397200Y-60750D01*
G01X405067Y-58500D02*
Y-62083D01*
X405400Y-62833D01*
X406067Y-63333D01*
X406900Y-63500D01*
X407733Y-63333D01*
X408400Y-62833D01*
X408733Y-62083D01*
Y-58500D01*
G01X410833D02*
Y-63500D01*
X414167D01*
G01X423200D02*
Y-59250D01*
X423367Y-58833D01*
X423700Y-58583D01*
X424200Y-58500D01*
X424700Y-58667D01*
X424950Y-59083D01*
G01X423950Y-60500D02*
X422283D01*
G01X429300Y-60167D02*
Y-63500D01*
G01Y-58833D02*
X429133Y-58750D01*
Y-58583D01*
X429300Y-58500D01*
X429467Y-58583D01*
Y-58750D01*
X429300Y-58833D01*
G01X434900Y-63500D02*
Y-58500D01*
G01X439250Y-61250D02*
X441917D01*
X441667Y-60667D01*
X441250Y-60333D01*
X440667Y-60167D01*
X440083Y-60250D01*
X439583Y-60500D01*
X439250Y-61083D01*
X439083Y-61583D01*
Y-62083D01*
X439250Y-62583D01*
X439667Y-63083D01*
X440167Y-63417D01*
X440750Y-63500D01*
X441333Y-63333D01*
X441917Y-62833D01*
G01X449783Y-63500D02*
Y-58500D01*
X453617Y-63500D01*
Y-58500D01*
G01X455883Y-60167D02*
Y-62500D01*
X456217Y-63083D01*
X456717Y-63417D01*
X457300Y-63500D01*
X457883Y-63417D01*
X458383Y-63083D01*
X458717Y-62500D01*
G01Y-63500D02*
Y-60167D01*
G01X460400Y-63500D02*
Y-60167D01*
G01Y-61083D02*
X460650Y-60667D01*
X461067Y-60333D01*
X461650Y-60167D01*
X462233Y-60333D01*
X462650Y-60667D01*
X462900Y-61083D01*
Y-63500D01*
G01Y-61083D02*
X463150Y-60667D01*
X463567Y-60333D01*
X464150Y-60167D01*
X464733Y-60333D01*
X465150Y-60667D01*
X465400Y-61167D01*
Y-63500D01*
G01X467000D02*
Y-58500D01*
G01Y-61000D02*
X467417Y-60500D01*
X467917Y-60250D01*
X468417Y-60167D01*
X469167Y-60333D01*
X469667Y-60667D01*
X470000Y-61250D01*
Y-61917D01*
X469833Y-62583D01*
X469500Y-63083D01*
X468917Y-63417D01*
X468417Y-63500D01*
X467917Y-63417D01*
X467417Y-63167D01*
X467000Y-62750D01*
G01X472850Y-61250D02*
X475517D01*
X475267Y-60667D01*
X474850Y-60333D01*
X474267Y-60167D01*
X473683Y-60250D01*
X473183Y-60500D01*
X472850Y-61083D01*
X472683Y-61583D01*
Y-62083D01*
X472850Y-62583D01*
X473267Y-63083D01*
X473767Y-63417D01*
X474350Y-63500D01*
X474933Y-63333D01*
X475517Y-62833D01*
G01X478533Y-63500D02*
Y-60167D01*
G01Y-60833D02*
X478950Y-60500D01*
X479367Y-60250D01*
X479950Y-60167D01*
X480367Y-60250D01*
X480867Y-60500D01*
G01X490900Y-60167D02*
Y-63500D01*
G01Y-58833D02*
X490733Y-58750D01*
Y-58583D01*
X490900Y-58500D01*
X491067Y-58583D01*
Y-58750D01*
X490900Y-58833D01*
G01X495083Y-63500D02*
Y-60167D01*
G01Y-61000D02*
X495417Y-60583D01*
X495917Y-60250D01*
X496583Y-60167D01*
X497167Y-60250D01*
X497667Y-60583D01*
X497917Y-61167D01*
Y-63500D01*
G01X506450Y-62917D02*
X506867Y-63250D01*
X507450Y-63500D01*
X507950D01*
X508450Y-63333D01*
X508783Y-63083D01*
X508950Y-62750D01*
X508867Y-62250D01*
X508533Y-62000D01*
X507033Y-61500D01*
X506700Y-60917D01*
X506867Y-60500D01*
X507200Y-60250D01*
X507700Y-60167D01*
X508200Y-60250D01*
X508700Y-60500D01*
G01X513300Y-60167D02*
Y-63500D01*
G01Y-58833D02*
X513133Y-58750D01*
Y-58583D01*
X513300Y-58500D01*
X513467Y-58583D01*
Y-58750D01*
X513300Y-58833D01*
G01X518900Y-63500D02*
Y-58500D01*
G01X523083Y-63500D02*
Y-58500D01*
G01X525750Y-60167D02*
X523083Y-62083D01*
G01X524167Y-61333D02*
X525917Y-63500D01*
G01X528850Y-62917D02*
X529267Y-63250D01*
X529850Y-63500D01*
X530350D01*
X530850Y-63333D01*
X531183Y-63083D01*
X531350Y-62750D01*
X531267Y-62250D01*
X530933Y-62000D01*
X529433Y-61500D01*
X529100Y-60917D01*
X529267Y-60500D01*
X529600Y-60250D01*
X530100Y-60167D01*
X530600Y-60250D01*
X531100Y-60500D01*
G01X537033Y-60583D02*
X536450Y-60250D01*
X535950Y-60167D01*
X535283Y-60333D01*
X534783Y-60667D01*
X534450Y-61250D01*
X534367Y-61833D01*
X534450Y-62417D01*
X534783Y-62917D01*
X535283Y-63333D01*
X535950Y-63500D01*
X536533Y-63333D01*
X537033Y-63000D01*
G01X540133Y-63500D02*
Y-60167D01*
G01Y-60833D02*
X540550Y-60500D01*
X540967Y-60250D01*
X541550Y-60167D01*
X541967Y-60250D01*
X542467Y-60500D01*
G01X545650Y-61250D02*
X548317D01*
X548067Y-60667D01*
X547650Y-60333D01*
X547067Y-60167D01*
X546483Y-60250D01*
X545983Y-60500D01*
X545650Y-61083D01*
X545483Y-61583D01*
Y-62083D01*
X545650Y-62583D01*
X546067Y-63083D01*
X546567Y-63417D01*
X547150Y-63500D01*
X547733Y-63333D01*
X548317Y-62833D01*
G01X551250Y-61250D02*
X553917D01*
X553667Y-60667D01*
X553250Y-60333D01*
X552667Y-60167D01*
X552083Y-60250D01*
X551583Y-60500D01*
X551250Y-61083D01*
X551083Y-61583D01*
Y-62083D01*
X551250Y-62583D01*
X551667Y-63083D01*
X552167Y-63417D01*
X552750Y-63500D01*
X553333Y-63333D01*
X553917Y-62833D01*
G01X556683Y-63500D02*
Y-60167D01*
G01Y-61000D02*
X557017Y-60583D01*
X557517Y-60250D01*
X558183Y-60167D01*
X558767Y-60250D01*
X559267Y-60583D01*
X559517Y-61167D01*
Y-63500D01*
G01X270750Y-47833D02*
X271417Y-48250D01*
X272167Y-48500D01*
X272833D01*
X273500Y-48250D01*
X274000Y-47833D01*
X274250Y-47250D01*
X274083Y-46667D01*
X273667Y-46167D01*
X272917Y-45833D01*
X271917Y-45667D01*
X271333Y-45333D01*
X271083Y-44750D01*
X271250Y-44167D01*
X271667Y-43750D01*
X272250Y-43500D01*
X272833D01*
X273417Y-43667D01*
X273917Y-44083D01*
G01X278100Y-48500D02*
X277600Y-48417D01*
X277100Y-48083D01*
X276767Y-47500D01*
X276600Y-46833D01*
X276767Y-46167D01*
X277100Y-45583D01*
X277600Y-45250D01*
X278100Y-45167D01*
X278600Y-45250D01*
X279100Y-45583D01*
X279433Y-46167D01*
X279517Y-46833D01*
X279433Y-47500D01*
X279100Y-48083D01*
X278600Y-48417D01*
X278100Y-48500D01*
G01X283700D02*
Y-43500D01*
G01X290800D02*
Y-48500D01*
G01Y-47750D02*
X290467Y-48167D01*
X289967Y-48417D01*
X289383Y-48500D01*
X288717Y-48333D01*
X288217Y-47917D01*
X287883Y-47417D01*
X287800Y-46833D01*
X287883Y-46250D01*
X288217Y-45750D01*
X288717Y-45333D01*
X289383Y-45167D01*
X289967Y-45250D01*
X290383Y-45417D01*
X290800Y-45750D01*
G01X293650Y-46250D02*
X296317D01*
X296067Y-45667D01*
X295650Y-45333D01*
X295067Y-45167D01*
X294483Y-45250D01*
X293983Y-45500D01*
X293650Y-46083D01*
X293483Y-46583D01*
Y-47083D01*
X293650Y-47583D01*
X294067Y-48083D01*
X294567Y-48417D01*
X295150Y-48500D01*
X295733Y-48333D01*
X296317Y-47833D01*
G01X299333Y-48500D02*
Y-45167D01*
G01Y-45833D02*
X299750Y-45500D01*
X300167Y-45250D01*
X300750Y-45167D01*
X301167Y-45250D01*
X301667Y-45500D01*
G01X309200Y-48500D02*
Y-45167D01*
G01Y-46083D02*
X309450Y-45667D01*
X309867Y-45333D01*
X310450Y-45167D01*
X311033Y-45333D01*
X311450Y-45667D01*
X311700Y-46083D01*
Y-48500D01*
G01Y-46083D02*
X311950Y-45667D01*
X312367Y-45333D01*
X312950Y-45167D01*
X313533Y-45333D01*
X313950Y-45667D01*
X314200Y-46167D01*
Y-48500D01*
G01X318800D02*
Y-45167D01*
G01Y-45750D02*
X318467Y-45417D01*
X317967Y-45250D01*
X317383Y-45167D01*
X316800Y-45333D01*
X316300Y-45667D01*
X315967Y-46167D01*
X315800Y-46833D01*
X315967Y-47500D01*
X316300Y-48000D01*
X316800Y-48333D01*
X317383Y-48500D01*
X317967Y-48417D01*
X318467Y-48167D01*
X318800Y-47833D01*
G01X321650Y-47917D02*
X322067Y-48250D01*
X322650Y-48500D01*
X323150D01*
X323650Y-48333D01*
X323983Y-48083D01*
X324150Y-47750D01*
X324067Y-47250D01*
X323733Y-47000D01*
X322233Y-46500D01*
X321900Y-45917D01*
X322067Y-45500D01*
X322400Y-45250D01*
X322900Y-45167D01*
X323400Y-45250D01*
X323900Y-45500D01*
G01X327083Y-48500D02*
Y-43500D01*
G01X329750Y-45167D02*
X327083Y-47083D01*
G01X328167Y-46333D02*
X329917Y-48500D01*
G01X339700Y-43500D02*
Y-48500D01*
G01X338533Y-45167D02*
X340867D01*
G01X343883Y-48500D02*
Y-43500D01*
G01Y-45917D02*
X344300Y-45500D01*
X344717Y-45250D01*
X345383Y-45167D01*
X345883Y-45250D01*
X346467Y-45583D01*
X346717Y-46083D01*
Y-48500D01*
G01X350900Y-45167D02*
Y-48500D01*
G01Y-43833D02*
X350733Y-43750D01*
Y-43583D01*
X350900Y-43500D01*
X351067Y-43583D01*
Y-43750D01*
X350900Y-43833D01*
G01X357833Y-45583D02*
X357250Y-45250D01*
X356750Y-45167D01*
X356083Y-45333D01*
X355583Y-45667D01*
X355250Y-46250D01*
X355167Y-46833D01*
X355250Y-47417D01*
X355583Y-47917D01*
X356083Y-48333D01*
X356750Y-48500D01*
X357333Y-48333D01*
X357833Y-48000D01*
G01X360683Y-48500D02*
Y-43500D01*
G01X363350Y-45167D02*
X360683Y-47083D01*
G01X361767Y-46333D02*
X363517Y-48500D01*
G01X366283D02*
Y-45167D01*
G01Y-46000D02*
X366617Y-45583D01*
X367117Y-45250D01*
X367783Y-45167D01*
X368367Y-45250D01*
X368867Y-45583D01*
X369117Y-46167D01*
Y-48500D01*
G01X372050Y-46250D02*
X374717D01*
X374467Y-45667D01*
X374050Y-45333D01*
X373467Y-45167D01*
X372883Y-45250D01*
X372383Y-45500D01*
X372050Y-46083D01*
X371883Y-46583D01*
Y-47083D01*
X372050Y-47583D01*
X372467Y-48083D01*
X372967Y-48417D01*
X373550Y-48500D01*
X374133Y-48333D01*
X374717Y-47833D01*
G01X377650Y-47917D02*
X378067Y-48250D01*
X378650Y-48500D01*
X379150D01*
X379650Y-48333D01*
X379983Y-48083D01*
X380150Y-47750D01*
X380067Y-47250D01*
X379733Y-47000D01*
X378233Y-46500D01*
X377900Y-45917D01*
X378067Y-45500D01*
X378400Y-45250D01*
X378900Y-45167D01*
X379400Y-45250D01*
X379900Y-45500D01*
G01X383250Y-47917D02*
X383667Y-48250D01*
X384250Y-48500D01*
X384750D01*
X385250Y-48333D01*
X385583Y-48083D01*
X385750Y-47750D01*
X385667Y-47250D01*
X385333Y-47000D01*
X383833Y-46500D01*
X383500Y-45917D01*
X383667Y-45500D01*
X384000Y-45250D01*
X384500Y-45167D01*
X385000Y-45250D01*
X385500Y-45500D01*
G01X394200Y-50167D02*
Y-45167D01*
G01Y-45917D02*
X394617Y-45500D01*
X395033Y-45250D01*
X395700Y-45167D01*
X396283Y-45250D01*
X396867Y-45667D01*
X397117Y-46250D01*
X397200Y-46833D01*
X397117Y-47417D01*
X396867Y-48000D01*
X396367Y-48333D01*
X395700Y-48500D01*
X395117Y-48417D01*
X394533Y-48167D01*
X394200Y-47833D01*
G01X401300Y-48500D02*
Y-43500D01*
G01X405483Y-45167D02*
Y-47500D01*
X405817Y-48083D01*
X406317Y-48417D01*
X406900Y-48500D01*
X407483Y-48417D01*
X407983Y-48083D01*
X408317Y-47500D01*
G01Y-48500D02*
Y-45167D01*
G01X411250Y-47917D02*
X411667Y-48250D01*
X412250Y-48500D01*
X412750D01*
X413250Y-48333D01*
X413583Y-48083D01*
X413750Y-47750D01*
X413667Y-47250D01*
X413333Y-47000D01*
X411833Y-46500D01*
X411500Y-45917D01*
X411667Y-45500D01*
X412000Y-45250D01*
X412500Y-45167D01*
X413000Y-45250D01*
X413500Y-45500D01*
G01X423700Y-48500D02*
Y-43500D01*
G01X428050Y-46250D02*
X430717D01*
X430467Y-45667D01*
X430050Y-45333D01*
X429467Y-45167D01*
X428883Y-45250D01*
X428383Y-45500D01*
X428050Y-46083D01*
X427883Y-46583D01*
Y-47083D01*
X428050Y-47583D01*
X428467Y-48083D01*
X428967Y-48417D01*
X429550Y-48500D01*
X430133Y-48333D01*
X430717Y-47833D01*
G01X433733Y-49750D02*
X434317Y-50083D01*
X434983Y-50167D01*
X435567Y-50083D01*
X436067Y-49667D01*
X436400Y-49083D01*
Y-45167D01*
G01Y-45833D02*
X436067Y-45500D01*
X435567Y-45250D01*
X434983Y-45167D01*
X434317Y-45333D01*
X433900Y-45667D01*
X433567Y-46250D01*
X433400Y-46833D01*
X433483Y-47333D01*
X433817Y-47917D01*
X434317Y-48333D01*
X434983Y-48500D01*
X435483Y-48417D01*
X436067Y-48083D01*
X436400Y-47750D01*
G01X439250Y-46250D02*
X441917D01*
X441667Y-45667D01*
X441250Y-45333D01*
X440667Y-45167D01*
X440083Y-45250D01*
X439583Y-45500D01*
X439250Y-46083D01*
X439083Y-46583D01*
Y-47083D01*
X439250Y-47583D01*
X439667Y-48083D01*
X440167Y-48417D01*
X440750Y-48500D01*
X441333Y-48333D01*
X441917Y-47833D01*
G01X444683Y-48500D02*
Y-45167D01*
G01Y-46000D02*
X445017Y-45583D01*
X445517Y-45250D01*
X446183Y-45167D01*
X446767Y-45250D01*
X447267Y-45583D01*
X447517Y-46167D01*
Y-48500D01*
G01X453200Y-43500D02*
Y-48500D01*
G01Y-47750D02*
X452867Y-48167D01*
X452367Y-48417D01*
X451783Y-48500D01*
X451117Y-48333D01*
X450617Y-47917D01*
X450283Y-47417D01*
X450200Y-46833D01*
X450283Y-46250D01*
X450617Y-45750D01*
X451117Y-45333D01*
X451783Y-45167D01*
X452367Y-45250D01*
X452783Y-45417D01*
X453200Y-45750D01*
G01X462900Y-43500D02*
Y-48500D01*
G01X461733Y-45167D02*
X464067D01*
G01X467083Y-48500D02*
Y-43500D01*
G01Y-45917D02*
X467500Y-45500D01*
X467917Y-45250D01*
X468583Y-45167D01*
X469083Y-45250D01*
X469667Y-45583D01*
X469917Y-46083D01*
Y-48500D01*
G01X474100Y-45167D02*
Y-48500D01*
G01Y-43833D02*
X473933Y-43750D01*
Y-43583D01*
X474100Y-43500D01*
X474267Y-43583D01*
Y-43750D01*
X474100Y-43833D01*
G01X481033Y-45583D02*
X480450Y-45250D01*
X479950Y-45167D01*
X479283Y-45333D01*
X478783Y-45667D01*
X478450Y-46250D01*
X478367Y-46833D01*
X478450Y-47417D01*
X478783Y-47917D01*
X479283Y-48333D01*
X479950Y-48500D01*
X480533Y-48333D01*
X481033Y-48000D01*
G01X483883Y-48500D02*
Y-43500D01*
G01X486550Y-45167D02*
X483883Y-47083D01*
G01X484967Y-46333D02*
X486717Y-48500D01*
G01X489483D02*
Y-45167D01*
G01Y-46000D02*
X489817Y-45583D01*
X490317Y-45250D01*
X490983Y-45167D01*
X491567Y-45250D01*
X492067Y-45583D01*
X492317Y-46167D01*
Y-48500D01*
G01X495250Y-46250D02*
X497917D01*
X497667Y-45667D01*
X497250Y-45333D01*
X496667Y-45167D01*
X496083Y-45250D01*
X495583Y-45500D01*
X495250Y-46083D01*
X495083Y-46583D01*
Y-47083D01*
X495250Y-47583D01*
X495667Y-48083D01*
X496167Y-48417D01*
X496750Y-48500D01*
X497333Y-48333D01*
X497917Y-47833D01*
G01X500850Y-47917D02*
X501267Y-48250D01*
X501850Y-48500D01*
X502350D01*
X502850Y-48333D01*
X503183Y-48083D01*
X503350Y-47750D01*
X503267Y-47250D01*
X502933Y-47000D01*
X501433Y-46500D01*
X501100Y-45917D01*
X501267Y-45500D01*
X501600Y-45250D01*
X502100Y-45167D01*
X502600Y-45250D01*
X503100Y-45500D01*
G01X506450Y-47917D02*
X506867Y-48250D01*
X507450Y-48500D01*
X507950D01*
X508450Y-48333D01*
X508783Y-48083D01*
X508950Y-47750D01*
X508867Y-47250D01*
X508533Y-47000D01*
X507033Y-46500D01*
X506700Y-45917D01*
X506867Y-45500D01*
X507200Y-45250D01*
X507700Y-45167D01*
X508200Y-45250D01*
X508700Y-45500D01*
G01X518900Y-48500D02*
X518400Y-48417D01*
X517900Y-48083D01*
X517567Y-47500D01*
X517400Y-46833D01*
X517567Y-46167D01*
X517900Y-45583D01*
X518400Y-45250D01*
X518900Y-45167D01*
X519400Y-45250D01*
X519900Y-45583D01*
X520233Y-46167D01*
X520317Y-46833D01*
X520233Y-47500D01*
X519900Y-48083D01*
X519400Y-48417D01*
X518900Y-48500D01*
G01X523083D02*
Y-45167D01*
G01Y-46000D02*
X523417Y-45583D01*
X523917Y-45250D01*
X524583Y-45167D01*
X525167Y-45250D01*
X525667Y-45583D01*
X525917Y-46167D01*
Y-48500D01*
G01X535700Y-43500D02*
Y-48500D01*
G01X534533Y-45167D02*
X536867D01*
G01X540133Y-48500D02*
Y-45167D01*
G01Y-45833D02*
X540550Y-45500D01*
X540967Y-45250D01*
X541550Y-45167D01*
X541967Y-45250D01*
X542467Y-45500D01*
G01X548400Y-48500D02*
Y-45167D01*
G01Y-45750D02*
X548067Y-45417D01*
X547567Y-45250D01*
X546983Y-45167D01*
X546400Y-45333D01*
X545900Y-45667D01*
X545567Y-46167D01*
X545400Y-46833D01*
X545567Y-47500D01*
X545900Y-48000D01*
X546400Y-48333D01*
X546983Y-48500D01*
X547567Y-48417D01*
X548067Y-48167D01*
X548400Y-47833D01*
G01X553833Y-45583D02*
X553250Y-45250D01*
X552750Y-45167D01*
X552083Y-45333D01*
X551583Y-45667D01*
X551250Y-46250D01*
X551167Y-46833D01*
X551250Y-47417D01*
X551583Y-47917D01*
X552083Y-48333D01*
X552750Y-48500D01*
X553333Y-48333D01*
X553833Y-48000D01*
G01X556850Y-46250D02*
X559517D01*
X559267Y-45667D01*
X558850Y-45333D01*
X558267Y-45167D01*
X557683Y-45250D01*
X557183Y-45500D01*
X556850Y-46083D01*
X556683Y-46583D01*
Y-47083D01*
X556850Y-47583D01*
X557267Y-48083D01*
X557767Y-48417D01*
X558350Y-48500D01*
X558933Y-48333D01*
X559517Y-47833D01*
G01X563700Y-48667D02*
X563533Y-48583D01*
Y-48417D01*
X563700Y-48333D01*
X563867Y-48417D01*
Y-48583D01*
X563700Y-48667D01*
G01X272500Y-33500D02*
Y-28500D01*
G01X276850Y-31250D02*
X279517D01*
X279267Y-30667D01*
X278850Y-30333D01*
X278267Y-30167D01*
X277683Y-30250D01*
X277183Y-30500D01*
X276850Y-31083D01*
X276683Y-31583D01*
Y-32083D01*
X276850Y-32583D01*
X277267Y-33083D01*
X277767Y-33417D01*
X278350Y-33500D01*
X278933Y-33333D01*
X279517Y-32833D01*
G01X282533Y-34750D02*
X283117Y-35083D01*
X283783Y-35167D01*
X284367Y-35083D01*
X284867Y-34667D01*
X285200Y-34083D01*
Y-30167D01*
G01Y-30833D02*
X284867Y-30500D01*
X284367Y-30250D01*
X283783Y-30167D01*
X283117Y-30333D01*
X282700Y-30667D01*
X282367Y-31250D01*
X282200Y-31833D01*
X282283Y-32333D01*
X282617Y-32917D01*
X283117Y-33333D01*
X283783Y-33500D01*
X284283Y-33417D01*
X284867Y-33083D01*
X285200Y-32750D01*
G01X288050Y-31250D02*
X290717D01*
X290467Y-30667D01*
X290050Y-30333D01*
X289467Y-30167D01*
X288883Y-30250D01*
X288383Y-30500D01*
X288050Y-31083D01*
X287883Y-31583D01*
Y-32083D01*
X288050Y-32583D01*
X288467Y-33083D01*
X288967Y-33417D01*
X289550Y-33500D01*
X290133Y-33333D01*
X290717Y-32833D01*
G01X293483Y-33500D02*
Y-30167D01*
G01Y-31000D02*
X293817Y-30583D01*
X294317Y-30250D01*
X294983Y-30167D01*
X295567Y-30250D01*
X296067Y-30583D01*
X296317Y-31167D01*
Y-33500D01*
G01X302000Y-28500D02*
Y-33500D01*
G01Y-32750D02*
X301667Y-33167D01*
X301167Y-33417D01*
X300583Y-33500D01*
X299917Y-33333D01*
X299417Y-32917D01*
X299083Y-32417D01*
X299000Y-31833D01*
X299083Y-31250D01*
X299417Y-30750D01*
X299917Y-30333D01*
X300583Y-30167D01*
X301167Y-30250D01*
X301583Y-30417D01*
X302000Y-30750D01*
G01X311700Y-28500D02*
Y-33500D01*
G01X310533Y-30167D02*
X312867D01*
G01X315883Y-33500D02*
Y-28500D01*
G01Y-30917D02*
X316300Y-30500D01*
X316717Y-30250D01*
X317383Y-30167D01*
X317883Y-30250D01*
X318467Y-30583D01*
X318717Y-31083D01*
Y-33500D01*
G01X322900Y-30167D02*
Y-33500D01*
G01Y-28833D02*
X322733Y-28750D01*
Y-28583D01*
X322900Y-28500D01*
X323067Y-28583D01*
Y-28750D01*
X322900Y-28833D01*
G01X329833Y-30583D02*
X329250Y-30250D01*
X328750Y-30167D01*
X328083Y-30333D01*
X327583Y-30667D01*
X327250Y-31250D01*
X327167Y-31833D01*
X327250Y-32417D01*
X327583Y-32917D01*
X328083Y-33333D01*
X328750Y-33500D01*
X329333Y-33333D01*
X329833Y-33000D01*
G01X332683Y-33500D02*
Y-28500D01*
G01X335350Y-30167D02*
X332683Y-32083D01*
G01X333767Y-31333D02*
X335517Y-33500D01*
G01X338283D02*
Y-30167D01*
G01Y-31000D02*
X338617Y-30583D01*
X339117Y-30250D01*
X339783Y-30167D01*
X340367Y-30250D01*
X340867Y-30583D01*
X341117Y-31167D01*
Y-33500D01*
G01X344050Y-31250D02*
X346717D01*
X346467Y-30667D01*
X346050Y-30333D01*
X345467Y-30167D01*
X344883Y-30250D01*
X344383Y-30500D01*
X344050Y-31083D01*
X343883Y-31583D01*
Y-32083D01*
X344050Y-32583D01*
X344467Y-33083D01*
X344967Y-33417D01*
X345550Y-33500D01*
X346133Y-33333D01*
X346717Y-32833D01*
G01X349650Y-32917D02*
X350067Y-33250D01*
X350650Y-33500D01*
X351150D01*
X351650Y-33333D01*
X351983Y-33083D01*
X352150Y-32750D01*
X352067Y-32250D01*
X351733Y-32000D01*
X350233Y-31500D01*
X349900Y-30917D01*
X350067Y-30500D01*
X350400Y-30250D01*
X350900Y-30167D01*
X351400Y-30250D01*
X351900Y-30500D01*
G01X355250Y-32917D02*
X355667Y-33250D01*
X356250Y-33500D01*
X356750D01*
X357250Y-33333D01*
X357583Y-33083D01*
X357750Y-32750D01*
X357667Y-32250D01*
X357333Y-32000D01*
X355833Y-31500D01*
X355500Y-30917D01*
X355667Y-30500D01*
X356000Y-30250D01*
X356500Y-30167D01*
X357000Y-30250D01*
X357500Y-30500D01*
G01X367700Y-33500D02*
X367200Y-33417D01*
X366700Y-33083D01*
X366367Y-32500D01*
X366200Y-31833D01*
X366367Y-31167D01*
X366700Y-30583D01*
X367200Y-30250D01*
X367700Y-30167D01*
X368200Y-30250D01*
X368700Y-30583D01*
X369033Y-31167D01*
X369117Y-31833D01*
X369033Y-32500D01*
X368700Y-33083D01*
X368200Y-33417D01*
X367700Y-33500D01*
G01X371883D02*
Y-30167D01*
G01Y-31000D02*
X372217Y-30583D01*
X372717Y-30250D01*
X373383Y-30167D01*
X373967Y-30250D01*
X374467Y-30583D01*
X374717Y-31167D01*
Y-33500D01*
G01X385833Y-30583D02*
X385250Y-30250D01*
X384750Y-30167D01*
X384083Y-30333D01*
X383583Y-30667D01*
X383250Y-31250D01*
X383167Y-31833D01*
X383250Y-32417D01*
X383583Y-32917D01*
X384083Y-33333D01*
X384750Y-33500D01*
X385333Y-33333D01*
X385833Y-33000D01*
G01X390100Y-33500D02*
X389600Y-33417D01*
X389100Y-33083D01*
X388767Y-32500D01*
X388600Y-31833D01*
X388767Y-31167D01*
X389100Y-30583D01*
X389600Y-30250D01*
X390100Y-30167D01*
X390600Y-30250D01*
X391100Y-30583D01*
X391433Y-31167D01*
X391517Y-31833D01*
X391433Y-32500D01*
X391100Y-33083D01*
X390600Y-33417D01*
X390100Y-33500D01*
G01X394200Y-35167D02*
Y-30167D01*
G01Y-30917D02*
X394617Y-30500D01*
X395033Y-30250D01*
X395700Y-30167D01*
X396283Y-30250D01*
X396867Y-30667D01*
X397117Y-31250D01*
X397200Y-31833D01*
X397117Y-32417D01*
X396867Y-33000D01*
X396367Y-33333D01*
X395700Y-33500D01*
X395117Y-33417D01*
X394533Y-33167D01*
X394200Y-32833D01*
G01X399800Y-35167D02*
Y-30167D01*
G01Y-30917D02*
X400217Y-30500D01*
X400633Y-30250D01*
X401300Y-30167D01*
X401883Y-30250D01*
X402467Y-30667D01*
X402717Y-31250D01*
X402800Y-31833D01*
X402717Y-32417D01*
X402467Y-33000D01*
X401967Y-33333D01*
X401300Y-33500D01*
X400717Y-33417D01*
X400133Y-33167D01*
X399800Y-32833D01*
G01X405650Y-31250D02*
X408317D01*
X408067Y-30667D01*
X407650Y-30333D01*
X407067Y-30167D01*
X406483Y-30250D01*
X405983Y-30500D01*
X405650Y-31083D01*
X405483Y-31583D01*
Y-32083D01*
X405650Y-32583D01*
X406067Y-33083D01*
X406567Y-33417D01*
X407150Y-33500D01*
X407733Y-33333D01*
X408317Y-32833D01*
G01X411333Y-33500D02*
Y-30167D01*
G01Y-30833D02*
X411750Y-30500D01*
X412167Y-30250D01*
X412750Y-30167D01*
X413167Y-30250D01*
X413667Y-30500D01*
G01X423283Y-35167D02*
X422450Y-34333D01*
X422033Y-33500D01*
Y-30167D01*
X422450Y-29333D01*
X423283Y-28500D01*
G01X427217Y-30167D02*
X428217Y-33500D01*
X429300Y-30167D01*
X430383Y-33500D01*
X431383Y-30167D01*
G01X433483Y-33500D02*
Y-28500D01*
G01Y-30917D02*
X433900Y-30500D01*
X434317Y-30250D01*
X434983Y-30167D01*
X435483Y-30250D01*
X436067Y-30583D01*
X436317Y-31083D01*
Y-33500D01*
G01X440500Y-30167D02*
Y-33500D01*
G01Y-28833D02*
X440333Y-28750D01*
Y-28583D01*
X440500Y-28500D01*
X440667Y-28583D01*
Y-28750D01*
X440500Y-28833D01*
G01X447433Y-30583D02*
X446850Y-30250D01*
X446350Y-30167D01*
X445683Y-30333D01*
X445183Y-30667D01*
X444850Y-31250D01*
X444767Y-31833D01*
X444850Y-32417D01*
X445183Y-32917D01*
X445683Y-33333D01*
X446350Y-33500D01*
X446933Y-33333D01*
X447433Y-33000D01*
G01X450283Y-33500D02*
Y-28500D01*
G01Y-30917D02*
X450700Y-30500D01*
X451117Y-30250D01*
X451783Y-30167D01*
X452283Y-30250D01*
X452867Y-30583D01*
X453117Y-31083D01*
Y-33500D01*
G01X462900Y-30167D02*
Y-33500D01*
G01Y-28833D02*
X462733Y-28750D01*
Y-28583D01*
X462900Y-28500D01*
X463067Y-28583D01*
Y-28750D01*
X462900Y-28833D01*
G01X467250Y-32917D02*
X467667Y-33250D01*
X468250Y-33500D01*
X468750D01*
X469250Y-33333D01*
X469583Y-33083D01*
X469750Y-32750D01*
X469667Y-32250D01*
X469333Y-32000D01*
X467833Y-31500D01*
X467500Y-30917D01*
X467667Y-30500D01*
X468000Y-30250D01*
X468500Y-30167D01*
X469000Y-30250D01*
X469500Y-30500D01*
G01X478200Y-33500D02*
Y-28500D01*
G01Y-31000D02*
X478617Y-30500D01*
X479117Y-30250D01*
X479617Y-30167D01*
X480367Y-30333D01*
X480867Y-30667D01*
X481200Y-31250D01*
Y-31917D01*
X481033Y-32583D01*
X480700Y-33083D01*
X480117Y-33417D01*
X479617Y-33500D01*
X479117Y-33417D01*
X478617Y-33167D01*
X478200Y-32750D01*
G01X484050Y-31250D02*
X486717D01*
X486467Y-30667D01*
X486050Y-30333D01*
X485467Y-30167D01*
X484883Y-30250D01*
X484383Y-30500D01*
X484050Y-31083D01*
X483883Y-31583D01*
Y-32083D01*
X484050Y-32583D01*
X484467Y-33083D01*
X484967Y-33417D01*
X485550Y-33500D01*
X486133Y-33333D01*
X486717Y-32833D01*
G01X490900Y-28500D02*
Y-33500D01*
G01X489733Y-30167D02*
X492067D01*
G01X496500Y-28500D02*
Y-33500D01*
G01X495333Y-30167D02*
X497667D01*
G01X500850Y-31250D02*
X503517D01*
X503267Y-30667D01*
X502850Y-30333D01*
X502267Y-30167D01*
X501683Y-30250D01*
X501183Y-30500D01*
X500850Y-31083D01*
X500683Y-31583D01*
Y-32083D01*
X500850Y-32583D01*
X501267Y-33083D01*
X501767Y-33417D01*
X502350Y-33500D01*
X502933Y-33333D01*
X503517Y-32833D01*
G01X506533Y-33500D02*
Y-30167D01*
G01Y-30833D02*
X506950Y-30500D01*
X507367Y-30250D01*
X507950Y-30167D01*
X508367Y-30250D01*
X508867Y-30500D01*
G01X513717Y-35167D02*
X514550Y-34333D01*
X514967Y-33500D01*
Y-30167D01*
X514550Y-29333D01*
X513717Y-28500D01*
G01X271250Y-19417D02*
X271667Y-19750D01*
X272250Y-20000D01*
X272750D01*
X273250Y-19833D01*
X273583Y-19583D01*
X273750Y-19250D01*
X273667Y-18750D01*
X273333Y-18500D01*
X271833Y-18000D01*
X271500Y-17417D01*
X271667Y-17000D01*
X272000Y-16750D01*
X272500Y-16667D01*
X273000Y-16750D01*
X273500Y-17000D01*
G01X278100Y-20000D02*
X277600Y-19917D01*
X277100Y-19583D01*
X276767Y-19000D01*
X276600Y-18333D01*
X276767Y-17667D01*
X277100Y-17083D01*
X277600Y-16750D01*
X278100Y-16667D01*
X278600Y-16750D01*
X279100Y-17083D01*
X279433Y-17667D01*
X279517Y-18333D01*
X279433Y-19000D01*
X279100Y-19583D01*
X278600Y-19917D01*
X278100Y-20000D01*
G01X283700D02*
Y-15000D01*
G01X290800D02*
Y-20000D01*
G01Y-19250D02*
X290467Y-19667D01*
X289967Y-19917D01*
X289383Y-20000D01*
X288717Y-19833D01*
X288217Y-19417D01*
X287883Y-18917D01*
X287800Y-18333D01*
X287883Y-17750D01*
X288217Y-17250D01*
X288717Y-16833D01*
X289383Y-16667D01*
X289967Y-16750D01*
X290383Y-16917D01*
X290800Y-17250D01*
G01X293650Y-17750D02*
X296317D01*
X296067Y-17167D01*
X295650Y-16833D01*
X295067Y-16667D01*
X294483Y-16750D01*
X293983Y-17000D01*
X293650Y-17583D01*
X293483Y-18083D01*
Y-18583D01*
X293650Y-19083D01*
X294067Y-19583D01*
X294567Y-19917D01*
X295150Y-20000D01*
X295733Y-19833D01*
X296317Y-19333D01*
G01X299333Y-20000D02*
Y-16667D01*
G01Y-17333D02*
X299750Y-17000D01*
X300167Y-16750D01*
X300750Y-16667D01*
X301167Y-16750D01*
X301667Y-17000D01*
G01X309200Y-20000D02*
Y-16667D01*
G01Y-17583D02*
X309450Y-17167D01*
X309867Y-16833D01*
X310450Y-16667D01*
X311033Y-16833D01*
X311450Y-17167D01*
X311700Y-17583D01*
Y-20000D01*
G01Y-17583D02*
X311950Y-17167D01*
X312367Y-16833D01*
X312950Y-16667D01*
X313533Y-16833D01*
X313950Y-17167D01*
X314200Y-17667D01*
Y-20000D01*
G01X318800D02*
Y-16667D01*
G01Y-17250D02*
X318467Y-16917D01*
X317967Y-16750D01*
X317383Y-16667D01*
X316800Y-16833D01*
X316300Y-17167D01*
X315967Y-17667D01*
X315800Y-18333D01*
X315967Y-19000D01*
X316300Y-19500D01*
X316800Y-19833D01*
X317383Y-20000D01*
X317967Y-19917D01*
X318467Y-19667D01*
X318800Y-19333D01*
G01X321650Y-19417D02*
X322067Y-19750D01*
X322650Y-20000D01*
X323150D01*
X323650Y-19833D01*
X323983Y-19583D01*
X324150Y-19250D01*
X324067Y-18750D01*
X323733Y-18500D01*
X322233Y-18000D01*
X321900Y-17417D01*
X322067Y-17000D01*
X322400Y-16750D01*
X322900Y-16667D01*
X323400Y-16750D01*
X323900Y-17000D01*
G01X327083Y-20000D02*
Y-15000D01*
G01X329750Y-16667D02*
X327083Y-18583D01*
G01X328167Y-17833D02*
X329917Y-20000D01*
G01X339700Y-15000D02*
Y-20000D01*
G01X338533Y-16667D02*
X340867D01*
G01X343883Y-20000D02*
Y-15000D01*
G01Y-17417D02*
X344300Y-17000D01*
X344717Y-16750D01*
X345383Y-16667D01*
X345883Y-16750D01*
X346467Y-17083D01*
X346717Y-17583D01*
Y-20000D01*
G01X350900Y-16667D02*
Y-20000D01*
G01Y-15333D02*
X350733Y-15250D01*
Y-15083D01*
X350900Y-15000D01*
X351067Y-15083D01*
Y-15250D01*
X350900Y-15333D01*
G01X357833Y-17083D02*
X357250Y-16750D01*
X356750Y-16667D01*
X356083Y-16833D01*
X355583Y-17167D01*
X355250Y-17750D01*
X355167Y-18333D01*
X355250Y-18917D01*
X355583Y-19417D01*
X356083Y-19833D01*
X356750Y-20000D01*
X357333Y-19833D01*
X357833Y-19500D01*
G01X360683Y-20000D02*
Y-15000D01*
G01X363350Y-16667D02*
X360683Y-18583D01*
G01X361767Y-17833D02*
X363517Y-20000D01*
G01X366283D02*
Y-16667D01*
G01Y-17500D02*
X366617Y-17083D01*
X367117Y-16750D01*
X367783Y-16667D01*
X368367Y-16750D01*
X368867Y-17083D01*
X369117Y-17667D01*
Y-20000D01*
G01X372050Y-17750D02*
X374717D01*
X374467Y-17167D01*
X374050Y-16833D01*
X373467Y-16667D01*
X372883Y-16750D01*
X372383Y-17000D01*
X372050Y-17583D01*
X371883Y-18083D01*
Y-18583D01*
X372050Y-19083D01*
X372467Y-19583D01*
X372967Y-19917D01*
X373550Y-20000D01*
X374133Y-19833D01*
X374717Y-19333D01*
G01X377650Y-19417D02*
X378067Y-19750D01*
X378650Y-20000D01*
X379150D01*
X379650Y-19833D01*
X379983Y-19583D01*
X380150Y-19250D01*
X380067Y-18750D01*
X379733Y-18500D01*
X378233Y-18000D01*
X377900Y-17417D01*
X378067Y-17000D01*
X378400Y-16750D01*
X378900Y-16667D01*
X379400Y-16750D01*
X379900Y-17000D01*
G01X383250Y-19417D02*
X383667Y-19750D01*
X384250Y-20000D01*
X384750D01*
X385250Y-19833D01*
X385583Y-19583D01*
X385750Y-19250D01*
X385667Y-18750D01*
X385333Y-18500D01*
X383833Y-18000D01*
X383500Y-17417D01*
X383667Y-17000D01*
X384000Y-16750D01*
X384500Y-16667D01*
X385000Y-16750D01*
X385500Y-17000D01*
G01X264000Y-39500D02*
X694500D01*
G01X272500Y0D02*
Y-5000D01*
G01X270583Y0D02*
X274417D01*
G01X276683Y-5000D02*
Y0D01*
G01Y-2417D02*
X277100Y-2000D01*
X277517Y-1750D01*
X278183Y-1667D01*
X278683Y-1750D01*
X279267Y-2083D01*
X279517Y-2583D01*
Y-5000D01*
G01X282450Y-2750D02*
X285117D01*
X284867Y-2167D01*
X284450Y-1833D01*
X283867Y-1667D01*
X283283Y-1750D01*
X282783Y-2000D01*
X282450Y-2583D01*
X282283Y-3083D01*
Y-3583D01*
X282450Y-4083D01*
X282867Y-4583D01*
X283367Y-4917D01*
X283950Y-5000D01*
X284533Y-4833D01*
X285117Y-4333D01*
G01X294900Y-5000D02*
Y0D01*
G01X302000Y-5000D02*
Y-1667D01*
G01Y-2250D02*
X301667Y-1917D01*
X301167Y-1750D01*
X300583Y-1667D01*
X300000Y-1833D01*
X299500Y-2167D01*
X299167Y-2667D01*
X299000Y-3333D01*
X299167Y-4000D01*
X299500Y-4500D01*
X300000Y-4833D01*
X300583Y-5000D01*
X301167Y-4917D01*
X301667Y-4667D01*
X302000Y-4333D01*
G01X304933Y-5000D02*
Y-1667D01*
G01Y-2333D02*
X305350Y-2000D01*
X305767Y-1750D01*
X306350Y-1667D01*
X306767Y-1750D01*
X307267Y-2000D01*
G01X310533Y-6250D02*
X311117Y-6583D01*
X311783Y-6667D01*
X312367Y-6583D01*
X312867Y-6167D01*
X313200Y-5583D01*
Y-1667D01*
G01Y-2333D02*
X312867Y-2000D01*
X312367Y-1750D01*
X311783Y-1667D01*
X311117Y-1833D01*
X310700Y-2167D01*
X310367Y-2750D01*
X310200Y-3333D01*
X310283Y-3833D01*
X310617Y-4417D01*
X311117Y-4833D01*
X311783Y-5000D01*
X312283Y-4917D01*
X312867Y-4583D01*
X313200Y-4250D01*
G01X316050Y-2750D02*
X318717D01*
X318467Y-2167D01*
X318050Y-1833D01*
X317467Y-1667D01*
X316883Y-1750D01*
X316383Y-2000D01*
X316050Y-2583D01*
X315883Y-3083D01*
Y-3583D01*
X316050Y-4083D01*
X316467Y-4583D01*
X316967Y-4917D01*
X317550Y-5000D01*
X318133Y-4833D01*
X318717Y-4333D01*
G01X321650Y-4417D02*
X322067Y-4750D01*
X322650Y-5000D01*
X323150D01*
X323650Y-4833D01*
X323983Y-4583D01*
X324150Y-4250D01*
X324067Y-3750D01*
X323733Y-3500D01*
X322233Y-3000D01*
X321900Y-2417D01*
X322067Y-2000D01*
X322400Y-1750D01*
X322900Y-1667D01*
X323400Y-1750D01*
X323900Y-2000D01*
G01X328500Y0D02*
Y-5000D01*
G01X327333Y-1667D02*
X329667D01*
G01X341200Y0D02*
Y-5000D01*
G01Y-4250D02*
X340867Y-4667D01*
X340367Y-4917D01*
X339783Y-5000D01*
X339117Y-4833D01*
X338617Y-4417D01*
X338283Y-3917D01*
X338200Y-3333D01*
X338283Y-2750D01*
X338617Y-2250D01*
X339117Y-1833D01*
X339783Y-1667D01*
X340367Y-1750D01*
X340783Y-1917D01*
X341200Y-2250D01*
G01X345300Y-1667D02*
Y-5000D01*
G01Y-333D02*
X345133Y-250D01*
Y-83D01*
X345300Y0D01*
X345467Y-83D01*
Y-250D01*
X345300Y-333D01*
G01X348400Y-5000D02*
Y-1667D01*
G01Y-2583D02*
X348650Y-2167D01*
X349067Y-1833D01*
X349650Y-1667D01*
X350233Y-1833D01*
X350650Y-2167D01*
X350900Y-2583D01*
Y-5000D01*
G01Y-2583D02*
X351150Y-2167D01*
X351567Y-1833D01*
X352150Y-1667D01*
X352733Y-1833D01*
X353150Y-2167D01*
X353400Y-2667D01*
Y-5000D01*
G01X355250Y-2750D02*
X357917D01*
X357667Y-2167D01*
X357250Y-1833D01*
X356667Y-1667D01*
X356083Y-1750D01*
X355583Y-2000D01*
X355250Y-2583D01*
X355083Y-3083D01*
Y-3583D01*
X355250Y-4083D01*
X355667Y-4583D01*
X356167Y-4917D01*
X356750Y-5000D01*
X357333Y-4833D01*
X357917Y-4333D01*
G01X360683Y-5000D02*
Y-1667D01*
G01Y-2500D02*
X361017Y-2083D01*
X361517Y-1750D01*
X362183Y-1667D01*
X362767Y-1750D01*
X363267Y-2083D01*
X363517Y-2667D01*
Y-5000D01*
G01X366450Y-4417D02*
X366867Y-4750D01*
X367450Y-5000D01*
X367950D01*
X368450Y-4833D01*
X368783Y-4583D01*
X368950Y-4250D01*
X368867Y-3750D01*
X368533Y-3500D01*
X367033Y-3000D01*
X366700Y-2417D01*
X366867Y-2000D01*
X367200Y-1750D01*
X367700Y-1667D01*
X368200Y-1750D01*
X368700Y-2000D01*
G01X373300Y-1667D02*
Y-5000D01*
G01Y-333D02*
X373133Y-250D01*
Y-83D01*
X373300Y0D01*
X373467Y-83D01*
Y-250D01*
X373300Y-333D01*
G01X378900Y-5000D02*
X378400Y-4917D01*
X377900Y-4583D01*
X377567Y-4000D01*
X377400Y-3333D01*
X377567Y-2667D01*
X377900Y-2083D01*
X378400Y-1750D01*
X378900Y-1667D01*
X379400Y-1750D01*
X379900Y-2083D01*
X380233Y-2667D01*
X380317Y-3333D01*
X380233Y-4000D01*
X379900Y-4583D01*
X379400Y-4917D01*
X378900Y-5000D01*
G01X383083D02*
Y-1667D01*
G01Y-2500D02*
X383417Y-2083D01*
X383917Y-1750D01*
X384583Y-1667D01*
X385167Y-1750D01*
X385667Y-2083D01*
X385917Y-2667D01*
Y-5000D01*
G01X395700D02*
X395200Y-4917D01*
X394700Y-4583D01*
X394367Y-4000D01*
X394200Y-3333D01*
X394367Y-2667D01*
X394700Y-2083D01*
X395200Y-1750D01*
X395700Y-1667D01*
X396200Y-1750D01*
X396700Y-2083D01*
X397033Y-2667D01*
X397117Y-3333D01*
X397033Y-4000D01*
X396700Y-4583D01*
X396200Y-4917D01*
X395700Y-5000D01*
G01X400800D02*
Y-750D01*
X400967Y-333D01*
X401300Y-83D01*
X401800Y0D01*
X402300Y-167D01*
X402550Y-583D01*
G01X401550Y-2000D02*
X399883D01*
G01X411000Y-6667D02*
Y-1667D01*
G01Y-2417D02*
X411417Y-2000D01*
X411833Y-1750D01*
X412500Y-1667D01*
X413083Y-1750D01*
X413667Y-2167D01*
X413917Y-2750D01*
X414000Y-3333D01*
X413917Y-3917D01*
X413667Y-4500D01*
X413167Y-4833D01*
X412500Y-5000D01*
X411917Y-4917D01*
X411333Y-4667D01*
X411000Y-4333D01*
G01X419600Y-5000D02*
Y-1667D01*
G01Y-2250D02*
X419267Y-1917D01*
X418767Y-1750D01*
X418183Y-1667D01*
X417600Y-1833D01*
X417100Y-2167D01*
X416767Y-2667D01*
X416600Y-3333D01*
X416767Y-4000D01*
X417100Y-4500D01*
X417600Y-4833D01*
X418183Y-5000D01*
X418767Y-4917D01*
X419267Y-4667D01*
X419600Y-4333D01*
G01X425200Y0D02*
Y-5000D01*
G01Y-4250D02*
X424867Y-4667D01*
X424367Y-4917D01*
X423783Y-5000D01*
X423117Y-4833D01*
X422617Y-4417D01*
X422283Y-3917D01*
X422200Y-3333D01*
X422283Y-2750D01*
X422617Y-2250D01*
X423117Y-1833D01*
X423783Y-1667D01*
X424367Y-1750D01*
X424783Y-1917D01*
X425200Y-2250D01*
G01X434900Y-5000D02*
X434400Y-4917D01*
X433900Y-4583D01*
X433567Y-4000D01*
X433400Y-3333D01*
X433567Y-2667D01*
X433900Y-2083D01*
X434400Y-1750D01*
X434900Y-1667D01*
X435400Y-1750D01*
X435900Y-2083D01*
X436233Y-2667D01*
X436317Y-3333D01*
X436233Y-4000D01*
X435900Y-4583D01*
X435400Y-4917D01*
X434900Y-5000D01*
G01X439333D02*
Y-1667D01*
G01Y-2333D02*
X439750Y-2000D01*
X440167Y-1750D01*
X440750Y-1667D01*
X441167Y-1750D01*
X441667Y-2000D01*
G01X453200Y0D02*
Y-5000D01*
G01Y-4250D02*
X452867Y-4667D01*
X452367Y-4917D01*
X451783Y-5000D01*
X451117Y-4833D01*
X450617Y-4417D01*
X450283Y-3917D01*
X450200Y-3333D01*
X450283Y-2750D01*
X450617Y-2250D01*
X451117Y-1833D01*
X451783Y-1667D01*
X452367Y-1750D01*
X452783Y-1917D01*
X453200Y-2250D01*
G01X457300Y-1667D02*
Y-5000D01*
G01Y-333D02*
X457133Y-250D01*
Y-83D01*
X457300Y0D01*
X457467Y-83D01*
Y-250D01*
X457300Y-333D01*
G01X464400Y-5000D02*
Y-1667D01*
G01Y-2250D02*
X464067Y-1917D01*
X463567Y-1750D01*
X462983Y-1667D01*
X462400Y-1833D01*
X461900Y-2167D01*
X461567Y-2667D01*
X461400Y-3333D01*
X461567Y-4000D01*
X461900Y-4500D01*
X462400Y-4833D01*
X462983Y-5000D01*
X463567Y-4917D01*
X464067Y-4667D01*
X464400Y-4333D01*
G01X466000Y-5000D02*
Y-1667D01*
G01Y-2583D02*
X466250Y-2167D01*
X466667Y-1833D01*
X467250Y-1667D01*
X467833Y-1833D01*
X468250Y-2167D01*
X468500Y-2583D01*
Y-5000D01*
G01Y-2583D02*
X468750Y-2167D01*
X469167Y-1833D01*
X469750Y-1667D01*
X470333Y-1833D01*
X470750Y-2167D01*
X471000Y-2667D01*
Y-5000D01*
G01X472850Y-2750D02*
X475517D01*
X475267Y-2167D01*
X474850Y-1833D01*
X474267Y-1667D01*
X473683Y-1750D01*
X473183Y-2000D01*
X472850Y-2583D01*
X472683Y-3083D01*
Y-3583D01*
X472850Y-4083D01*
X473267Y-4583D01*
X473767Y-4917D01*
X474350Y-5000D01*
X474933Y-4833D01*
X475517Y-4333D01*
G01X479700Y0D02*
Y-5000D01*
G01X478533Y-1667D02*
X480867D01*
G01X484050Y-2750D02*
X486717D01*
X486467Y-2167D01*
X486050Y-1833D01*
X485467Y-1667D01*
X484883Y-1750D01*
X484383Y-2000D01*
X484050Y-2583D01*
X483883Y-3083D01*
Y-3583D01*
X484050Y-4083D01*
X484467Y-4583D01*
X484967Y-4917D01*
X485550Y-5000D01*
X486133Y-4833D01*
X486717Y-4333D01*
G01X489733Y-5000D02*
Y-1667D01*
G01Y-2333D02*
X490150Y-2000D01*
X490567Y-1750D01*
X491150Y-1667D01*
X491567Y-1750D01*
X492067Y-2000D01*
G01X503767Y-5000D02*
X500433Y-3333D01*
X503767Y-1667D01*
G01X506617Y-4083D02*
X508783D01*
G01Y-2583D02*
X506617D01*
G01X518900Y-5000D02*
Y0D01*
X517900Y-1000D01*
G01Y-5000D02*
X519900D01*
G01X525500D02*
Y0D01*
X522417Y-3583D01*
X526583D01*
G01X533200Y-5000D02*
Y-1667D01*
G01Y-2583D02*
X533450Y-2167D01*
X533867Y-1833D01*
X534450Y-1667D01*
X535033Y-1833D01*
X535450Y-2167D01*
X535700Y-2583D01*
Y-5000D01*
G01Y-2583D02*
X535950Y-2167D01*
X536367Y-1833D01*
X536950Y-1667D01*
X537533Y-1833D01*
X537950Y-2167D01*
X538200Y-2667D01*
Y-5000D01*
G01X541300Y-1667D02*
Y-5000D01*
G01Y-333D02*
X541133Y-250D01*
Y-83D01*
X541300Y0D01*
X541467Y-83D01*
Y-250D01*
X541300Y-333D01*
G01X546900Y-5000D02*
Y0D01*
G01X272500Y52000D02*
Y47000D01*
G01X270583Y52000D02*
X274417D01*
G01X276683Y47000D02*
Y52000D01*
G01Y49583D02*
X277100Y50000D01*
X277517Y50250D01*
X278183Y50333D01*
X278683Y50250D01*
X279267Y49917D01*
X279517Y49417D01*
Y47000D01*
G01X282450Y49250D02*
X285117D01*
X284867Y49833D01*
X284450Y50167D01*
X283867Y50333D01*
X283283Y50250D01*
X282783Y50000D01*
X282450Y49417D01*
X282283Y48917D01*
Y48417D01*
X282450Y47917D01*
X282867Y47417D01*
X283367Y47083D01*
X283950Y47000D01*
X284533Y47167D01*
X285117Y47667D01*
G01X294900Y47000D02*
Y52000D01*
G01X302000Y47000D02*
Y50333D01*
G01Y49750D02*
X301667Y50083D01*
X301167Y50250D01*
X300583Y50333D01*
X300000Y50167D01*
X299500Y49833D01*
X299167Y49333D01*
X299000Y48667D01*
X299167Y48000D01*
X299500Y47500D01*
X300000Y47167D01*
X300583Y47000D01*
X301167Y47083D01*
X301667Y47333D01*
X302000Y47667D01*
G01X304933Y47000D02*
Y50333D01*
G01Y49667D02*
X305350Y50000D01*
X305767Y50250D01*
X306350Y50333D01*
X306767Y50250D01*
X307267Y50000D01*
G01X310533Y45750D02*
X311117Y45417D01*
X311783Y45333D01*
X312367Y45417D01*
X312867Y45833D01*
X313200Y46417D01*
Y50333D01*
G01Y49667D02*
X312867Y50000D01*
X312367Y50250D01*
X311783Y50333D01*
X311117Y50167D01*
X310700Y49833D01*
X310367Y49250D01*
X310200Y48667D01*
X310283Y48167D01*
X310617Y47583D01*
X311117Y47167D01*
X311783Y47000D01*
X312283Y47083D01*
X312867Y47417D01*
X313200Y47750D01*
G01X316050Y49250D02*
X318717D01*
X318467Y49833D01*
X318050Y50167D01*
X317467Y50333D01*
X316883Y50250D01*
X316383Y50000D01*
X316050Y49417D01*
X315883Y48917D01*
Y48417D01*
X316050Y47917D01*
X316467Y47417D01*
X316967Y47083D01*
X317550Y47000D01*
X318133Y47167D01*
X318717Y47667D01*
G01X321650Y47583D02*
X322067Y47250D01*
X322650Y47000D01*
X323150D01*
X323650Y47167D01*
X323983Y47417D01*
X324150Y47750D01*
X324067Y48250D01*
X323733Y48500D01*
X322233Y49000D01*
X321900Y49583D01*
X322067Y50000D01*
X322400Y50250D01*
X322900Y50333D01*
X323400Y50250D01*
X323900Y50000D01*
G01X328500Y52000D02*
Y47000D01*
G01X327333Y50333D02*
X329667D01*
G01X341200Y52000D02*
Y47000D01*
G01Y47750D02*
X340867Y47333D01*
X340367Y47083D01*
X339783Y47000D01*
X339117Y47167D01*
X338617Y47583D01*
X338283Y48083D01*
X338200Y48667D01*
X338283Y49250D01*
X338617Y49750D01*
X339117Y50167D01*
X339783Y50333D01*
X340367Y50250D01*
X340783Y50083D01*
X341200Y49750D01*
G01X345300Y50333D02*
Y47000D01*
G01Y51667D02*
X345133Y51750D01*
Y51917D01*
X345300Y52000D01*
X345467Y51917D01*
Y51750D01*
X345300Y51667D01*
G01X348400Y47000D02*
Y50333D01*
G01Y49417D02*
X348650Y49833D01*
X349067Y50167D01*
X349650Y50333D01*
X350233Y50167D01*
X350650Y49833D01*
X350900Y49417D01*
Y47000D01*
G01Y49417D02*
X351150Y49833D01*
X351567Y50167D01*
X352150Y50333D01*
X352733Y50167D01*
X353150Y49833D01*
X353400Y49333D01*
Y47000D01*
G01X355250Y49250D02*
X357917D01*
X357667Y49833D01*
X357250Y50167D01*
X356667Y50333D01*
X356083Y50250D01*
X355583Y50000D01*
X355250Y49417D01*
X355083Y48917D01*
Y48417D01*
X355250Y47917D01*
X355667Y47417D01*
X356167Y47083D01*
X356750Y47000D01*
X357333Y47167D01*
X357917Y47667D01*
G01X360683Y47000D02*
Y50333D01*
G01Y49500D02*
X361017Y49917D01*
X361517Y50250D01*
X362183Y50333D01*
X362767Y50250D01*
X363267Y49917D01*
X363517Y49333D01*
Y47000D01*
G01X366450Y47583D02*
X366867Y47250D01*
X367450Y47000D01*
X367950D01*
X368450Y47167D01*
X368783Y47417D01*
X368950Y47750D01*
X368867Y48250D01*
X368533Y48500D01*
X367033Y49000D01*
X366700Y49583D01*
X366867Y50000D01*
X367200Y50250D01*
X367700Y50333D01*
X368200Y50250D01*
X368700Y50000D01*
G01X373300Y50333D02*
Y47000D01*
G01Y51667D02*
X373133Y51750D01*
Y51917D01*
X373300Y52000D01*
X373467Y51917D01*
Y51750D01*
X373300Y51667D01*
G01X378900Y47000D02*
X378400Y47083D01*
X377900Y47417D01*
X377567Y48000D01*
X377400Y48667D01*
X377567Y49333D01*
X377900Y49917D01*
X378400Y50250D01*
X378900Y50333D01*
X379400Y50250D01*
X379900Y49917D01*
X380233Y49333D01*
X380317Y48667D01*
X380233Y48000D01*
X379900Y47417D01*
X379400Y47083D01*
X378900Y47000D01*
G01X383083D02*
Y50333D01*
G01Y49500D02*
X383417Y49917D01*
X383917Y50250D01*
X384583Y50333D01*
X385167Y50250D01*
X385667Y49917D01*
X385917Y49333D01*
Y47000D01*
G01X395700D02*
X395200Y47083D01*
X394700Y47417D01*
X394367Y48000D01*
X394200Y48667D01*
X394367Y49333D01*
X394700Y49917D01*
X395200Y50250D01*
X395700Y50333D01*
X396200Y50250D01*
X396700Y49917D01*
X397033Y49333D01*
X397117Y48667D01*
X397033Y48000D01*
X396700Y47417D01*
X396200Y47083D01*
X395700Y47000D01*
G01X400800D02*
Y51250D01*
X400967Y51667D01*
X401300Y51917D01*
X401800Y52000D01*
X402300Y51833D01*
X402550Y51417D01*
G01X401550Y50000D02*
X399883D01*
G01X411000Y45333D02*
Y50333D01*
G01Y49583D02*
X411417Y50000D01*
X411833Y50250D01*
X412500Y50333D01*
X413083Y50250D01*
X413667Y49833D01*
X413917Y49250D01*
X414000Y48667D01*
X413917Y48083D01*
X413667Y47500D01*
X413167Y47167D01*
X412500Y47000D01*
X411917Y47083D01*
X411333Y47333D01*
X411000Y47667D01*
G01X419600Y47000D02*
Y50333D01*
G01Y49750D02*
X419267Y50083D01*
X418767Y50250D01*
X418183Y50333D01*
X417600Y50167D01*
X417100Y49833D01*
X416767Y49333D01*
X416600Y48667D01*
X416767Y48000D01*
X417100Y47500D01*
X417600Y47167D01*
X418183Y47000D01*
X418767Y47083D01*
X419267Y47333D01*
X419600Y47667D01*
G01X425200Y52000D02*
Y47000D01*
G01Y47750D02*
X424867Y47333D01*
X424367Y47083D01*
X423783Y47000D01*
X423117Y47167D01*
X422617Y47583D01*
X422283Y48083D01*
X422200Y48667D01*
X422283Y49250D01*
X422617Y49750D01*
X423117Y50167D01*
X423783Y50333D01*
X424367Y50250D01*
X424783Y50083D01*
X425200Y49750D01*
G01X434900Y47000D02*
X434400Y47083D01*
X433900Y47417D01*
X433567Y48000D01*
X433400Y48667D01*
X433567Y49333D01*
X433900Y49917D01*
X434400Y50250D01*
X434900Y50333D01*
X435400Y50250D01*
X435900Y49917D01*
X436233Y49333D01*
X436317Y48667D01*
X436233Y48000D01*
X435900Y47417D01*
X435400Y47083D01*
X434900Y47000D01*
G01X439333D02*
Y50333D01*
G01Y49667D02*
X439750Y50000D01*
X440167Y50250D01*
X440750Y50333D01*
X441167Y50250D01*
X441667Y50000D01*
G01X453200Y52000D02*
Y47000D01*
G01Y47750D02*
X452867Y47333D01*
X452367Y47083D01*
X451783Y47000D01*
X451117Y47167D01*
X450617Y47583D01*
X450283Y48083D01*
X450200Y48667D01*
X450283Y49250D01*
X450617Y49750D01*
X451117Y50167D01*
X451783Y50333D01*
X452367Y50250D01*
X452783Y50083D01*
X453200Y49750D01*
G01X457300Y50333D02*
Y47000D01*
G01Y51667D02*
X457133Y51750D01*
Y51917D01*
X457300Y52000D01*
X457467Y51917D01*
Y51750D01*
X457300Y51667D01*
G01X464400Y47000D02*
Y50333D01*
G01Y49750D02*
X464067Y50083D01*
X463567Y50250D01*
X462983Y50333D01*
X462400Y50167D01*
X461900Y49833D01*
X461567Y49333D01*
X461400Y48667D01*
X461567Y48000D01*
X461900Y47500D01*
X462400Y47167D01*
X462983Y47000D01*
X463567Y47083D01*
X464067Y47333D01*
X464400Y47667D01*
G01X466000Y47000D02*
Y50333D01*
G01Y49417D02*
X466250Y49833D01*
X466667Y50167D01*
X467250Y50333D01*
X467833Y50167D01*
X468250Y49833D01*
X468500Y49417D01*
Y47000D01*
G01Y49417D02*
X468750Y49833D01*
X469167Y50167D01*
X469750Y50333D01*
X470333Y50167D01*
X470750Y49833D01*
X471000Y49333D01*
Y47000D01*
G01X472850Y49250D02*
X475517D01*
X475267Y49833D01*
X474850Y50167D01*
X474267Y50333D01*
X473683Y50250D01*
X473183Y50000D01*
X472850Y49417D01*
X472683Y48917D01*
Y48417D01*
X472850Y47917D01*
X473267Y47417D01*
X473767Y47083D01*
X474350Y47000D01*
X474933Y47167D01*
X475517Y47667D01*
G01X479700Y52000D02*
Y47000D01*
G01X478533Y50333D02*
X480867D01*
G01X484050Y49250D02*
X486717D01*
X486467Y49833D01*
X486050Y50167D01*
X485467Y50333D01*
X484883Y50250D01*
X484383Y50000D01*
X484050Y49417D01*
X483883Y48917D01*
Y48417D01*
X484050Y47917D01*
X484467Y47417D01*
X484967Y47083D01*
X485550Y47000D01*
X486133Y47167D01*
X486717Y47667D01*
G01X489733Y47000D02*
Y50333D01*
G01Y49667D02*
X490150Y50000D01*
X490567Y50250D01*
X491150Y50333D01*
X491567Y50250D01*
X492067Y50000D01*
G01X500433Y47000D02*
X503767Y48667D01*
X500433Y50333D01*
G01X513300Y47000D02*
Y52000D01*
X512300Y51000D01*
G01Y47000D02*
X514300D01*
G01X519900D02*
Y52000D01*
X516817Y48417D01*
X520983D01*
G01X527600Y47000D02*
Y50333D01*
G01Y49417D02*
X527850Y49833D01*
X528267Y50167D01*
X528850Y50333D01*
X529433Y50167D01*
X529850Y49833D01*
X530100Y49417D01*
Y47000D01*
G01Y49417D02*
X530350Y49833D01*
X530767Y50167D01*
X531350Y50333D01*
X531933Y50167D01*
X532350Y49833D01*
X532600Y49333D01*
Y47000D01*
G01X535700Y50333D02*
Y47000D01*
G01Y51667D02*
X535533Y51750D01*
Y51917D01*
X535700Y52000D01*
X535867Y51917D01*
Y51750D01*
X535700Y51667D01*
G01X541300Y47000D02*
Y52000D01*
G01X273580Y32670D02*
Y27670D01*
G01X271663Y32670D02*
X275497D01*
G01X277763Y27670D02*
Y32670D01*
G01Y30253D02*
X278180Y30670D01*
X278597Y30920D01*
X279263Y31003D01*
X279763Y30920D01*
X280347Y30587D01*
X280597Y30087D01*
Y27670D01*
G01X283530Y29920D02*
X286197D01*
X285947Y30503D01*
X285530Y30837D01*
X284947Y31003D01*
X284363Y30920D01*
X283863Y30670D01*
X283530Y30087D01*
X283363Y29587D01*
Y29087D01*
X283530Y28587D01*
X283947Y28087D01*
X284447Y27753D01*
X285030Y27670D01*
X285613Y27837D01*
X286197Y28337D01*
G01X295980Y27670D02*
Y32670D01*
G01X303080Y27670D02*
Y31003D01*
G01Y30420D02*
X302747Y30753D01*
X302247Y30920D01*
X301663Y31003D01*
X301080Y30837D01*
X300580Y30503D01*
X300247Y30003D01*
X300080Y29337D01*
X300247Y28670D01*
X300580Y28170D01*
X301080Y27837D01*
X301663Y27670D01*
X302247Y27753D01*
X302747Y28003D01*
X303080Y28337D01*
G01X306013Y27670D02*
Y31003D01*
G01Y30337D02*
X306430Y30670D01*
X306847Y30920D01*
X307430Y31003D01*
X307847Y30920D01*
X308347Y30670D01*
G01X311613Y26420D02*
X312197Y26087D01*
X312863Y26003D01*
X313447Y26087D01*
X313947Y26503D01*
X314280Y27087D01*
Y31003D01*
G01Y30337D02*
X313947Y30670D01*
X313447Y30920D01*
X312863Y31003D01*
X312197Y30837D01*
X311780Y30503D01*
X311447Y29920D01*
X311280Y29337D01*
X311363Y28837D01*
X311697Y28253D01*
X312197Y27837D01*
X312863Y27670D01*
X313363Y27753D01*
X313947Y28087D01*
X314280Y28420D01*
G01X317130Y29920D02*
X319797D01*
X319547Y30503D01*
X319130Y30837D01*
X318547Y31003D01*
X317963Y30920D01*
X317463Y30670D01*
X317130Y30087D01*
X316963Y29587D01*
Y29087D01*
X317130Y28587D01*
X317547Y28087D01*
X318047Y27753D01*
X318630Y27670D01*
X319213Y27837D01*
X319797Y28337D01*
G01X322730Y28253D02*
X323147Y27920D01*
X323730Y27670D01*
X324230D01*
X324730Y27837D01*
X325063Y28087D01*
X325230Y28420D01*
X325147Y28920D01*
X324813Y29170D01*
X323313Y29670D01*
X322980Y30253D01*
X323147Y30670D01*
X323480Y30920D01*
X323980Y31003D01*
X324480Y30920D01*
X324980Y30670D01*
G01X329580Y32670D02*
Y27670D01*
G01X328413Y31003D02*
X330747D01*
G01X342280Y32670D02*
Y27670D01*
G01Y28420D02*
X341947Y28003D01*
X341447Y27753D01*
X340863Y27670D01*
X340197Y27837D01*
X339697Y28253D01*
X339363Y28753D01*
X339280Y29337D01*
X339363Y29920D01*
X339697Y30420D01*
X340197Y30837D01*
X340863Y31003D01*
X341447Y30920D01*
X341863Y30753D01*
X342280Y30420D01*
G01X346380Y31003D02*
Y27670D01*
G01Y32337D02*
X346213Y32420D01*
Y32587D01*
X346380Y32670D01*
X346547Y32587D01*
Y32420D01*
X346380Y32337D01*
G01X349480Y27670D02*
Y31003D01*
G01Y30087D02*
X349730Y30503D01*
X350147Y30837D01*
X350730Y31003D01*
X351313Y30837D01*
X351730Y30503D01*
X351980Y30087D01*
Y27670D01*
G01Y30087D02*
X352230Y30503D01*
X352647Y30837D01*
X353230Y31003D01*
X353813Y30837D01*
X354230Y30503D01*
X354480Y30003D01*
Y27670D01*
G01X356330Y29920D02*
X358997D01*
X358747Y30503D01*
X358330Y30837D01*
X357747Y31003D01*
X357163Y30920D01*
X356663Y30670D01*
X356330Y30087D01*
X356163Y29587D01*
Y29087D01*
X356330Y28587D01*
X356747Y28087D01*
X357247Y27753D01*
X357830Y27670D01*
X358413Y27837D01*
X358997Y28337D01*
G01X361763Y27670D02*
Y31003D01*
G01Y30170D02*
X362097Y30587D01*
X362597Y30920D01*
X363263Y31003D01*
X363847Y30920D01*
X364347Y30587D01*
X364597Y30003D01*
Y27670D01*
G01X367530Y28253D02*
X367947Y27920D01*
X368530Y27670D01*
X369030D01*
X369530Y27837D01*
X369863Y28087D01*
X370030Y28420D01*
X369947Y28920D01*
X369613Y29170D01*
X368113Y29670D01*
X367780Y30253D01*
X367947Y30670D01*
X368280Y30920D01*
X368780Y31003D01*
X369280Y30920D01*
X369780Y30670D01*
G01X374380Y31003D02*
Y27670D01*
G01Y32337D02*
X374213Y32420D01*
Y32587D01*
X374380Y32670D01*
X374547Y32587D01*
Y32420D01*
X374380Y32337D01*
G01X379980Y27670D02*
X379480Y27753D01*
X378980Y28087D01*
X378647Y28670D01*
X378480Y29337D01*
X378647Y30003D01*
X378980Y30587D01*
X379480Y30920D01*
X379980Y31003D01*
X380480Y30920D01*
X380980Y30587D01*
X381313Y30003D01*
X381397Y29337D01*
X381313Y28670D01*
X380980Y28087D01*
X380480Y27753D01*
X379980Y27670D01*
G01X384163D02*
Y31003D01*
G01Y30170D02*
X384497Y30587D01*
X384997Y30920D01*
X385663Y31003D01*
X386247Y30920D01*
X386747Y30587D01*
X386997Y30003D01*
Y27670D01*
G01X396780D02*
X396280Y27753D01*
X395780Y28087D01*
X395447Y28670D01*
X395280Y29337D01*
X395447Y30003D01*
X395780Y30587D01*
X396280Y30920D01*
X396780Y31003D01*
X397280Y30920D01*
X397780Y30587D01*
X398113Y30003D01*
X398197Y29337D01*
X398113Y28670D01*
X397780Y28087D01*
X397280Y27753D01*
X396780Y27670D01*
G01X401880D02*
Y31920D01*
X402047Y32337D01*
X402380Y32587D01*
X402880Y32670D01*
X403380Y32503D01*
X403630Y32087D01*
G01X402630Y30670D02*
X400963D01*
G01X412080Y26003D02*
Y31003D01*
G01Y30253D02*
X412497Y30670D01*
X412913Y30920D01*
X413580Y31003D01*
X414163Y30920D01*
X414747Y30503D01*
X414997Y29920D01*
X415080Y29337D01*
X414997Y28753D01*
X414747Y28170D01*
X414247Y27837D01*
X413580Y27670D01*
X412997Y27753D01*
X412413Y28003D01*
X412080Y28337D01*
G01X420680Y27670D02*
Y31003D01*
G01Y30420D02*
X420347Y30753D01*
X419847Y30920D01*
X419263Y31003D01*
X418680Y30837D01*
X418180Y30503D01*
X417847Y30003D01*
X417680Y29337D01*
X417847Y28670D01*
X418180Y28170D01*
X418680Y27837D01*
X419263Y27670D01*
X419847Y27753D01*
X420347Y28003D01*
X420680Y28337D01*
G01X426280Y32670D02*
Y27670D01*
G01Y28420D02*
X425947Y28003D01*
X425447Y27753D01*
X424863Y27670D01*
X424197Y27837D01*
X423697Y28253D01*
X423363Y28753D01*
X423280Y29337D01*
X423363Y29920D01*
X423697Y30420D01*
X424197Y30837D01*
X424863Y31003D01*
X425447Y30920D01*
X425863Y30753D01*
X426280Y30420D01*
G01X435980Y27670D02*
X435480Y27753D01*
X434980Y28087D01*
X434647Y28670D01*
X434480Y29337D01*
X434647Y30003D01*
X434980Y30587D01*
X435480Y30920D01*
X435980Y31003D01*
X436480Y30920D01*
X436980Y30587D01*
X437313Y30003D01*
X437397Y29337D01*
X437313Y28670D01*
X436980Y28087D01*
X436480Y27753D01*
X435980Y27670D01*
G01X440413D02*
Y31003D01*
G01Y30337D02*
X440830Y30670D01*
X441247Y30920D01*
X441830Y31003D01*
X442247Y30920D01*
X442747Y30670D01*
G01X454280Y32670D02*
Y27670D01*
G01Y28420D02*
X453947Y28003D01*
X453447Y27753D01*
X452863Y27670D01*
X452197Y27837D01*
X451697Y28253D01*
X451363Y28753D01*
X451280Y29337D01*
X451363Y29920D01*
X451697Y30420D01*
X452197Y30837D01*
X452863Y31003D01*
X453447Y30920D01*
X453863Y30753D01*
X454280Y30420D01*
G01X458380Y31003D02*
Y27670D01*
G01Y32337D02*
X458213Y32420D01*
Y32587D01*
X458380Y32670D01*
X458547Y32587D01*
Y32420D01*
X458380Y32337D01*
G01X465480Y27670D02*
Y31003D01*
G01Y30420D02*
X465147Y30753D01*
X464647Y30920D01*
X464063Y31003D01*
X463480Y30837D01*
X462980Y30503D01*
X462647Y30003D01*
X462480Y29337D01*
X462647Y28670D01*
X462980Y28170D01*
X463480Y27837D01*
X464063Y27670D01*
X464647Y27753D01*
X465147Y28003D01*
X465480Y28337D01*
G01X467080Y27670D02*
Y31003D01*
G01Y30087D02*
X467330Y30503D01*
X467747Y30837D01*
X468330Y31003D01*
X468913Y30837D01*
X469330Y30503D01*
X469580Y30087D01*
Y27670D01*
G01Y30087D02*
X469830Y30503D01*
X470247Y30837D01*
X470830Y31003D01*
X471413Y30837D01*
X471830Y30503D01*
X472080Y30003D01*
Y27670D01*
G01X473930Y29920D02*
X476597D01*
X476347Y30503D01*
X475930Y30837D01*
X475347Y31003D01*
X474763Y30920D01*
X474263Y30670D01*
X473930Y30087D01*
X473763Y29587D01*
Y29087D01*
X473930Y28587D01*
X474347Y28087D01*
X474847Y27753D01*
X475430Y27670D01*
X476013Y27837D01*
X476597Y28337D01*
G01X480780Y32670D02*
Y27670D01*
G01X479613Y31003D02*
X481947D01*
G01X485130Y29920D02*
X487797D01*
X487547Y30503D01*
X487130Y30837D01*
X486547Y31003D01*
X485963Y30920D01*
X485463Y30670D01*
X485130Y30087D01*
X484963Y29587D01*
Y29087D01*
X485130Y28587D01*
X485547Y28087D01*
X486047Y27753D01*
X486630Y27670D01*
X487213Y27837D01*
X487797Y28337D01*
G01X490813Y27670D02*
Y31003D01*
G01Y30337D02*
X491230Y30670D01*
X491647Y30920D01*
X492230Y31003D01*
X492647Y30920D01*
X493147Y30670D01*
G01X504847Y27670D02*
X501513Y29337D01*
X504847Y31003D01*
G01X507697Y28587D02*
X509863D01*
G01Y30087D02*
X507697D01*
G01X519980Y27670D02*
Y32670D01*
X518980Y31670D01*
G01Y27670D02*
X520980D01*
G01X526580D02*
Y32670D01*
X523497Y29087D01*
X527663D01*
G01X534280Y27670D02*
Y31003D01*
G01Y30087D02*
X534530Y30503D01*
X534947Y30837D01*
X535530Y31003D01*
X536113Y30837D01*
X536530Y30503D01*
X536780Y30087D01*
Y27670D01*
G01Y30087D02*
X537030Y30503D01*
X537447Y30837D01*
X538030Y31003D01*
X538613Y30837D01*
X539030Y30503D01*
X539280Y30003D01*
Y27670D01*
G01X542380Y31003D02*
Y27670D01*
G01Y32337D02*
X542213Y32420D01*
Y32587D01*
X542380Y32670D01*
X542547Y32587D01*
Y32420D01*
X542380Y32337D01*
G01X547980Y27670D02*
Y32670D01*
G01X272500Y15000D02*
Y10000D01*
G01X270583Y15000D02*
X274417D01*
G01X276683Y10000D02*
Y15000D01*
G01Y12583D02*
X277100Y13000D01*
X277517Y13250D01*
X278183Y13333D01*
X278683Y13250D01*
X279267Y12917D01*
X279517Y12417D01*
Y10000D01*
G01X282450Y12250D02*
X285117D01*
X284867Y12833D01*
X284450Y13167D01*
X283867Y13333D01*
X283283Y13250D01*
X282783Y13000D01*
X282450Y12417D01*
X282283Y11917D01*
Y11417D01*
X282450Y10917D01*
X282867Y10417D01*
X283367Y10083D01*
X283950Y10000D01*
X284533Y10167D01*
X285117Y10667D01*
G01X294900Y10000D02*
Y15000D01*
G01X302000Y10000D02*
Y13333D01*
G01Y12750D02*
X301667Y13083D01*
X301167Y13250D01*
X300583Y13333D01*
X300000Y13167D01*
X299500Y12833D01*
X299167Y12333D01*
X299000Y11667D01*
X299167Y11000D01*
X299500Y10500D01*
X300000Y10167D01*
X300583Y10000D01*
X301167Y10083D01*
X301667Y10333D01*
X302000Y10667D01*
G01X304933Y10000D02*
Y13333D01*
G01Y12667D02*
X305350Y13000D01*
X305767Y13250D01*
X306350Y13333D01*
X306767Y13250D01*
X307267Y13000D01*
G01X310533Y8750D02*
X311117Y8417D01*
X311783Y8333D01*
X312367Y8417D01*
X312867Y8833D01*
X313200Y9417D01*
Y13333D01*
G01Y12667D02*
X312867Y13000D01*
X312367Y13250D01*
X311783Y13333D01*
X311117Y13167D01*
X310700Y12833D01*
X310367Y12250D01*
X310200Y11667D01*
X310283Y11167D01*
X310617Y10583D01*
X311117Y10167D01*
X311783Y10000D01*
X312283Y10083D01*
X312867Y10417D01*
X313200Y10750D01*
G01X316050Y12250D02*
X318717D01*
X318467Y12833D01*
X318050Y13167D01*
X317467Y13333D01*
X316883Y13250D01*
X316383Y13000D01*
X316050Y12417D01*
X315883Y11917D01*
Y11417D01*
X316050Y10917D01*
X316467Y10417D01*
X316967Y10083D01*
X317550Y10000D01*
X318133Y10167D01*
X318717Y10667D01*
G01X321650Y10583D02*
X322067Y10250D01*
X322650Y10000D01*
X323150D01*
X323650Y10167D01*
X323983Y10417D01*
X324150Y10750D01*
X324067Y11250D01*
X323733Y11500D01*
X322233Y12000D01*
X321900Y12583D01*
X322067Y13000D01*
X322400Y13250D01*
X322900Y13333D01*
X323400Y13250D01*
X323900Y13000D01*
G01X328500Y15000D02*
Y10000D01*
G01X327333Y13333D02*
X329667D01*
G01X341200Y15000D02*
Y10000D01*
G01Y10750D02*
X340867Y10333D01*
X340367Y10083D01*
X339783Y10000D01*
X339117Y10167D01*
X338617Y10583D01*
X338283Y11083D01*
X338200Y11667D01*
X338283Y12250D01*
X338617Y12750D01*
X339117Y13167D01*
X339783Y13333D01*
X340367Y13250D01*
X340783Y13083D01*
X341200Y12750D01*
G01X345300Y13333D02*
Y10000D01*
G01Y14667D02*
X345133Y14750D01*
Y14917D01*
X345300Y15000D01*
X345467Y14917D01*
Y14750D01*
X345300Y14667D01*
G01X348400Y10000D02*
Y13333D01*
G01Y12417D02*
X348650Y12833D01*
X349067Y13167D01*
X349650Y13333D01*
X350233Y13167D01*
X350650Y12833D01*
X350900Y12417D01*
Y10000D01*
G01Y12417D02*
X351150Y12833D01*
X351567Y13167D01*
X352150Y13333D01*
X352733Y13167D01*
X353150Y12833D01*
X353400Y12333D01*
Y10000D01*
G01X355250Y12250D02*
X357917D01*
X357667Y12833D01*
X357250Y13167D01*
X356667Y13333D01*
X356083Y13250D01*
X355583Y13000D01*
X355250Y12417D01*
X355083Y11917D01*
Y11417D01*
X355250Y10917D01*
X355667Y10417D01*
X356167Y10083D01*
X356750Y10000D01*
X357333Y10167D01*
X357917Y10667D01*
G01X360683Y10000D02*
Y13333D01*
G01Y12500D02*
X361017Y12917D01*
X361517Y13250D01*
X362183Y13333D01*
X362767Y13250D01*
X363267Y12917D01*
X363517Y12333D01*
Y10000D01*
G01X366450Y10583D02*
X366867Y10250D01*
X367450Y10000D01*
X367950D01*
X368450Y10167D01*
X368783Y10417D01*
X368950Y10750D01*
X368867Y11250D01*
X368533Y11500D01*
X367033Y12000D01*
X366700Y12583D01*
X366867Y13000D01*
X367200Y13250D01*
X367700Y13333D01*
X368200Y13250D01*
X368700Y13000D01*
G01X373300Y13333D02*
Y10000D01*
G01Y14667D02*
X373133Y14750D01*
Y14917D01*
X373300Y15000D01*
X373467Y14917D01*
Y14750D01*
X373300Y14667D01*
G01X378900Y10000D02*
X378400Y10083D01*
X377900Y10417D01*
X377567Y11000D01*
X377400Y11667D01*
X377567Y12333D01*
X377900Y12917D01*
X378400Y13250D01*
X378900Y13333D01*
X379400Y13250D01*
X379900Y12917D01*
X380233Y12333D01*
X380317Y11667D01*
X380233Y11000D01*
X379900Y10417D01*
X379400Y10083D01*
X378900Y10000D01*
G01X383083D02*
Y13333D01*
G01Y12500D02*
X383417Y12917D01*
X383917Y13250D01*
X384583Y13333D01*
X385167Y13250D01*
X385667Y12917D01*
X385917Y12333D01*
Y10000D01*
G01X395700D02*
X395200Y10083D01*
X394700Y10417D01*
X394367Y11000D01*
X394200Y11667D01*
X394367Y12333D01*
X394700Y12917D01*
X395200Y13250D01*
X395700Y13333D01*
X396200Y13250D01*
X396700Y12917D01*
X397033Y12333D01*
X397117Y11667D01*
X397033Y11000D01*
X396700Y10417D01*
X396200Y10083D01*
X395700Y10000D01*
G01X400800D02*
Y14250D01*
X400967Y14667D01*
X401300Y14917D01*
X401800Y15000D01*
X402300Y14833D01*
X402550Y14417D01*
G01X401550Y13000D02*
X399883D01*
G01X411000Y8333D02*
Y13333D01*
G01Y12583D02*
X411417Y13000D01*
X411833Y13250D01*
X412500Y13333D01*
X413083Y13250D01*
X413667Y12833D01*
X413917Y12250D01*
X414000Y11667D01*
X413917Y11083D01*
X413667Y10500D01*
X413167Y10167D01*
X412500Y10000D01*
X411917Y10083D01*
X411333Y10333D01*
X411000Y10667D01*
G01X419600Y10000D02*
Y13333D01*
G01Y12750D02*
X419267Y13083D01*
X418767Y13250D01*
X418183Y13333D01*
X417600Y13167D01*
X417100Y12833D01*
X416767Y12333D01*
X416600Y11667D01*
X416767Y11000D01*
X417100Y10500D01*
X417600Y10167D01*
X418183Y10000D01*
X418767Y10083D01*
X419267Y10333D01*
X419600Y10667D01*
G01X425200Y15000D02*
Y10000D01*
G01Y10750D02*
X424867Y10333D01*
X424367Y10083D01*
X423783Y10000D01*
X423117Y10167D01*
X422617Y10583D01*
X422283Y11083D01*
X422200Y11667D01*
X422283Y12250D01*
X422617Y12750D01*
X423117Y13167D01*
X423783Y13333D01*
X424367Y13250D01*
X424783Y13083D01*
X425200Y12750D01*
G01X434900Y10000D02*
X434400Y10083D01*
X433900Y10417D01*
X433567Y11000D01*
X433400Y11667D01*
X433567Y12333D01*
X433900Y12917D01*
X434400Y13250D01*
X434900Y13333D01*
X435400Y13250D01*
X435900Y12917D01*
X436233Y12333D01*
X436317Y11667D01*
X436233Y11000D01*
X435900Y10417D01*
X435400Y10083D01*
X434900Y10000D01*
G01X439333D02*
Y13333D01*
G01Y12667D02*
X439750Y13000D01*
X440167Y13250D01*
X440750Y13333D01*
X441167Y13250D01*
X441667Y13000D01*
G01X453200Y15000D02*
Y10000D01*
G01Y10750D02*
X452867Y10333D01*
X452367Y10083D01*
X451783Y10000D01*
X451117Y10167D01*
X450617Y10583D01*
X450283Y11083D01*
X450200Y11667D01*
X450283Y12250D01*
X450617Y12750D01*
X451117Y13167D01*
X451783Y13333D01*
X452367Y13250D01*
X452783Y13083D01*
X453200Y12750D01*
G01X457300Y13333D02*
Y10000D01*
G01Y14667D02*
X457133Y14750D01*
Y14917D01*
X457300Y15000D01*
X457467Y14917D01*
Y14750D01*
X457300Y14667D01*
G01X464400Y10000D02*
Y13333D01*
G01Y12750D02*
X464067Y13083D01*
X463567Y13250D01*
X462983Y13333D01*
X462400Y13167D01*
X461900Y12833D01*
X461567Y12333D01*
X461400Y11667D01*
X461567Y11000D01*
X461900Y10500D01*
X462400Y10167D01*
X462983Y10000D01*
X463567Y10083D01*
X464067Y10333D01*
X464400Y10667D01*
G01X466000Y10000D02*
Y13333D01*
G01Y12417D02*
X466250Y12833D01*
X466667Y13167D01*
X467250Y13333D01*
X467833Y13167D01*
X468250Y12833D01*
X468500Y12417D01*
Y10000D01*
G01Y12417D02*
X468750Y12833D01*
X469167Y13167D01*
X469750Y13333D01*
X470333Y13167D01*
X470750Y12833D01*
X471000Y12333D01*
Y10000D01*
G01X472850Y12250D02*
X475517D01*
X475267Y12833D01*
X474850Y13167D01*
X474267Y13333D01*
X473683Y13250D01*
X473183Y13000D01*
X472850Y12417D01*
X472683Y11917D01*
Y11417D01*
X472850Y10917D01*
X473267Y10417D01*
X473767Y10083D01*
X474350Y10000D01*
X474933Y10167D01*
X475517Y10667D01*
G01X479700Y15000D02*
Y10000D01*
G01X478533Y13333D02*
X480867D01*
G01X484050Y12250D02*
X486717D01*
X486467Y12833D01*
X486050Y13167D01*
X485467Y13333D01*
X484883Y13250D01*
X484383Y13000D01*
X484050Y12417D01*
X483883Y11917D01*
Y11417D01*
X484050Y10917D01*
X484467Y10417D01*
X484967Y10083D01*
X485550Y10000D01*
X486133Y10167D01*
X486717Y10667D01*
G01X489733Y10000D02*
Y13333D01*
G01Y12667D02*
X490150Y13000D01*
X490567Y13250D01*
X491150Y13333D01*
X491567Y13250D01*
X492067Y13000D01*
G01X500433Y10000D02*
X503767Y11667D01*
X500433Y13333D01*
G01X507700Y10000D02*
Y15000D01*
X506700Y14000D01*
G01Y10000D02*
X508700D01*
G01X514300D02*
Y15000D01*
X511217Y11417D01*
X515383D01*
G01X522000Y10000D02*
Y13333D01*
G01Y12417D02*
X522250Y12833D01*
X522667Y13167D01*
X523250Y13333D01*
X523833Y13167D01*
X524250Y12833D01*
X524500Y12417D01*
Y10000D01*
G01Y12417D02*
X524750Y12833D01*
X525167Y13167D01*
X525750Y13333D01*
X526333Y13167D01*
X526750Y12833D01*
X527000Y12333D01*
Y10000D01*
G01X530100Y13333D02*
Y10000D01*
G01Y14667D02*
X529933Y14750D01*
Y14917D01*
X530100Y15000D01*
X530267Y14917D01*
Y14750D01*
X530100Y14667D01*
G01X535700Y10000D02*
Y15000D01*
G01X264000Y5500D02*
X694500D01*
G01X264000Y40500D02*
X694500D01*
G01X272500Y101500D02*
Y96500D01*
G01X271333Y99833D02*
X273667D01*
G01X276933Y96500D02*
Y99833D01*
G01Y99167D02*
X277350Y99500D01*
X277767Y99750D01*
X278350Y99833D01*
X278767Y99750D01*
X279267Y99500D01*
G01X285200Y96500D02*
Y99833D01*
G01Y99250D02*
X284867Y99583D01*
X284367Y99750D01*
X283783Y99833D01*
X283200Y99667D01*
X282700Y99333D01*
X282367Y98833D01*
X282200Y98167D01*
X282367Y97500D01*
X282700Y97000D01*
X283200Y96667D01*
X283783Y96500D01*
X284367Y96583D01*
X284867Y96833D01*
X285200Y97167D01*
G01X290633Y99417D02*
X290050Y99750D01*
X289550Y99833D01*
X288883Y99667D01*
X288383Y99333D01*
X288050Y98750D01*
X287967Y98167D01*
X288050Y97583D01*
X288383Y97083D01*
X288883Y96667D01*
X289550Y96500D01*
X290133Y96667D01*
X290633Y97000D01*
G01X293650Y98750D02*
X296317D01*
X296067Y99333D01*
X295650Y99667D01*
X295067Y99833D01*
X294483Y99750D01*
X293983Y99500D01*
X293650Y98917D01*
X293483Y98417D01*
Y97917D01*
X293650Y97417D01*
X294067Y96917D01*
X294567Y96583D01*
X295150Y96500D01*
X295733Y96667D01*
X296317Y97167D01*
G01X304017Y99833D02*
X305017Y96500D01*
X306100Y99833D01*
X307183Y96500D01*
X308183Y99833D01*
G01X311700D02*
Y96500D01*
G01Y101167D02*
X311533Y101250D01*
Y101417D01*
X311700Y101500D01*
X311867Y101417D01*
Y101250D01*
X311700Y101167D01*
G01X318800Y101500D02*
Y96500D01*
G01Y97250D02*
X318467Y96833D01*
X317967Y96583D01*
X317383Y96500D01*
X316717Y96667D01*
X316217Y97083D01*
X315883Y97583D01*
X315800Y98167D01*
X315883Y98750D01*
X316217Y99250D01*
X316717Y99667D01*
X317383Y99833D01*
X317967Y99750D01*
X318383Y99583D01*
X318800Y99250D01*
G01X322900Y101500D02*
Y96500D01*
G01X321733Y99833D02*
X324067D01*
G01X327083Y96500D02*
Y101500D01*
G01Y99083D02*
X327500Y99500D01*
X327917Y99750D01*
X328583Y99833D01*
X329083Y99750D01*
X329667Y99417D01*
X329917Y98917D01*
Y96500D01*
G01X341367D02*
X338033Y98167D01*
X341367Y99833D01*
G01X344217Y97417D02*
X346383D01*
G01Y98917D02*
X344217D01*
G01X354667Y97250D02*
X355167Y96833D01*
X355750Y96583D01*
X356500Y96500D01*
X357250Y96667D01*
X357833Y97000D01*
X358250Y97583D01*
X358333Y98250D01*
X358167Y98917D01*
X357750Y99333D01*
X357167Y99667D01*
X356583Y99750D01*
X356000Y99667D01*
X355250Y99333D01*
X355500Y101500D01*
X357750D01*
G01X365200Y96500D02*
Y99833D01*
G01Y98917D02*
X365450Y99333D01*
X365867Y99667D01*
X366450Y99833D01*
X367033Y99667D01*
X367450Y99333D01*
X367700Y98917D01*
Y96500D01*
G01Y98917D02*
X367950Y99333D01*
X368367Y99667D01*
X368950Y99833D01*
X369533Y99667D01*
X369950Y99333D01*
X370200Y98833D01*
Y96500D01*
G01X373300Y99833D02*
Y96500D01*
G01Y101167D02*
X373133Y101250D01*
Y101417D01*
X373300Y101500D01*
X373467Y101417D01*
Y101250D01*
X373300Y101167D01*
G01X378900Y96500D02*
Y101500D01*
G01X270667Y82250D02*
X271167Y81833D01*
X271750Y81583D01*
X272500Y81500D01*
X273250Y81667D01*
X273833Y82000D01*
X274250Y82583D01*
X274333Y83250D01*
X274167Y83917D01*
X273750Y84333D01*
X273167Y84667D01*
X272583Y84750D01*
X272000Y84667D01*
X271250Y84333D01*
X271500Y86500D01*
X273750D01*
G01X281200Y81500D02*
Y84833D01*
G01Y83917D02*
X281450Y84333D01*
X281867Y84667D01*
X282450Y84833D01*
X283033Y84667D01*
X283450Y84333D01*
X283700Y83917D01*
Y81500D01*
G01Y83917D02*
X283950Y84333D01*
X284367Y84667D01*
X284950Y84833D01*
X285533Y84667D01*
X285950Y84333D01*
X286200Y83833D01*
Y81500D01*
G01X289300Y84833D02*
Y81500D01*
G01Y86167D02*
X289133Y86250D01*
Y86417D01*
X289300Y86500D01*
X289467Y86417D01*
Y86250D01*
X289300Y86167D01*
G01X294900Y81500D02*
Y86500D01*
G01X307767Y81500D02*
X304433Y83167D01*
X307767Y84833D01*
G01X317300Y86500D02*
Y81500D01*
G01X316133Y84833D02*
X318467D01*
G01X321733Y81500D02*
Y84833D01*
G01Y84167D02*
X322150Y84500D01*
X322567Y84750D01*
X323150Y84833D01*
X323567Y84750D01*
X324067Y84500D01*
G01X330000Y81500D02*
Y84833D01*
G01Y84250D02*
X329667Y84583D01*
X329167Y84750D01*
X328583Y84833D01*
X328000Y84667D01*
X327500Y84333D01*
X327167Y83833D01*
X327000Y83167D01*
X327167Y82500D01*
X327500Y82000D01*
X328000Y81667D01*
X328583Y81500D01*
X329167Y81583D01*
X329667Y81833D01*
X330000Y82167D01*
G01X335433Y84417D02*
X334850Y84750D01*
X334350Y84833D01*
X333683Y84667D01*
X333183Y84333D01*
X332850Y83750D01*
X332767Y83167D01*
X332850Y82583D01*
X333183Y82083D01*
X333683Y81667D01*
X334350Y81500D01*
X334933Y81667D01*
X335433Y82000D01*
G01X338450Y83750D02*
X341117D01*
X340867Y84333D01*
X340450Y84667D01*
X339867Y84833D01*
X339283Y84750D01*
X338783Y84500D01*
X338450Y83917D01*
X338283Y83417D01*
Y82917D01*
X338450Y82417D01*
X338867Y81917D01*
X339367Y81583D01*
X339950Y81500D01*
X340533Y81667D01*
X341117Y82167D01*
G01X348817Y84833D02*
X349817Y81500D01*
X350900Y84833D01*
X351983Y81500D01*
X352983Y84833D01*
G01X356500D02*
Y81500D01*
G01Y86167D02*
X356333Y86250D01*
Y86417D01*
X356500Y86500D01*
X356667Y86417D01*
Y86250D01*
X356500Y86167D01*
G01X363600Y86500D02*
Y81500D01*
G01Y82250D02*
X363267Y81833D01*
X362767Y81583D01*
X362183Y81500D01*
X361517Y81667D01*
X361017Y82083D01*
X360683Y82583D01*
X360600Y83167D01*
X360683Y83750D01*
X361017Y84250D01*
X361517Y84667D01*
X362183Y84833D01*
X362767Y84750D01*
X363183Y84583D01*
X363600Y84250D01*
G01X367700Y86500D02*
Y81500D01*
G01X366533Y84833D02*
X368867D01*
G01X371883Y81500D02*
Y86500D01*
G01Y84083D02*
X372300Y84500D01*
X372717Y84750D01*
X373383Y84833D01*
X373883Y84750D01*
X374467Y84417D01*
X374717Y83917D01*
Y81500D01*
G01X386167D02*
X382833Y83167D01*
X386167Y84833D01*
G01X389017Y82417D02*
X391183D01*
G01Y83917D02*
X389017D01*
G01X401133Y81500D02*
X401300Y82583D01*
X401550Y83500D01*
X401883Y84333D01*
X402300Y85250D01*
X402967Y86500D01*
X399633D01*
G01X410000Y81500D02*
Y84833D01*
G01Y83917D02*
X410250Y84333D01*
X410667Y84667D01*
X411250Y84833D01*
X411833Y84667D01*
X412250Y84333D01*
X412500Y83917D01*
Y81500D01*
G01Y83917D02*
X412750Y84333D01*
X413167Y84667D01*
X413750Y84833D01*
X414333Y84667D01*
X414750Y84333D01*
X415000Y83833D01*
Y81500D01*
G01X418100Y84833D02*
Y81500D01*
G01Y86167D02*
X417933Y86250D01*
Y86417D01*
X418100Y86500D01*
X418267Y86417D01*
Y86250D01*
X418100Y86167D01*
G01X423700Y81500D02*
Y86500D01*
G01X272500Y71500D02*
Y66500D01*
G01X271333Y69833D02*
X273667D01*
G01X276933Y66500D02*
Y69833D01*
G01Y69167D02*
X277350Y69500D01*
X277767Y69750D01*
X278350Y69833D01*
X278767Y69750D01*
X279267Y69500D01*
G01X285200Y66500D02*
Y69833D01*
G01Y69250D02*
X284867Y69583D01*
X284367Y69750D01*
X283783Y69833D01*
X283200Y69667D01*
X282700Y69333D01*
X282367Y68833D01*
X282200Y68167D01*
X282367Y67500D01*
X282700Y67000D01*
X283200Y66667D01*
X283783Y66500D01*
X284367Y66583D01*
X284867Y66833D01*
X285200Y67167D01*
G01X290633Y69417D02*
X290050Y69750D01*
X289550Y69833D01*
X288883Y69667D01*
X288383Y69333D01*
X288050Y68750D01*
X287967Y68167D01*
X288050Y67583D01*
X288383Y67083D01*
X288883Y66667D01*
X289550Y66500D01*
X290133Y66667D01*
X290633Y67000D01*
G01X293650Y68750D02*
X296317D01*
X296067Y69333D01*
X295650Y69667D01*
X295067Y69833D01*
X294483Y69750D01*
X293983Y69500D01*
X293650Y68917D01*
X293483Y68417D01*
Y67917D01*
X293650Y67417D01*
X294067Y66917D01*
X294567Y66583D01*
X295150Y66500D01*
X295733Y66667D01*
X296317Y67167D01*
G01X304017Y69833D02*
X305017Y66500D01*
X306100Y69833D01*
X307183Y66500D01*
X308183Y69833D01*
G01X311700D02*
Y66500D01*
G01Y71167D02*
X311533Y71250D01*
Y71417D01*
X311700Y71500D01*
X311867Y71417D01*
Y71250D01*
X311700Y71167D01*
G01X318800Y71500D02*
Y66500D01*
G01Y67250D02*
X318467Y66833D01*
X317967Y66583D01*
X317383Y66500D01*
X316717Y66667D01*
X316217Y67083D01*
X315883Y67583D01*
X315800Y68167D01*
X315883Y68750D01*
X316217Y69250D01*
X316717Y69667D01*
X317383Y69833D01*
X317967Y69750D01*
X318383Y69583D01*
X318800Y69250D01*
G01X322900Y71500D02*
Y66500D01*
G01X321733Y69833D02*
X324067D01*
G01X327083Y66500D02*
Y71500D01*
G01Y69083D02*
X327500Y69500D01*
X327917Y69750D01*
X328583Y69833D01*
X329083Y69750D01*
X329667Y69417D01*
X329917Y68917D01*
Y66500D01*
G01X338033D02*
X341367Y68167D01*
X338033Y69833D01*
G01X350733Y66500D02*
X350900Y67583D01*
X351150Y68500D01*
X351483Y69333D01*
X351900Y70250D01*
X352567Y71500D01*
X349233D01*
G01X359600Y66500D02*
Y69833D01*
G01Y68917D02*
X359850Y69333D01*
X360267Y69667D01*
X360850Y69833D01*
X361433Y69667D01*
X361850Y69333D01*
X362100Y68917D01*
Y66500D01*
G01Y68917D02*
X362350Y69333D01*
X362767Y69667D01*
X363350Y69833D01*
X363933Y69667D01*
X364350Y69333D01*
X364600Y68833D01*
Y66500D01*
G01X367700Y69833D02*
Y66500D01*
G01Y71167D02*
X367533Y71250D01*
Y71417D01*
X367700Y71500D01*
X367867Y71417D01*
Y71250D01*
X367700Y71167D01*
G01X373300Y66500D02*
Y71500D01*
G01X270833Y110000D02*
Y115000D01*
X272917D01*
X273583Y114750D01*
X274000Y114417D01*
X274167Y113750D01*
X274000Y113083D01*
X273500Y112667D01*
X272917Y112417D01*
X270833D01*
G01X272917D02*
X274167Y110000D01*
G01X276850Y112250D02*
X279517D01*
X279267Y112833D01*
X278850Y113167D01*
X278267Y113333D01*
X277683Y113250D01*
X277183Y113000D01*
X276850Y112417D01*
X276683Y111917D01*
Y111417D01*
X276850Y110917D01*
X277267Y110417D01*
X277767Y110083D01*
X278350Y110000D01*
X278933Y110167D01*
X279517Y110667D01*
G01X283700Y110000D02*
Y115000D01*
G01X290800Y110000D02*
Y113333D01*
G01Y112750D02*
X290467Y113083D01*
X289967Y113250D01*
X289383Y113333D01*
X288800Y113167D01*
X288300Y112833D01*
X287967Y112333D01*
X287800Y111667D01*
X287967Y111000D01*
X288300Y110500D01*
X288800Y110167D01*
X289383Y110000D01*
X289967Y110083D01*
X290467Y110333D01*
X290800Y110667D01*
G01X294900Y115000D02*
Y110000D01*
G01X293733Y113333D02*
X296067D01*
G01X300500D02*
Y110000D01*
G01Y114667D02*
X300333Y114750D01*
Y114917D01*
X300500Y115000D01*
X300667Y114917D01*
Y114750D01*
X300500Y114667D01*
G01X304600Y113333D02*
X306100Y110000D01*
X307600Y113333D01*
G01X310450Y112250D02*
X313117D01*
X312867Y112833D01*
X312450Y113167D01*
X311867Y113333D01*
X311283Y113250D01*
X310783Y113000D01*
X310450Y112417D01*
X310283Y111917D01*
Y111417D01*
X310450Y110917D01*
X310867Y110417D01*
X311367Y110083D01*
X311950Y110000D01*
X312533Y110167D01*
X313117Y110667D01*
G01X321400Y108333D02*
Y113333D01*
G01Y112583D02*
X321817Y113000D01*
X322233Y113250D01*
X322900Y113333D01*
X323483Y113250D01*
X324067Y112833D01*
X324317Y112250D01*
X324400Y111667D01*
X324317Y111083D01*
X324067Y110500D01*
X323567Y110167D01*
X322900Y110000D01*
X322317Y110083D01*
X321733Y110333D01*
X321400Y110667D01*
G01X328500Y110000D02*
X328000Y110083D01*
X327500Y110417D01*
X327167Y111000D01*
X327000Y111667D01*
X327167Y112333D01*
X327500Y112917D01*
X328000Y113250D01*
X328500Y113333D01*
X329000Y113250D01*
X329500Y112917D01*
X329833Y112333D01*
X329917Y111667D01*
X329833Y111000D01*
X329500Y110417D01*
X329000Y110083D01*
X328500Y110000D01*
G01X332850Y110583D02*
X333267Y110250D01*
X333850Y110000D01*
X334350D01*
X334850Y110167D01*
X335183Y110417D01*
X335350Y110750D01*
X335267Y111250D01*
X334933Y111500D01*
X333433Y112000D01*
X333100Y112583D01*
X333267Y113000D01*
X333600Y113250D01*
X334100Y113333D01*
X334600Y113250D01*
X335100Y113000D01*
G01X339700Y113333D02*
Y110000D01*
G01Y114667D02*
X339533Y114750D01*
Y114917D01*
X339700Y115000D01*
X339867Y114917D01*
Y114750D01*
X339700Y114667D01*
G01X345300Y115000D02*
Y110000D01*
G01X344133Y113333D02*
X346467D01*
G01X350900D02*
Y110000D01*
G01Y114667D02*
X350733Y114750D01*
Y114917D01*
X350900Y115000D01*
X351067Y114917D01*
Y114750D01*
X350900Y114667D01*
G01X356500Y110000D02*
X356000Y110083D01*
X355500Y110417D01*
X355167Y111000D01*
X355000Y111667D01*
X355167Y112333D01*
X355500Y112917D01*
X356000Y113250D01*
X356500Y113333D01*
X357000Y113250D01*
X357500Y112917D01*
X357833Y112333D01*
X357917Y111667D01*
X357833Y111000D01*
X357500Y110417D01*
X357000Y110083D01*
X356500Y110000D01*
G01X360683D02*
Y113333D01*
G01Y112500D02*
X361017Y112917D01*
X361517Y113250D01*
X362183Y113333D01*
X362767Y113250D01*
X363267Y112917D01*
X363517Y112333D01*
Y110000D01*
G01X371800D02*
Y115000D01*
G01Y112500D02*
X372217Y113000D01*
X372717Y113250D01*
X373217Y113333D01*
X373967Y113167D01*
X374467Y112833D01*
X374800Y112250D01*
Y111583D01*
X374633Y110917D01*
X374300Y110417D01*
X373717Y110083D01*
X373217Y110000D01*
X372717Y110083D01*
X372217Y110333D01*
X371800Y110750D01*
G01X377650Y112250D02*
X380317D01*
X380067Y112833D01*
X379650Y113167D01*
X379067Y113333D01*
X378483Y113250D01*
X377983Y113000D01*
X377650Y112417D01*
X377483Y111917D01*
Y111417D01*
X377650Y110917D01*
X378067Y110417D01*
X378567Y110083D01*
X379150Y110000D01*
X379733Y110167D01*
X380317Y110667D01*
G01X384500Y115000D02*
Y110000D01*
G01X383333Y113333D02*
X385667D01*
G01X388017D02*
X389017Y110000D01*
X390100Y113333D01*
X391183Y110000D01*
X392183Y113333D01*
G01X394450Y112250D02*
X397117D01*
X396867Y112833D01*
X396450Y113167D01*
X395867Y113333D01*
X395283Y113250D01*
X394783Y113000D01*
X394450Y112417D01*
X394283Y111917D01*
Y111417D01*
X394450Y110917D01*
X394867Y110417D01*
X395367Y110083D01*
X395950Y110000D01*
X396533Y110167D01*
X397117Y110667D01*
G01X400050Y112250D02*
X402717D01*
X402467Y112833D01*
X402050Y113167D01*
X401467Y113333D01*
X400883Y113250D01*
X400383Y113000D01*
X400050Y112417D01*
X399883Y111917D01*
Y111417D01*
X400050Y110917D01*
X400467Y110417D01*
X400967Y110083D01*
X401550Y110000D01*
X402133Y110167D01*
X402717Y110667D01*
G01X405483Y110000D02*
Y113333D01*
G01Y112500D02*
X405817Y112917D01*
X406317Y113250D01*
X406983Y113333D01*
X407567Y113250D01*
X408067Y112917D01*
X408317Y112333D01*
Y110000D01*
G01X419600D02*
Y113333D01*
G01Y112750D02*
X419267Y113083D01*
X418767Y113250D01*
X418183Y113333D01*
X417600Y113167D01*
X417100Y112833D01*
X416767Y112333D01*
X416600Y111667D01*
X416767Y111000D01*
X417100Y110500D01*
X417600Y110167D01*
X418183Y110000D01*
X418767Y110083D01*
X419267Y110333D01*
X419600Y110667D01*
G01X422283Y110000D02*
Y113333D01*
G01Y112500D02*
X422617Y112917D01*
X423117Y113250D01*
X423783Y113333D01*
X424367Y113250D01*
X424867Y112917D01*
X425117Y112333D01*
Y110000D01*
G01X427550Y108500D02*
X428050Y108333D01*
X428717Y108500D01*
X429133Y108833D01*
X429467Y109250D01*
X429967Y110583D01*
X431050Y113333D01*
G01X428383D02*
X429967Y110583D01*
G01X439000Y108333D02*
Y113333D01*
G01Y112583D02*
X439417Y113000D01*
X439833Y113250D01*
X440500Y113333D01*
X441083Y113250D01*
X441667Y112833D01*
X441917Y112250D01*
X442000Y111667D01*
X441917Y111083D01*
X441667Y110500D01*
X441167Y110167D01*
X440500Y110000D01*
X439917Y110083D01*
X439333Y110333D01*
X439000Y110667D01*
G01X447600Y110000D02*
Y113333D01*
G01Y112750D02*
X447267Y113083D01*
X446767Y113250D01*
X446183Y113333D01*
X445600Y113167D01*
X445100Y112833D01*
X444767Y112333D01*
X444600Y111667D01*
X444767Y111000D01*
X445100Y110500D01*
X445600Y110167D01*
X446183Y110000D01*
X446767Y110083D01*
X447267Y110333D01*
X447600Y110667D01*
G01X453200Y115000D02*
Y110000D01*
G01Y110750D02*
X452867Y110333D01*
X452367Y110083D01*
X451783Y110000D01*
X451117Y110167D01*
X450617Y110583D01*
X450283Y111083D01*
X450200Y111667D01*
X450283Y112250D01*
X450617Y112750D01*
X451117Y113167D01*
X451783Y113333D01*
X452367Y113250D01*
X452783Y113083D01*
X453200Y112750D01*
G01X462900Y115000D02*
Y110000D01*
G01X461733Y113333D02*
X464067D01*
G01X468500Y110000D02*
X468000Y110083D01*
X467500Y110417D01*
X467167Y111000D01*
X467000Y111667D01*
X467167Y112333D01*
X467500Y112917D01*
X468000Y113250D01*
X468500Y113333D01*
X469000Y113250D01*
X469500Y112917D01*
X469833Y112333D01*
X469917Y111667D01*
X469833Y111000D01*
X469500Y110417D01*
X469000Y110083D01*
X468500Y110000D01*
G01X478200Y108333D02*
Y113333D01*
G01Y112583D02*
X478617Y113000D01*
X479033Y113250D01*
X479700Y113333D01*
X480283Y113250D01*
X480867Y112833D01*
X481117Y112250D01*
X481200Y111667D01*
X481117Y111083D01*
X480867Y110500D01*
X480367Y110167D01*
X479700Y110000D01*
X479117Y110083D01*
X478533Y110333D01*
X478200Y110667D01*
G01X486800Y110000D02*
Y113333D01*
G01Y112750D02*
X486467Y113083D01*
X485967Y113250D01*
X485383Y113333D01*
X484800Y113167D01*
X484300Y112833D01*
X483967Y112333D01*
X483800Y111667D01*
X483967Y111000D01*
X484300Y110500D01*
X484800Y110167D01*
X485383Y110000D01*
X485967Y110083D01*
X486467Y110333D01*
X486800Y110667D01*
G01X492400Y115000D02*
Y110000D01*
G01Y110750D02*
X492067Y110333D01*
X491567Y110083D01*
X490983Y110000D01*
X490317Y110167D01*
X489817Y110583D01*
X489483Y111083D01*
X489400Y111667D01*
X489483Y112250D01*
X489817Y112750D01*
X490317Y113167D01*
X490983Y113333D01*
X491567Y113250D01*
X491983Y113083D01*
X492400Y112750D01*
G01X264000Y75500D02*
X694500D01*
G01X264000Y90500D02*
X694500D01*
G01X271250Y141583D02*
X271667Y141250D01*
X272250Y141000D01*
X272750D01*
X273250Y141167D01*
X273583Y141417D01*
X273750Y141750D01*
X273667Y142250D01*
X273333Y142500D01*
X271833Y143000D01*
X271500Y143583D01*
X271667Y144000D01*
X272000Y144250D01*
X272500Y144333D01*
X273000Y144250D01*
X273500Y144000D01*
G01X276600Y139333D02*
Y144333D01*
G01Y143583D02*
X277017Y144000D01*
X277433Y144250D01*
X278100Y144333D01*
X278683Y144250D01*
X279267Y143833D01*
X279517Y143250D01*
X279600Y142667D01*
X279517Y142083D01*
X279267Y141500D01*
X278767Y141167D01*
X278100Y141000D01*
X277517Y141083D01*
X276933Y141333D01*
X276600Y141667D01*
G01X282450Y143250D02*
X285117D01*
X284867Y143833D01*
X284450Y144167D01*
X283867Y144333D01*
X283283Y144250D01*
X282783Y144000D01*
X282450Y143417D01*
X282283Y142917D01*
Y142417D01*
X282450Y141917D01*
X282867Y141417D01*
X283367Y141083D01*
X283950Y141000D01*
X284533Y141167D01*
X285117Y141667D01*
G01X290633Y143917D02*
X290050Y144250D01*
X289550Y144333D01*
X288883Y144167D01*
X288383Y143833D01*
X288050Y143250D01*
X287967Y142667D01*
X288050Y142083D01*
X288383Y141583D01*
X288883Y141167D01*
X289550Y141000D01*
X290133Y141167D01*
X290633Y141500D01*
G01X294900Y144333D02*
Y141000D01*
G01Y145667D02*
X294733Y145750D01*
Y145917D01*
X294900Y146000D01*
X295067Y145917D01*
Y145750D01*
X294900Y145667D01*
G01X300000Y141000D02*
Y145250D01*
X300167Y145667D01*
X300500Y145917D01*
X301000Y146000D01*
X301500Y145833D01*
X301750Y145417D01*
G01X300750Y144000D02*
X299083D01*
G01X306100Y144333D02*
Y141000D01*
G01Y145667D02*
X305933Y145750D01*
Y145917D01*
X306100Y146000D01*
X306267Y145917D01*
Y145750D01*
X306100Y145667D01*
G01X313033Y143917D02*
X312450Y144250D01*
X311950Y144333D01*
X311283Y144167D01*
X310783Y143833D01*
X310450Y143250D01*
X310367Y142667D01*
X310450Y142083D01*
X310783Y141583D01*
X311283Y141167D01*
X311950Y141000D01*
X312533Y141167D01*
X313033Y141500D01*
G01X318800Y141000D02*
Y144333D01*
G01Y143750D02*
X318467Y144083D01*
X317967Y144250D01*
X317383Y144333D01*
X316800Y144167D01*
X316300Y143833D01*
X315967Y143333D01*
X315800Y142667D01*
X315967Y142000D01*
X316300Y141500D01*
X316800Y141167D01*
X317383Y141000D01*
X317967Y141083D01*
X318467Y141333D01*
X318800Y141667D01*
G01X322900Y146000D02*
Y141000D01*
G01X321733Y144333D02*
X324067D01*
G01X328500D02*
Y141000D01*
G01Y145667D02*
X328333Y145750D01*
Y145917D01*
X328500Y146000D01*
X328667Y145917D01*
Y145750D01*
X328500Y145667D01*
G01X334100Y141000D02*
X333600Y141083D01*
X333100Y141417D01*
X332767Y142000D01*
X332600Y142667D01*
X332767Y143333D01*
X333100Y143917D01*
X333600Y144250D01*
X334100Y144333D01*
X334600Y144250D01*
X335100Y143917D01*
X335433Y143333D01*
X335517Y142667D01*
X335433Y142000D01*
X335100Y141417D01*
X334600Y141083D01*
X334100Y141000D01*
G01X338283D02*
Y144333D01*
G01Y143500D02*
X338617Y143917D01*
X339117Y144250D01*
X339783Y144333D01*
X340367Y144250D01*
X340867Y143917D01*
X341117Y143333D01*
Y141000D01*
G01X345300Y140833D02*
X345133Y140917D01*
Y141083D01*
X345300Y141167D01*
X345467Y141083D01*
Y140917D01*
X345300Y140833D01*
G01X270750Y125000D02*
Y130000D01*
G01X274250D02*
Y125000D01*
G01Y127500D02*
X270750D01*
G01X276267Y125000D02*
Y130000D01*
X277933D01*
X278600Y129750D01*
X279100Y129417D01*
X279517Y128917D01*
X279850Y128333D01*
X279933Y127500D01*
X279850Y126667D01*
X279517Y126083D01*
X279100Y125583D01*
X278600Y125250D01*
X277933Y125000D01*
X276267D01*
G01X282700Y130000D02*
X284700D01*
G01X283700D02*
Y125000D01*
G01X282700D02*
X284700D01*
G01X293233D02*
Y130000D01*
X295233D01*
X295900Y129750D01*
X296400Y129167D01*
X296567Y128500D01*
X296400Y127833D01*
X295983Y127333D01*
X295233Y127083D01*
X293233D01*
G01X302333Y129583D02*
X301833Y129833D01*
X301250Y130000D01*
X300583D01*
X299833Y129750D01*
X299250Y129333D01*
X298833Y128833D01*
X298500Y128000D01*
X298417Y127250D01*
X298583Y126500D01*
X298833Y126000D01*
X299333Y125500D01*
X299917Y125167D01*
X300500Y125000D01*
X301083D01*
X301667Y125167D01*
X302167Y125417D01*
X302583Y125750D01*
G01X306767Y127667D02*
X307100Y127917D01*
X307350Y128333D01*
X307517Y128917D01*
X307350Y129417D01*
X307017Y129750D01*
X306433Y130000D01*
X304183D01*
Y125000D01*
X306933D01*
X307517Y125333D01*
X307850Y125833D01*
X308017Y126417D01*
X307850Y127000D01*
X307350Y127500D01*
X306767Y127667D01*
X304183D01*
G01X311700Y124833D02*
X311533Y124917D01*
Y125083D01*
X311700Y125167D01*
X311867Y125083D01*
Y124917D01*
X311700Y124833D01*
G01X270750Y150667D02*
X271417Y150250D01*
X272167Y150000D01*
X272833D01*
X273500Y150250D01*
X274000Y150667D01*
X274250Y151250D01*
X274083Y151833D01*
X273667Y152333D01*
X272917Y152667D01*
X271917Y152833D01*
X271333Y153167D01*
X271083Y153750D01*
X271250Y154333D01*
X271667Y154750D01*
X272250Y155000D01*
X272833D01*
X273417Y154833D01*
X273917Y154417D01*
G01X276850Y152250D02*
X279517D01*
X279267Y152833D01*
X278850Y153167D01*
X278267Y153333D01*
X277683Y153250D01*
X277183Y153000D01*
X276850Y152417D01*
X276683Y151917D01*
Y151417D01*
X276850Y150917D01*
X277267Y150417D01*
X277767Y150083D01*
X278350Y150000D01*
X278933Y150167D01*
X279517Y150667D01*
G01X282533Y150000D02*
Y153333D01*
G01Y152667D02*
X282950Y153000D01*
X283367Y153250D01*
X283950Y153333D01*
X284367Y153250D01*
X284867Y153000D01*
G01X287800Y153333D02*
X289300Y150000D01*
X290800Y153333D01*
G01X293650Y152250D02*
X296317D01*
X296067Y152833D01*
X295650Y153167D01*
X295067Y153333D01*
X294483Y153250D01*
X293983Y153000D01*
X293650Y152417D01*
X293483Y151917D01*
Y151417D01*
X293650Y150917D01*
X294067Y150417D01*
X294567Y150083D01*
X295150Y150000D01*
X295733Y150167D01*
X296317Y150667D01*
G01X299333Y150000D02*
Y153333D01*
G01Y152667D02*
X299750Y153000D01*
X300167Y153250D01*
X300750Y153333D01*
X301167Y153250D01*
X301667Y153000D01*
G01X310033Y150000D02*
Y155000D01*
X312033D01*
X312700Y154750D01*
X313200Y154167D01*
X313367Y153500D01*
X313200Y152833D01*
X312783Y152333D01*
X312033Y152083D01*
X310033D01*
G01X319133Y154583D02*
X318633Y154833D01*
X318050Y155000D01*
X317383D01*
X316633Y154750D01*
X316050Y154333D01*
X315633Y153833D01*
X315300Y153000D01*
X315217Y152250D01*
X315383Y151500D01*
X315633Y151000D01*
X316133Y150500D01*
X316717Y150167D01*
X317300Y150000D01*
X317883D01*
X318467Y150167D01*
X318967Y150417D01*
X319383Y150750D01*
G01X323567Y152667D02*
X323900Y152917D01*
X324150Y153333D01*
X324317Y153917D01*
X324150Y154417D01*
X323817Y154750D01*
X323233Y155000D01*
X320983D01*
Y150000D01*
X323733D01*
X324317Y150333D01*
X324650Y150833D01*
X324817Y151417D01*
X324650Y152000D01*
X324150Y152500D01*
X323567Y152667D01*
X320983D01*
G01X328500Y149833D02*
X328333Y149917D01*
Y150083D01*
X328500Y150167D01*
X328667Y150083D01*
Y149917D01*
X328500Y149833D01*
G01Y152083D02*
X328333Y152167D01*
Y152333D01*
X328500Y152417D01*
X328667Y152333D01*
Y152167D01*
X328500Y152083D01*
G01X332517Y150000D02*
Y155000D01*
X335683D01*
G01X334517Y152583D02*
X332517D01*
G01X339700Y150000D02*
X339200Y150083D01*
X338700Y150417D01*
X338367Y151000D01*
X338200Y151667D01*
X338367Y152333D01*
X338700Y152917D01*
X339200Y153250D01*
X339700Y153333D01*
X340200Y153250D01*
X340700Y152917D01*
X341033Y152333D01*
X341117Y151667D01*
X341033Y151000D01*
X340700Y150417D01*
X340200Y150083D01*
X339700Y150000D01*
G01X345300D02*
Y155000D01*
G01X350900Y150000D02*
Y155000D01*
G01X356500Y150000D02*
X356000Y150083D01*
X355500Y150417D01*
X355167Y151000D01*
X355000Y151667D01*
X355167Y152333D01*
X355500Y152917D01*
X356000Y153250D01*
X356500Y153333D01*
X357000Y153250D01*
X357500Y152917D01*
X357833Y152333D01*
X357917Y151667D01*
X357833Y151000D01*
X357500Y150417D01*
X357000Y150083D01*
X356500Y150000D01*
G01X360017Y153333D02*
X361017Y150000D01*
X362100Y153333D01*
X363183Y150000D01*
X364183Y153333D01*
G01X372133Y150000D02*
Y153333D01*
G01Y152667D02*
X372550Y153000D01*
X372967Y153250D01*
X373550Y153333D01*
X373967Y153250D01*
X374467Y153000D01*
G01X378900Y153333D02*
Y150000D01*
G01Y154667D02*
X378733Y154750D01*
Y154917D01*
X378900Y155000D01*
X379067Y154917D01*
Y154750D01*
X378900Y154667D01*
G01X383333Y148750D02*
X383917Y148417D01*
X384583Y148333D01*
X385167Y148417D01*
X385667Y148833D01*
X386000Y149417D01*
Y153333D01*
G01Y152667D02*
X385667Y153000D01*
X385167Y153250D01*
X384583Y153333D01*
X383917Y153167D01*
X383500Y152833D01*
X383167Y152250D01*
X383000Y151667D01*
X383083Y151167D01*
X383417Y150583D01*
X383917Y150167D01*
X384583Y150000D01*
X385083Y150083D01*
X385667Y150417D01*
X386000Y150750D01*
G01X388683Y150000D02*
Y155000D01*
G01Y152583D02*
X389100Y153000D01*
X389517Y153250D01*
X390183Y153333D01*
X390683Y153250D01*
X391267Y152917D01*
X391517Y152417D01*
Y150000D01*
G01X395700Y155000D02*
Y150000D01*
G01X394533Y153333D02*
X396867D01*
G01X405650Y150583D02*
X406067Y150250D01*
X406650Y150000D01*
X407150D01*
X407650Y150167D01*
X407983Y150417D01*
X408150Y150750D01*
X408067Y151250D01*
X407733Y151500D01*
X406233Y152000D01*
X405900Y152583D01*
X406067Y153000D01*
X406400Y153250D01*
X406900Y153333D01*
X407400Y153250D01*
X407900Y153000D01*
G01X412500Y153333D02*
Y150000D01*
G01Y154667D02*
X412333Y154750D01*
Y154917D01*
X412500Y155000D01*
X412667Y154917D01*
Y154750D01*
X412500Y154667D01*
G01X419600Y155000D02*
Y150000D01*
G01Y150750D02*
X419267Y150333D01*
X418767Y150083D01*
X418183Y150000D01*
X417517Y150167D01*
X417017Y150583D01*
X416683Y151083D01*
X416600Y151667D01*
X416683Y152250D01*
X417017Y152750D01*
X417517Y153167D01*
X418183Y153333D01*
X418767Y153250D01*
X419183Y153083D01*
X419600Y152750D01*
G01X422450Y152250D02*
X425117D01*
X424867Y152833D01*
X424450Y153167D01*
X423867Y153333D01*
X423283Y153250D01*
X422783Y153000D01*
X422450Y152417D01*
X422283Y151917D01*
Y151417D01*
X422450Y150917D01*
X422867Y150417D01*
X423367Y150083D01*
X423950Y150000D01*
X424533Y150167D01*
X425117Y150667D01*
G01X433650Y150583D02*
X434067Y150250D01*
X434650Y150000D01*
X435150D01*
X435650Y150167D01*
X435983Y150417D01*
X436150Y150750D01*
X436067Y151250D01*
X435733Y151500D01*
X434233Y152000D01*
X433900Y152583D01*
X434067Y153000D01*
X434400Y153250D01*
X434900Y153333D01*
X435400Y153250D01*
X435900Y153000D01*
G01X439000Y148333D02*
Y153333D01*
G01Y152583D02*
X439417Y153000D01*
X439833Y153250D01*
X440500Y153333D01*
X441083Y153250D01*
X441667Y152833D01*
X441917Y152250D01*
X442000Y151667D01*
X441917Y151083D01*
X441667Y150500D01*
X441167Y150167D01*
X440500Y150000D01*
X439917Y150083D01*
X439333Y150333D01*
X439000Y150667D01*
G01X444850Y152250D02*
X447517D01*
X447267Y152833D01*
X446850Y153167D01*
X446267Y153333D01*
X445683Y153250D01*
X445183Y153000D01*
X444850Y152417D01*
X444683Y151917D01*
Y151417D01*
X444850Y150917D01*
X445267Y150417D01*
X445767Y150083D01*
X446350Y150000D01*
X446933Y150167D01*
X447517Y150667D01*
G01X453033Y152917D02*
X452450Y153250D01*
X451950Y153333D01*
X451283Y153167D01*
X450783Y152833D01*
X450450Y152250D01*
X450367Y151667D01*
X450450Y151083D01*
X450783Y150583D01*
X451283Y150167D01*
X451950Y150000D01*
X452533Y150167D01*
X453033Y150500D01*
G01X462733Y149083D02*
X463067Y150167D01*
G01X468500Y153333D02*
Y150000D01*
G01Y154667D02*
X468333Y154750D01*
Y154917D01*
X468500Y155000D01*
X468667Y154917D01*
Y154750D01*
X468500Y154667D01*
G01X473600Y150000D02*
Y154250D01*
X473767Y154667D01*
X474100Y154917D01*
X474600Y155000D01*
X475100Y154833D01*
X475350Y154417D01*
G01X474350Y153000D02*
X472683D01*
G01X484050Y150583D02*
X484467Y150250D01*
X485050Y150000D01*
X485550D01*
X486050Y150167D01*
X486383Y150417D01*
X486550Y150750D01*
X486467Y151250D01*
X486133Y151500D01*
X484633Y152000D01*
X484300Y152583D01*
X484467Y153000D01*
X484800Y153250D01*
X485300Y153333D01*
X485800Y153250D01*
X486300Y153000D01*
G01X490900Y155000D02*
Y150000D01*
G01X489733Y153333D02*
X492067D01*
G01X498000Y150000D02*
Y153333D01*
G01Y152750D02*
X497667Y153083D01*
X497167Y153250D01*
X496583Y153333D01*
X496000Y153167D01*
X495500Y152833D01*
X495167Y152333D01*
X495000Y151667D01*
X495167Y151000D01*
X495500Y150500D01*
X496000Y150167D01*
X496583Y150000D01*
X497167Y150083D01*
X497667Y150333D01*
X498000Y150667D01*
G01X503433Y152917D02*
X502850Y153250D01*
X502350Y153333D01*
X501683Y153167D01*
X501183Y152833D01*
X500850Y152250D01*
X500767Y151667D01*
X500850Y151083D01*
X501183Y150583D01*
X501683Y150167D01*
X502350Y150000D01*
X502933Y150167D01*
X503433Y150500D01*
G01X506283Y150000D02*
Y155000D01*
G01X508950Y153333D02*
X506283Y151417D01*
G01X507367Y152167D02*
X509117Y150000D01*
G01X517483Y153333D02*
Y151000D01*
X517817Y150417D01*
X518317Y150083D01*
X518900Y150000D01*
X519483Y150083D01*
X519983Y150417D01*
X520317Y151000D01*
G01Y150000D02*
Y153333D01*
G01X523000Y148333D02*
Y153333D01*
G01Y152583D02*
X523417Y153000D01*
X523833Y153250D01*
X524500Y153333D01*
X525083Y153250D01*
X525667Y152833D01*
X525917Y152250D01*
X526000Y151667D01*
X525917Y151083D01*
X525667Y150500D01*
X525167Y150167D01*
X524500Y150000D01*
X523917Y150083D01*
X523333Y150333D01*
X523000Y150667D01*
G01X533617Y153333D02*
X534617Y150000D01*
X535700Y153333D01*
X536783Y150000D01*
X537783Y153333D01*
G01X541300D02*
Y150000D01*
G01Y154667D02*
X541133Y154750D01*
Y154917D01*
X541300Y155000D01*
X541467Y154917D01*
Y154750D01*
X541300Y154667D01*
G01X546900Y155000D02*
Y150000D01*
G01X545733Y153333D02*
X548067D01*
G01X551083Y150000D02*
Y155000D01*
G01Y152583D02*
X551500Y153000D01*
X551917Y153250D01*
X552583Y153333D01*
X553083Y153250D01*
X553667Y152917D01*
X553917Y152417D01*
Y150000D01*
G01X558100D02*
X557600Y150083D01*
X557100Y150417D01*
X556767Y151000D01*
X556600Y151667D01*
X556767Y152333D01*
X557100Y152917D01*
X557600Y153250D01*
X558100Y153333D01*
X558600Y153250D01*
X559100Y152917D01*
X559433Y152333D01*
X559517Y151667D01*
X559433Y151000D01*
X559100Y150417D01*
X558600Y150083D01*
X558100Y150000D01*
G01X562283Y153333D02*
Y151000D01*
X562617Y150417D01*
X563117Y150083D01*
X563700Y150000D01*
X564283Y150083D01*
X564783Y150417D01*
X565117Y151000D01*
G01Y150000D02*
Y153333D01*
G01X569300Y155000D02*
Y150000D01*
G01X568133Y153333D02*
X570467D01*
G01X272500Y170000D02*
Y165000D01*
G01X270583Y170000D02*
X274417D01*
G01X276933Y165000D02*
Y168333D01*
G01Y167667D02*
X277350Y168000D01*
X277767Y168250D01*
X278350Y168333D01*
X278767Y168250D01*
X279267Y168000D01*
G01X285200Y165000D02*
Y168333D01*
G01Y167750D02*
X284867Y168083D01*
X284367Y168250D01*
X283783Y168333D01*
X283200Y168167D01*
X282700Y167833D01*
X282367Y167333D01*
X282200Y166667D01*
X282367Y166000D01*
X282700Y165500D01*
X283200Y165167D01*
X283783Y165000D01*
X284367Y165083D01*
X284867Y165333D01*
X285200Y165667D01*
G01X290800Y170000D02*
Y165000D01*
G01Y165750D02*
X290467Y165333D01*
X289967Y165083D01*
X289383Y165000D01*
X288717Y165167D01*
X288217Y165583D01*
X287883Y166083D01*
X287800Y166667D01*
X287883Y167250D01*
X288217Y167750D01*
X288717Y168167D01*
X289383Y168333D01*
X289967Y168250D01*
X290383Y168083D01*
X290800Y167750D01*
G01X294900Y168333D02*
Y165000D01*
G01Y169667D02*
X294733Y169750D01*
Y169917D01*
X294900Y170000D01*
X295067Y169917D01*
Y169750D01*
X294900Y169667D01*
G01X300500Y170000D02*
Y165000D01*
G01X299333Y168333D02*
X301667D01*
G01X306100D02*
Y165000D01*
G01Y169667D02*
X305933Y169750D01*
Y169917D01*
X306100Y170000D01*
X306267Y169917D01*
Y169750D01*
X306100Y169667D01*
G01X311700Y165000D02*
X311200Y165083D01*
X310700Y165417D01*
X310367Y166000D01*
X310200Y166667D01*
X310367Y167333D01*
X310700Y167917D01*
X311200Y168250D01*
X311700Y168333D01*
X312200Y168250D01*
X312700Y167917D01*
X313033Y167333D01*
X313117Y166667D01*
X313033Y166000D01*
X312700Y165417D01*
X312200Y165083D01*
X311700Y165000D01*
G01X315883D02*
Y168333D01*
G01Y167500D02*
X316217Y167917D01*
X316717Y168250D01*
X317383Y168333D01*
X317967Y168250D01*
X318467Y167917D01*
X318717Y167333D01*
Y165000D01*
G01X324400D02*
Y168333D01*
G01Y167750D02*
X324067Y168083D01*
X323567Y168250D01*
X322983Y168333D01*
X322400Y168167D01*
X321900Y167833D01*
X321567Y167333D01*
X321400Y166667D01*
X321567Y166000D01*
X321900Y165500D01*
X322400Y165167D01*
X322983Y165000D01*
X323567Y165083D01*
X324067Y165333D01*
X324400Y165667D01*
G01X328500Y165000D02*
Y170000D01*
G01X338033Y165000D02*
Y170000D01*
X340033D01*
X340700Y169750D01*
X341200Y169167D01*
X341367Y168500D01*
X341200Y167833D01*
X340783Y167333D01*
X340033Y167083D01*
X338033D01*
G01X347133Y169583D02*
X346633Y169833D01*
X346050Y170000D01*
X345383D01*
X344633Y169750D01*
X344050Y169333D01*
X343633Y168833D01*
X343300Y168000D01*
X343217Y167250D01*
X343383Y166500D01*
X343633Y166000D01*
X344133Y165500D01*
X344717Y165167D01*
X345300Y165000D01*
X345883D01*
X346467Y165167D01*
X346967Y165417D01*
X347383Y165750D01*
G01X351567Y167667D02*
X351900Y167917D01*
X352150Y168333D01*
X352317Y168917D01*
X352150Y169417D01*
X351817Y169750D01*
X351233Y170000D01*
X348983D01*
Y165000D01*
X351733D01*
X352317Y165333D01*
X352650Y165833D01*
X352817Y166417D01*
X352650Y167000D01*
X352150Y167500D01*
X351567Y167667D01*
X348983D01*
G01X356500Y164833D02*
X356333Y164917D01*
Y165083D01*
X356500Y165167D01*
X356667Y165083D01*
Y164917D01*
X356500Y164833D01*
G01X264000Y135500D02*
X694500D01*
G01X264000Y160500D02*
X694500D01*
G01X322623Y303963D02*
X322890Y304163D01*
X323090Y304497D01*
X323223Y304963D01*
X323090Y305363D01*
X322823Y305630D01*
X322357Y305830D01*
X320557D01*
Y301830D01*
X322757D01*
X323223Y302097D01*
X323490Y302497D01*
X323623Y302963D01*
X323490Y303430D01*
X323090Y303830D01*
X322623Y303963D01*
X320557D01*
G01X320423Y351330D02*
X322090Y355330D01*
X323757Y351330D01*
G01X323157Y352730D02*
X321023D01*
G01X270000Y374000D02*
Y369000D01*
G01X268833Y372333D02*
X271167D01*
G01X275600Y369000D02*
X275100Y369083D01*
X274600Y369417D01*
X274267Y370000D01*
X274100Y370667D01*
X274267Y371333D01*
X274600Y371917D01*
X275100Y372250D01*
X275600Y372333D01*
X276100Y372250D01*
X276600Y371917D01*
X276933Y371333D01*
X277017Y370667D01*
X276933Y370000D01*
X276600Y369417D01*
X276100Y369083D01*
X275600Y369000D01*
G01X281200D02*
Y374000D01*
G01X285550Y371250D02*
X288217D01*
X287967Y371833D01*
X287550Y372167D01*
X286967Y372333D01*
X286383Y372250D01*
X285883Y372000D01*
X285550Y371417D01*
X285383Y370917D01*
Y370417D01*
X285550Y369917D01*
X285967Y369417D01*
X286467Y369083D01*
X287050Y369000D01*
X287633Y369167D01*
X288217Y369667D01*
G01X291233Y369000D02*
Y372333D01*
G01Y371667D02*
X291650Y372000D01*
X292067Y372250D01*
X292650Y372333D01*
X293067Y372250D01*
X293567Y372000D01*
G01X299500Y369000D02*
Y372333D01*
G01Y371750D02*
X299167Y372083D01*
X298667Y372250D01*
X298083Y372333D01*
X297500Y372167D01*
X297000Y371833D01*
X296667Y371333D01*
X296500Y370667D01*
X296667Y370000D01*
X297000Y369500D01*
X297500Y369167D01*
X298083Y369000D01*
X298667Y369083D01*
X299167Y369333D01*
X299500Y369667D01*
G01X302183Y369000D02*
Y372333D01*
G01Y371500D02*
X302517Y371917D01*
X303017Y372250D01*
X303683Y372333D01*
X304267Y372250D01*
X304767Y371917D01*
X305017Y371333D01*
Y369000D01*
G01X310533Y371917D02*
X309950Y372250D01*
X309450Y372333D01*
X308783Y372167D01*
X308283Y371833D01*
X307950Y371250D01*
X307867Y370667D01*
X307950Y370083D01*
X308283Y369583D01*
X308783Y369167D01*
X309450Y369000D01*
X310033Y369167D01*
X310533Y369500D01*
G01X313550Y371250D02*
X316217D01*
X315967Y371833D01*
X315550Y372167D01*
X314967Y372333D01*
X314383Y372250D01*
X313883Y372000D01*
X313550Y371417D01*
X313383Y370917D01*
Y370417D01*
X313550Y369917D01*
X313967Y369417D01*
X314467Y369083D01*
X315050Y369000D01*
X315633Y369167D01*
X316217Y369667D01*
G01X326000Y374000D02*
Y369000D01*
G01X324833Y372333D02*
X327167D01*
G01X333100Y369000D02*
Y372333D01*
G01Y371750D02*
X332767Y372083D01*
X332267Y372250D01*
X331683Y372333D01*
X331100Y372167D01*
X330600Y371833D01*
X330267Y371333D01*
X330100Y370667D01*
X330267Y370000D01*
X330600Y369500D01*
X331100Y369167D01*
X331683Y369000D01*
X332267Y369083D01*
X332767Y369333D01*
X333100Y369667D01*
G01X335700Y369000D02*
Y374000D01*
G01Y371500D02*
X336117Y372000D01*
X336617Y372250D01*
X337117Y372333D01*
X337867Y372167D01*
X338367Y371833D01*
X338700Y371250D01*
Y370583D01*
X338533Y369917D01*
X338200Y369417D01*
X337617Y369083D01*
X337117Y369000D01*
X336617Y369083D01*
X336117Y369333D01*
X335700Y369750D01*
G01X342800Y369000D02*
Y374000D01*
G01X347150Y371250D02*
X349817D01*
X349567Y371833D01*
X349150Y372167D01*
X348567Y372333D01*
X347983Y372250D01*
X347483Y372000D01*
X347150Y371417D01*
X346983Y370917D01*
Y370417D01*
X347150Y369917D01*
X347567Y369417D01*
X348067Y369083D01*
X348650Y369000D01*
X349233Y369167D01*
X349817Y369667D01*
G01X354000Y368833D02*
X353833Y368917D01*
Y369083D01*
X354000Y369167D01*
X354167Y369083D01*
Y368917D01*
X354000Y368833D01*
G01X268667Y379750D02*
X269250Y379417D01*
X269750Y379333D01*
X270417Y379500D01*
X270917Y379917D01*
X271167Y380667D01*
Y384333D01*
G01Y385667D02*
X271000Y385750D01*
Y385917D01*
X271167Y386000D01*
X271333Y385917D01*
Y385750D01*
X271167Y385667D01*
G01X274183Y384333D02*
Y382000D01*
X274517Y381417D01*
X275017Y381083D01*
X275600Y381000D01*
X276183Y381083D01*
X276683Y381417D01*
X277017Y382000D01*
G01Y381000D02*
Y384333D01*
G01X279783Y381000D02*
Y384333D01*
G01Y383500D02*
X280117Y383917D01*
X280617Y384250D01*
X281283Y384333D01*
X281867Y384250D01*
X282367Y383917D01*
X282617Y383333D01*
Y381000D01*
G01X288133Y383917D02*
X287550Y384250D01*
X287050Y384333D01*
X286383Y384167D01*
X285883Y383833D01*
X285550Y383250D01*
X285467Y382667D01*
X285550Y382083D01*
X285883Y381583D01*
X286383Y381167D01*
X287050Y381000D01*
X287633Y381167D01*
X288133Y381500D01*
G01X292400Y386000D02*
Y381000D01*
G01X291233Y384333D02*
X293567D01*
G01X298000D02*
Y381000D01*
G01Y385667D02*
X297833Y385750D01*
Y385917D01*
X298000Y386000D01*
X298167Y385917D01*
Y385750D01*
X298000Y385667D01*
G01X303600Y381000D02*
X303100Y381083D01*
X302600Y381417D01*
X302267Y382000D01*
X302100Y382667D01*
X302267Y383333D01*
X302600Y383917D01*
X303100Y384250D01*
X303600Y384333D01*
X304100Y384250D01*
X304600Y383917D01*
X304933Y383333D01*
X305017Y382667D01*
X304933Y382000D01*
X304600Y381417D01*
X304100Y381083D01*
X303600Y381000D01*
G01X307783D02*
Y384333D01*
G01Y383500D02*
X308117Y383917D01*
X308617Y384250D01*
X309283Y384333D01*
X309867Y384250D01*
X310367Y383917D01*
X310617Y383333D01*
Y381000D01*
G01X318900D02*
Y386000D01*
G01Y383500D02*
X319317Y384000D01*
X319817Y384250D01*
X320317Y384333D01*
X321067Y384167D01*
X321567Y383833D01*
X321900Y383250D01*
Y382583D01*
X321733Y381917D01*
X321400Y381417D01*
X320817Y381083D01*
X320317Y381000D01*
X319817Y381083D01*
X319317Y381333D01*
X318900Y381750D01*
G01X324750Y383250D02*
X327417D01*
X327167Y383833D01*
X326750Y384167D01*
X326167Y384333D01*
X325583Y384250D01*
X325083Y384000D01*
X324750Y383417D01*
X324583Y382917D01*
Y382417D01*
X324750Y381917D01*
X325167Y381417D01*
X325667Y381083D01*
X326250Y381000D01*
X326833Y381167D01*
X327417Y381667D01*
G01X331600Y381000D02*
Y386000D01*
G01X337200Y381000D02*
X336700Y381083D01*
X336200Y381417D01*
X335867Y382000D01*
X335700Y382667D01*
X335867Y383333D01*
X336200Y383917D01*
X336700Y384250D01*
X337200Y384333D01*
X337700Y384250D01*
X338200Y383917D01*
X338533Y383333D01*
X338617Y382667D01*
X338533Y382000D01*
X338200Y381417D01*
X337700Y381083D01*
X337200Y381000D01*
G01X340717Y384333D02*
X341717Y381000D01*
X342800Y384333D01*
X343883Y381000D01*
X344883Y384333D01*
G01X354000Y386000D02*
Y381000D01*
G01X352833Y384333D02*
X355167D01*
G01X358183Y381000D02*
Y386000D01*
G01Y383583D02*
X358600Y384000D01*
X359017Y384250D01*
X359683Y384333D01*
X360183Y384250D01*
X360767Y383917D01*
X361017Y383417D01*
Y381000D01*
G01X363950Y383250D02*
X366617D01*
X366367Y383833D01*
X365950Y384167D01*
X365367Y384333D01*
X364783Y384250D01*
X364283Y384000D01*
X363950Y383417D01*
X363783Y382917D01*
Y382417D01*
X363950Y381917D01*
X364367Y381417D01*
X364867Y381083D01*
X365450Y381000D01*
X366033Y381167D01*
X366617Y381667D01*
G01X373900Y381000D02*
Y384333D01*
G01Y383417D02*
X374150Y383833D01*
X374567Y384167D01*
X375150Y384333D01*
X375733Y384167D01*
X376150Y383833D01*
X376400Y383417D01*
Y381000D01*
G01Y383417D02*
X376650Y383833D01*
X377067Y384167D01*
X377650Y384333D01*
X378233Y384167D01*
X378650Y383833D01*
X378900Y383333D01*
Y381000D01*
G01X382000Y384333D02*
Y381000D01*
G01Y385667D02*
X381833Y385750D01*
Y385917D01*
X382000Y386000D01*
X382167Y385917D01*
Y385750D01*
X382000Y385667D01*
G01X386183Y381000D02*
Y384333D01*
G01Y383500D02*
X386517Y383917D01*
X387017Y384250D01*
X387683Y384333D01*
X388267Y384250D01*
X388767Y383917D01*
X389017Y383333D01*
Y381000D01*
G01X400133Y383917D02*
X399550Y384250D01*
X399050Y384333D01*
X398383Y384167D01*
X397883Y383833D01*
X397550Y383250D01*
X397467Y382667D01*
X397550Y382083D01*
X397883Y381583D01*
X398383Y381167D01*
X399050Y381000D01*
X399633Y381167D01*
X400133Y381500D01*
G01X404400Y381000D02*
X403900Y381083D01*
X403400Y381417D01*
X403067Y382000D01*
X402900Y382667D01*
X403067Y383333D01*
X403400Y383917D01*
X403900Y384250D01*
X404400Y384333D01*
X404900Y384250D01*
X405400Y383917D01*
X405733Y383333D01*
X405817Y382667D01*
X405733Y382000D01*
X405400Y381417D01*
X404900Y381083D01*
X404400Y381000D01*
G01X408583D02*
Y384333D01*
G01Y383500D02*
X408917Y383917D01*
X409417Y384250D01*
X410083Y384333D01*
X410667Y384250D01*
X411167Y383917D01*
X411417Y383333D01*
Y381000D01*
G01X417100Y386000D02*
Y381000D01*
G01Y381750D02*
X416767Y381333D01*
X416267Y381083D01*
X415683Y381000D01*
X415017Y381167D01*
X414517Y381583D01*
X414183Y382083D01*
X414100Y382667D01*
X414183Y383250D01*
X414517Y383750D01*
X415017Y384167D01*
X415683Y384333D01*
X416267Y384250D01*
X416683Y384083D01*
X417100Y383750D01*
G01X419783Y384333D02*
Y382000D01*
X420117Y381417D01*
X420617Y381083D01*
X421200Y381000D01*
X421783Y381083D01*
X422283Y381417D01*
X422617Y382000D01*
G01Y381000D02*
Y384333D01*
G01X428133Y383917D02*
X427550Y384250D01*
X427050Y384333D01*
X426383Y384167D01*
X425883Y383833D01*
X425550Y383250D01*
X425467Y382667D01*
X425550Y382083D01*
X425883Y381583D01*
X426383Y381167D01*
X427050Y381000D01*
X427633Y381167D01*
X428133Y381500D01*
G01X432400Y386000D02*
Y381000D01*
G01X431233Y384333D02*
X433567D01*
G01X438000Y381000D02*
X437500Y381083D01*
X437000Y381417D01*
X436667Y382000D01*
X436500Y382667D01*
X436667Y383333D01*
X437000Y383917D01*
X437500Y384250D01*
X438000Y384333D01*
X438500Y384250D01*
X439000Y383917D01*
X439333Y383333D01*
X439417Y382667D01*
X439333Y382000D01*
X439000Y381417D01*
X438500Y381083D01*
X438000Y381000D01*
G01X442433D02*
Y384333D01*
G01Y383667D02*
X442850Y384000D01*
X443267Y384250D01*
X443850Y384333D01*
X444267Y384250D01*
X444767Y384000D01*
G01X452717Y384333D02*
X453717Y381000D01*
X454800Y384333D01*
X455883Y381000D01*
X456883Y384333D01*
G01X460400D02*
Y381000D01*
G01Y385667D02*
X460233Y385750D01*
Y385917D01*
X460400Y386000D01*
X460567Y385917D01*
Y385750D01*
X460400Y385667D01*
G01X467500Y386000D02*
Y381000D01*
G01Y381750D02*
X467167Y381333D01*
X466667Y381083D01*
X466083Y381000D01*
X465417Y381167D01*
X464917Y381583D01*
X464583Y382083D01*
X464500Y382667D01*
X464583Y383250D01*
X464917Y383750D01*
X465417Y384167D01*
X466083Y384333D01*
X466667Y384250D01*
X467083Y384083D01*
X467500Y383750D01*
G01X471600Y386000D02*
Y381000D01*
G01X470433Y384333D02*
X472767D01*
G01X475783Y381000D02*
Y386000D01*
G01Y383583D02*
X476200Y384000D01*
X476617Y384250D01*
X477283Y384333D01*
X477783Y384250D01*
X478367Y383917D01*
X478617Y383417D01*
Y381000D01*
G01X487150Y381583D02*
X487567Y381250D01*
X488150Y381000D01*
X488650D01*
X489150Y381167D01*
X489483Y381417D01*
X489650Y381750D01*
X489567Y382250D01*
X489233Y382500D01*
X487733Y383000D01*
X487400Y383583D01*
X487567Y384000D01*
X487900Y384250D01*
X488400Y384333D01*
X488900Y384250D01*
X489400Y384000D01*
G01X492500Y379333D02*
Y384333D01*
G01Y383583D02*
X492917Y384000D01*
X493333Y384250D01*
X494000Y384333D01*
X494583Y384250D01*
X495167Y383833D01*
X495417Y383250D01*
X495500Y382667D01*
X495417Y382083D01*
X495167Y381500D01*
X494667Y381167D01*
X494000Y381000D01*
X493417Y381083D01*
X492833Y381333D01*
X492500Y381667D01*
G01X498350Y383250D02*
X501017D01*
X500767Y383833D01*
X500350Y384167D01*
X499767Y384333D01*
X499183Y384250D01*
X498683Y384000D01*
X498350Y383417D01*
X498183Y382917D01*
Y382417D01*
X498350Y381917D01*
X498767Y381417D01*
X499267Y381083D01*
X499850Y381000D01*
X500433Y381167D01*
X501017Y381667D01*
G01X506533Y383917D02*
X505950Y384250D01*
X505450Y384333D01*
X504783Y384167D01*
X504283Y383833D01*
X503950Y383250D01*
X503867Y382667D01*
X503950Y382083D01*
X504283Y381583D01*
X504783Y381167D01*
X505450Y381000D01*
X506033Y381167D01*
X506533Y381500D01*
G01X510800Y384333D02*
Y381000D01*
G01Y385667D02*
X510633Y385750D01*
Y385917D01*
X510800Y386000D01*
X510967Y385917D01*
Y385750D01*
X510800Y385667D01*
G01X515900Y381000D02*
Y385250D01*
X516067Y385667D01*
X516400Y385917D01*
X516900Y386000D01*
X517400Y385833D01*
X517650Y385417D01*
G01X516650Y384000D02*
X514983D01*
G01X522000Y384333D02*
Y381000D01*
G01Y385667D02*
X521833Y385750D01*
Y385917D01*
X522000Y386000D01*
X522167Y385917D01*
Y385750D01*
X522000Y385667D01*
G01X526350Y383250D02*
X529017D01*
X528767Y383833D01*
X528350Y384167D01*
X527767Y384333D01*
X527183Y384250D01*
X526683Y384000D01*
X526350Y383417D01*
X526183Y382917D01*
Y382417D01*
X526350Y381917D01*
X526767Y381417D01*
X527267Y381083D01*
X527850Y381000D01*
X528433Y381167D01*
X529017Y381667D01*
G01X534700Y386000D02*
Y381000D01*
G01Y381750D02*
X534367Y381333D01*
X533867Y381083D01*
X533283Y381000D01*
X532617Y381167D01*
X532117Y381583D01*
X531783Y382083D01*
X531700Y382667D01*
X531783Y383250D01*
X532117Y383750D01*
X532617Y384167D01*
X533283Y384333D01*
X533867Y384250D01*
X534283Y384083D01*
X534700Y383750D01*
G01X544400Y381000D02*
X543900Y381083D01*
X543400Y381417D01*
X543067Y382000D01*
X542900Y382667D01*
X543067Y383333D01*
X543400Y383917D01*
X543900Y384250D01*
X544400Y384333D01*
X544900Y384250D01*
X545400Y383917D01*
X545733Y383333D01*
X545817Y382667D01*
X545733Y382000D01*
X545400Y381417D01*
X544900Y381083D01*
X544400Y381000D01*
G01X548583D02*
Y384333D01*
G01Y383500D02*
X548917Y383917D01*
X549417Y384250D01*
X550083Y384333D01*
X550667Y384250D01*
X551167Y383917D01*
X551417Y383333D01*
Y381000D01*
G01X561200Y386000D02*
Y381000D01*
G01X560033Y384333D02*
X562367D01*
G01X565383Y381000D02*
Y386000D01*
G01Y383583D02*
X565800Y384000D01*
X566217Y384250D01*
X566883Y384333D01*
X567383Y384250D01*
X567967Y383917D01*
X568217Y383417D01*
Y381000D01*
G01X571150Y383250D02*
X573817D01*
X573567Y383833D01*
X573150Y384167D01*
X572567Y384333D01*
X571983Y384250D01*
X571483Y384000D01*
X571150Y383417D01*
X570983Y382917D01*
Y382417D01*
X571150Y381917D01*
X571567Y381417D01*
X572067Y381083D01*
X572650Y381000D01*
X573233Y381167D01*
X573817Y381667D01*
G01X268250Y391500D02*
Y396500D01*
G01X271750D02*
Y391500D01*
G01Y394000D02*
X268250D01*
G01X275600Y391500D02*
X275100Y391583D01*
X274600Y391917D01*
X274267Y392500D01*
X274100Y393167D01*
X274267Y393833D01*
X274600Y394417D01*
X275100Y394750D01*
X275600Y394833D01*
X276100Y394750D01*
X276600Y394417D01*
X276933Y393833D01*
X277017Y393167D01*
X276933Y392500D01*
X276600Y391917D01*
X276100Y391583D01*
X275600Y391500D01*
G01X279117Y394833D02*
X280117Y391500D01*
X281200Y394833D01*
X282283Y391500D01*
X283283Y394833D01*
G01X285550Y393750D02*
X288217D01*
X287967Y394333D01*
X287550Y394667D01*
X286967Y394833D01*
X286383Y394750D01*
X285883Y394500D01*
X285550Y393917D01*
X285383Y393417D01*
Y392917D01*
X285550Y392417D01*
X285967Y391917D01*
X286467Y391583D01*
X287050Y391500D01*
X287633Y391667D01*
X288217Y392167D01*
G01X290900Y394833D02*
X292400Y391500D01*
X293900Y394833D01*
G01X296750Y393750D02*
X299417D01*
X299167Y394333D01*
X298750Y394667D01*
X298167Y394833D01*
X297583Y394750D01*
X297083Y394500D01*
X296750Y393917D01*
X296583Y393417D01*
Y392917D01*
X296750Y392417D01*
X297167Y391917D01*
X297667Y391583D01*
X298250Y391500D01*
X298833Y391667D01*
X299417Y392167D01*
G01X302433Y391500D02*
Y394833D01*
G01Y394167D02*
X302850Y394500D01*
X303267Y394750D01*
X303850Y394833D01*
X304267Y394750D01*
X304767Y394500D01*
G01X309033Y390583D02*
X309367Y391667D01*
G01X314800Y396500D02*
Y391500D01*
G01X313633Y394833D02*
X315967D01*
G01X318983Y391500D02*
Y396500D01*
G01Y394083D02*
X319400Y394500D01*
X319817Y394750D01*
X320483Y394833D01*
X320983Y394750D01*
X321567Y394417D01*
X321817Y393917D01*
Y391500D01*
G01X324750Y393750D02*
X327417D01*
X327167Y394333D01*
X326750Y394667D01*
X326167Y394833D01*
X325583Y394750D01*
X325083Y394500D01*
X324750Y393917D01*
X324583Y393417D01*
Y392917D01*
X324750Y392417D01*
X325167Y391917D01*
X325667Y391583D01*
X326250Y391500D01*
X326833Y391667D01*
X327417Y392167D01*
G01X337200Y396500D02*
Y391500D01*
G01X336033Y394833D02*
X338367D01*
G01X344300Y391500D02*
Y394833D01*
G01Y394250D02*
X343967Y394583D01*
X343467Y394750D01*
X342883Y394833D01*
X342300Y394667D01*
X341800Y394333D01*
X341467Y393833D01*
X341300Y393167D01*
X341467Y392500D01*
X341800Y392000D01*
X342300Y391667D01*
X342883Y391500D01*
X343467Y391583D01*
X343967Y391833D01*
X344300Y392167D01*
G01X346983Y391500D02*
Y394833D01*
G01Y394000D02*
X347317Y394417D01*
X347817Y394750D01*
X348483Y394833D01*
X349067Y394750D01*
X349567Y394417D01*
X349817Y393833D01*
Y391500D01*
G01X352833Y390250D02*
X353417Y389917D01*
X354083Y389833D01*
X354667Y389917D01*
X355167Y390333D01*
X355500Y390917D01*
Y394833D01*
G01Y394167D02*
X355167Y394500D01*
X354667Y394750D01*
X354083Y394833D01*
X353417Y394667D01*
X353000Y394333D01*
X352667Y393750D01*
X352500Y393167D01*
X352583Y392667D01*
X352917Y392083D01*
X353417Y391667D01*
X354083Y391500D01*
X354583Y391583D01*
X355167Y391917D01*
X355500Y392250D01*
G01X358350Y393750D02*
X361017D01*
X360767Y394333D01*
X360350Y394667D01*
X359767Y394833D01*
X359183Y394750D01*
X358683Y394500D01*
X358350Y393917D01*
X358183Y393417D01*
Y392917D01*
X358350Y392417D01*
X358767Y391917D01*
X359267Y391583D01*
X359850Y391500D01*
X360433Y391667D01*
X361017Y392167D01*
G01X363783Y391500D02*
Y394833D01*
G01Y394000D02*
X364117Y394417D01*
X364617Y394750D01*
X365283Y394833D01*
X365867Y394750D01*
X366367Y394417D01*
X366617Y393833D01*
Y391500D01*
G01X372133Y394417D02*
X371550Y394750D01*
X371050Y394833D01*
X370383Y394667D01*
X369883Y394333D01*
X369550Y393750D01*
X369467Y393167D01*
X369550Y392583D01*
X369883Y392083D01*
X370383Y391667D01*
X371050Y391500D01*
X371633Y391667D01*
X372133Y392000D01*
G01X374650Y390000D02*
X375150Y389833D01*
X375817Y390000D01*
X376233Y390333D01*
X376567Y390750D01*
X377067Y392083D01*
X378150Y394833D01*
G01X375483D02*
X377067Y392083D01*
G01X386350D02*
X386767Y391750D01*
X387350Y391500D01*
X387850D01*
X388350Y391667D01*
X388683Y391917D01*
X388850Y392250D01*
X388767Y392750D01*
X388433Y393000D01*
X386933Y393500D01*
X386600Y394083D01*
X386767Y394500D01*
X387100Y394750D01*
X387600Y394833D01*
X388100Y394750D01*
X388600Y394500D01*
G01X391783Y391500D02*
Y396500D01*
G01Y394083D02*
X392200Y394500D01*
X392617Y394750D01*
X393283Y394833D01*
X393783Y394750D01*
X394367Y394417D01*
X394617Y393917D01*
Y391500D01*
G01X398800D02*
X398300Y391583D01*
X397800Y391917D01*
X397467Y392500D01*
X397300Y393167D01*
X397467Y393833D01*
X397800Y394417D01*
X398300Y394750D01*
X398800Y394833D01*
X399300Y394750D01*
X399800Y394417D01*
X400133Y393833D01*
X400217Y393167D01*
X400133Y392500D01*
X399800Y391917D01*
X399300Y391583D01*
X398800Y391500D01*
G01X402983Y394833D02*
Y392500D01*
X403317Y391917D01*
X403817Y391583D01*
X404400Y391500D01*
X404983Y391583D01*
X405483Y391917D01*
X405817Y392500D01*
G01Y391500D02*
Y394833D01*
G01X410000Y391500D02*
Y396500D01*
G01X417100D02*
Y391500D01*
G01Y392250D02*
X416767Y391833D01*
X416267Y391583D01*
X415683Y391500D01*
X415017Y391667D01*
X414517Y392083D01*
X414183Y392583D01*
X414100Y393167D01*
X414183Y393750D01*
X414517Y394250D01*
X415017Y394667D01*
X415683Y394833D01*
X416267Y394750D01*
X416683Y394583D01*
X417100Y394250D01*
G01X425383Y391500D02*
Y394833D01*
G01Y394000D02*
X425717Y394417D01*
X426217Y394750D01*
X426883Y394833D01*
X427467Y394750D01*
X427967Y394417D01*
X428217Y393833D01*
Y391500D01*
G01X432400D02*
X431900Y391583D01*
X431400Y391917D01*
X431067Y392500D01*
X430900Y393167D01*
X431067Y393833D01*
X431400Y394417D01*
X431900Y394750D01*
X432400Y394833D01*
X432900Y394750D01*
X433400Y394417D01*
X433733Y393833D01*
X433817Y393167D01*
X433733Y392500D01*
X433400Y391917D01*
X432900Y391583D01*
X432400Y391500D01*
G01X438000Y396500D02*
Y391500D01*
G01X436833Y394833D02*
X439167D01*
G01X448033Y391500D02*
Y394833D01*
G01Y394167D02*
X448450Y394500D01*
X448867Y394750D01*
X449450Y394833D01*
X449867Y394750D01*
X450367Y394500D01*
G01X453550Y393750D02*
X456217D01*
X455967Y394333D01*
X455550Y394667D01*
X454967Y394833D01*
X454383Y394750D01*
X453883Y394500D01*
X453550Y393917D01*
X453383Y393417D01*
Y392917D01*
X453550Y392417D01*
X453967Y391917D01*
X454467Y391583D01*
X455050Y391500D01*
X455633Y391667D01*
X456217Y392167D01*
G01X461900Y396500D02*
Y391500D01*
G01Y392250D02*
X461567Y391833D01*
X461067Y391583D01*
X460483Y391500D01*
X459817Y391667D01*
X459317Y392083D01*
X458983Y392583D01*
X458900Y393167D01*
X458983Y393750D01*
X459317Y394250D01*
X459817Y394667D01*
X460483Y394833D01*
X461067Y394750D01*
X461483Y394583D01*
X461900Y394250D01*
G01X464583Y394833D02*
Y392500D01*
X464917Y391917D01*
X465417Y391583D01*
X466000Y391500D01*
X466583Y391583D01*
X467083Y391917D01*
X467417Y392500D01*
G01Y391500D02*
Y394833D01*
G01X472933Y394417D02*
X472350Y394750D01*
X471850Y394833D01*
X471183Y394667D01*
X470683Y394333D01*
X470350Y393750D01*
X470267Y393167D01*
X470350Y392583D01*
X470683Y392083D01*
X471183Y391667D01*
X471850Y391500D01*
X472433Y391667D01*
X472933Y392000D01*
G01X475950Y393750D02*
X478617D01*
X478367Y394333D01*
X477950Y394667D01*
X477367Y394833D01*
X476783Y394750D01*
X476283Y394500D01*
X475950Y393917D01*
X475783Y393417D01*
Y392917D01*
X475950Y392417D01*
X476367Y391917D01*
X476867Y391583D01*
X477450Y391500D01*
X478033Y391667D01*
X478617Y392167D01*
G01X488400Y396500D02*
Y391500D01*
G01X487233Y394833D02*
X489567D01*
G01X492583Y391500D02*
Y396500D01*
G01Y394083D02*
X493000Y394500D01*
X493417Y394750D01*
X494083Y394833D01*
X494583Y394750D01*
X495167Y394417D01*
X495417Y393917D01*
Y391500D01*
G01X498350Y393750D02*
X501017D01*
X500767Y394333D01*
X500350Y394667D01*
X499767Y394833D01*
X499183Y394750D01*
X498683Y394500D01*
X498350Y393917D01*
X498183Y393417D01*
Y392917D01*
X498350Y392417D01*
X498767Y391917D01*
X499267Y391583D01*
X499850Y391500D01*
X500433Y391667D01*
X501017Y392167D01*
G01X510800Y391500D02*
Y396500D01*
G01X517900Y391500D02*
Y394833D01*
G01Y394250D02*
X517567Y394583D01*
X517067Y394750D01*
X516483Y394833D01*
X515900Y394667D01*
X515400Y394333D01*
X515067Y393833D01*
X514900Y393167D01*
X515067Y392500D01*
X515400Y392000D01*
X515900Y391667D01*
X516483Y391500D01*
X517067Y391583D01*
X517567Y391833D01*
X517900Y392167D01*
G01X520583Y391500D02*
Y394833D01*
G01Y394000D02*
X520917Y394417D01*
X521417Y394750D01*
X522083Y394833D01*
X522667Y394750D01*
X523167Y394417D01*
X523417Y393833D01*
Y391500D01*
G01X529100Y396500D02*
Y391500D01*
G01Y392250D02*
X528767Y391833D01*
X528267Y391583D01*
X527683Y391500D01*
X527017Y391667D01*
X526517Y392083D01*
X526183Y392583D01*
X526100Y393167D01*
X526183Y393750D01*
X526517Y394250D01*
X527017Y394667D01*
X527683Y394833D01*
X528267Y394750D01*
X528683Y394583D01*
X529100Y394250D01*
G01X531700Y391333D02*
X534700Y396500D01*
G01X540133Y394417D02*
X539550Y394750D01*
X539050Y394833D01*
X538383Y394667D01*
X537883Y394333D01*
X537550Y393750D01*
X537467Y393167D01*
X537550Y392583D01*
X537883Y392083D01*
X538383Y391667D01*
X539050Y391500D01*
X539633Y391667D01*
X540133Y392000D01*
G01X544400Y391500D02*
X543900Y391583D01*
X543400Y391917D01*
X543067Y392500D01*
X542900Y393167D01*
X543067Y393833D01*
X543400Y394417D01*
X543900Y394750D01*
X544400Y394833D01*
X544900Y394750D01*
X545400Y394417D01*
X545733Y393833D01*
X545817Y393167D01*
X545733Y392500D01*
X545400Y391917D01*
X544900Y391583D01*
X544400Y391500D01*
G01X548583D02*
Y394833D01*
G01Y394000D02*
X548917Y394417D01*
X549417Y394750D01*
X550083Y394833D01*
X550667Y394750D01*
X551167Y394417D01*
X551417Y393833D01*
Y391500D01*
G01X557100Y396500D02*
Y391500D01*
G01Y392250D02*
X556767Y391833D01*
X556267Y391583D01*
X555683Y391500D01*
X555017Y391667D01*
X554517Y392083D01*
X554183Y392583D01*
X554100Y393167D01*
X554183Y393750D01*
X554517Y394250D01*
X555017Y394667D01*
X555683Y394833D01*
X556267Y394750D01*
X556683Y394583D01*
X557100Y394250D01*
G01X559783Y394833D02*
Y392500D01*
X560117Y391917D01*
X560617Y391583D01*
X561200Y391500D01*
X561783Y391583D01*
X562283Y391917D01*
X562617Y392500D01*
G01Y391500D02*
Y394833D01*
G01X568133Y394417D02*
X567550Y394750D01*
X567050Y394833D01*
X566383Y394667D01*
X565883Y394333D01*
X565550Y393750D01*
X565467Y393167D01*
X565550Y392583D01*
X565883Y392083D01*
X566383Y391667D01*
X567050Y391500D01*
X567633Y391667D01*
X568133Y392000D01*
G01X572400Y396500D02*
Y391500D01*
G01X571233Y394833D02*
X573567D01*
G01X578000Y391500D02*
X577500Y391583D01*
X577000Y391917D01*
X576667Y392500D01*
X576500Y393167D01*
X576667Y393833D01*
X577000Y394417D01*
X577500Y394750D01*
X578000Y394833D01*
X578500Y394750D01*
X579000Y394417D01*
X579333Y393833D01*
X579417Y393167D01*
X579333Y392500D01*
X579000Y391917D01*
X578500Y391583D01*
X578000Y391500D01*
G01X582433D02*
Y394833D01*
G01Y394167D02*
X582850Y394500D01*
X583267Y394750D01*
X583850Y394833D01*
X584267Y394750D01*
X584767Y394500D01*
G01X271500Y402000D02*
Y405333D01*
G01Y404750D02*
X271167Y405083D01*
X270667Y405250D01*
X270083Y405333D01*
X269500Y405167D01*
X269000Y404833D01*
X268667Y404333D01*
X268500Y403667D01*
X268667Y403000D01*
X269000Y402500D01*
X269500Y402167D01*
X270083Y402000D01*
X270667Y402083D01*
X271167Y402333D01*
X271500Y402667D01*
G01X276933Y404917D02*
X276350Y405250D01*
X275850Y405333D01*
X275183Y405167D01*
X274683Y404833D01*
X274350Y404250D01*
X274267Y403667D01*
X274350Y403083D01*
X274683Y402583D01*
X275183Y402167D01*
X275850Y402000D01*
X276433Y402167D01*
X276933Y402500D01*
G01X282533Y404917D02*
X281950Y405250D01*
X281450Y405333D01*
X280783Y405167D01*
X280283Y404833D01*
X279950Y404250D01*
X279867Y403667D01*
X279950Y403083D01*
X280283Y402583D01*
X280783Y402167D01*
X281450Y402000D01*
X282033Y402167D01*
X282533Y402500D01*
G01X285550Y404250D02*
X288217D01*
X287967Y404833D01*
X287550Y405167D01*
X286967Y405333D01*
X286383Y405250D01*
X285883Y405000D01*
X285550Y404417D01*
X285383Y403917D01*
Y403417D01*
X285550Y402917D01*
X285967Y402417D01*
X286467Y402083D01*
X287050Y402000D01*
X287633Y402167D01*
X288217Y402667D01*
G01X290900Y400333D02*
Y405333D01*
G01Y404583D02*
X291317Y405000D01*
X291733Y405250D01*
X292400Y405333D01*
X292983Y405250D01*
X293567Y404833D01*
X293817Y404250D01*
X293900Y403667D01*
X293817Y403083D01*
X293567Y402500D01*
X293067Y402167D01*
X292400Y402000D01*
X291817Y402083D01*
X291233Y402333D01*
X290900Y402667D01*
G01X298000Y407000D02*
Y402000D01*
G01X296833Y405333D02*
X299167D01*
G01X305100Y402000D02*
Y405333D01*
G01Y404750D02*
X304767Y405083D01*
X304267Y405250D01*
X303683Y405333D01*
X303100Y405167D01*
X302600Y404833D01*
X302267Y404333D01*
X302100Y403667D01*
X302267Y403000D01*
X302600Y402500D01*
X303100Y402167D01*
X303683Y402000D01*
X304267Y402083D01*
X304767Y402333D01*
X305100Y402667D01*
G01X307700Y402000D02*
Y407000D01*
G01Y404500D02*
X308117Y405000D01*
X308617Y405250D01*
X309117Y405333D01*
X309867Y405167D01*
X310367Y404833D01*
X310700Y404250D01*
Y403583D01*
X310533Y402917D01*
X310200Y402417D01*
X309617Y402083D01*
X309117Y402000D01*
X308617Y402083D01*
X308117Y402333D01*
X307700Y402750D01*
G01X314800Y402000D02*
Y407000D01*
G01X319150Y404250D02*
X321817D01*
X321567Y404833D01*
X321150Y405167D01*
X320567Y405333D01*
X319983Y405250D01*
X319483Y405000D01*
X319150Y404417D01*
X318983Y403917D01*
Y403417D01*
X319150Y402917D01*
X319567Y402417D01*
X320067Y402083D01*
X320650Y402000D01*
X321233Y402167D01*
X321817Y402667D01*
G01X326000Y401833D02*
X325833Y401917D01*
Y402083D01*
X326000Y402167D01*
X326167Y402083D01*
Y401917D01*
X326000Y401833D01*
G01X270000Y417500D02*
Y412500D01*
G01X268083Y417500D02*
X271917D01*
G01X274183Y412500D02*
Y417500D01*
G01Y415083D02*
X274600Y415500D01*
X275017Y415750D01*
X275683Y415833D01*
X276183Y415750D01*
X276767Y415417D01*
X277017Y414917D01*
Y412500D01*
G01X279950Y414750D02*
X282617D01*
X282367Y415333D01*
X281950Y415667D01*
X281367Y415833D01*
X280783Y415750D01*
X280283Y415500D01*
X279950Y414917D01*
X279783Y414417D01*
Y413917D01*
X279950Y413417D01*
X280367Y412917D01*
X280867Y412583D01*
X281450Y412500D01*
X282033Y412667D01*
X282617Y413167D01*
G01X290900Y412500D02*
Y417500D01*
G01Y415000D02*
X291317Y415500D01*
X291817Y415750D01*
X292317Y415833D01*
X293067Y415667D01*
X293567Y415333D01*
X293900Y414750D01*
Y414083D01*
X293733Y413417D01*
X293400Y412917D01*
X292817Y412583D01*
X292317Y412500D01*
X291817Y412583D01*
X291317Y412833D01*
X290900Y413250D01*
G01X296833Y412500D02*
Y415833D01*
G01Y415167D02*
X297250Y415500D01*
X297667Y415750D01*
X298250Y415833D01*
X298667Y415750D01*
X299167Y415500D01*
G01X302350Y414750D02*
X305017D01*
X304767Y415333D01*
X304350Y415667D01*
X303767Y415833D01*
X303183Y415750D01*
X302683Y415500D01*
X302350Y414917D01*
X302183Y414417D01*
Y413917D01*
X302350Y413417D01*
X302767Y412917D01*
X303267Y412583D01*
X303850Y412500D01*
X304433Y412667D01*
X305017Y413167D01*
G01X310700Y412500D02*
Y415833D01*
G01Y415250D02*
X310367Y415583D01*
X309867Y415750D01*
X309283Y415833D01*
X308700Y415667D01*
X308200Y415333D01*
X307867Y414833D01*
X307700Y414167D01*
X307867Y413500D01*
X308200Y413000D01*
X308700Y412667D01*
X309283Y412500D01*
X309867Y412583D01*
X310367Y412833D01*
X310700Y413167D01*
G01X313383Y412500D02*
Y417500D01*
G01X316050Y415833D02*
X313383Y413917D01*
G01X314467Y414667D02*
X316217Y412500D01*
G01X320400D02*
X319900Y412583D01*
X319400Y412917D01*
X319067Y413500D01*
X318900Y414167D01*
X319067Y414833D01*
X319400Y415417D01*
X319900Y415750D01*
X320400Y415833D01*
X320900Y415750D01*
X321400Y415417D01*
X321733Y414833D01*
X321817Y414167D01*
X321733Y413500D01*
X321400Y412917D01*
X320900Y412583D01*
X320400Y412500D01*
G01X324583Y415833D02*
Y413500D01*
X324917Y412917D01*
X325417Y412583D01*
X326000Y412500D01*
X326583Y412583D01*
X327083Y412917D01*
X327417Y413500D01*
G01Y412500D02*
Y415833D01*
G01X331600Y417500D02*
Y412500D01*
G01X330433Y415833D02*
X332767D01*
G01X342800D02*
Y412500D01*
G01Y417167D02*
X342633Y417250D01*
Y417417D01*
X342800Y417500D01*
X342967Y417417D01*
Y417250D01*
X342800Y417167D01*
G01X347150Y413083D02*
X347567Y412750D01*
X348150Y412500D01*
X348650D01*
X349150Y412667D01*
X349483Y412917D01*
X349650Y413250D01*
X349567Y413750D01*
X349233Y414000D01*
X347733Y414500D01*
X347400Y415083D01*
X347567Y415500D01*
X347900Y415750D01*
X348400Y415833D01*
X348900Y415750D01*
X349400Y415500D01*
G01X358183Y412500D02*
Y415833D01*
G01Y415000D02*
X358517Y415417D01*
X359017Y415750D01*
X359683Y415833D01*
X360267Y415750D01*
X360767Y415417D01*
X361017Y414833D01*
Y412500D01*
G01X365200D02*
X364700Y412583D01*
X364200Y412917D01*
X363867Y413500D01*
X363700Y414167D01*
X363867Y414833D01*
X364200Y415417D01*
X364700Y415750D01*
X365200Y415833D01*
X365700Y415750D01*
X366200Y415417D01*
X366533Y414833D01*
X366617Y414167D01*
X366533Y413500D01*
X366200Y412917D01*
X365700Y412583D01*
X365200Y412500D01*
G01X370800Y417500D02*
Y412500D01*
G01X369633Y415833D02*
X371967D01*
G01X383500Y412500D02*
Y415833D01*
G01Y415250D02*
X383167Y415583D01*
X382667Y415750D01*
X382083Y415833D01*
X381500Y415667D01*
X381000Y415333D01*
X380667Y414833D01*
X380500Y414167D01*
X380667Y413500D01*
X381000Y413000D01*
X381500Y412667D01*
X382083Y412500D01*
X382667Y412583D01*
X383167Y412833D01*
X383500Y413167D01*
G01X387600Y412500D02*
Y417500D01*
G01X393200Y412500D02*
Y417500D01*
G01X398800Y412500D02*
X398300Y412583D01*
X397800Y412917D01*
X397467Y413500D01*
X397300Y414167D01*
X397467Y414833D01*
X397800Y415417D01*
X398300Y415750D01*
X398800Y415833D01*
X399300Y415750D01*
X399800Y415417D01*
X400133Y414833D01*
X400217Y414167D01*
X400133Y413500D01*
X399800Y412917D01*
X399300Y412583D01*
X398800Y412500D01*
G01X402317Y415833D02*
X403317Y412500D01*
X404400Y415833D01*
X405483Y412500D01*
X406483Y415833D01*
G01X408750Y414750D02*
X411417D01*
X411167Y415333D01*
X410750Y415667D01*
X410167Y415833D01*
X409583Y415750D01*
X409083Y415500D01*
X408750Y414917D01*
X408583Y414417D01*
Y413917D01*
X408750Y413417D01*
X409167Y412917D01*
X409667Y412583D01*
X410250Y412500D01*
X410833Y412667D01*
X411417Y413167D01*
G01X417100Y417500D02*
Y412500D01*
G01Y413250D02*
X416767Y412833D01*
X416267Y412583D01*
X415683Y412500D01*
X415017Y412667D01*
X414517Y413083D01*
X414183Y413583D01*
X414100Y414167D01*
X414183Y414750D01*
X414517Y415250D01*
X415017Y415667D01*
X415683Y415833D01*
X416267Y415750D01*
X416683Y415583D01*
X417100Y415250D01*
G01X421033Y411583D02*
X421367Y412667D01*
G01X436500Y412500D02*
Y417500D01*
G01Y415000D02*
X436917Y415500D01*
X437417Y415750D01*
X437917Y415833D01*
X438667Y415667D01*
X439167Y415333D01*
X439500Y414750D01*
Y414083D01*
X439333Y413417D01*
X439000Y412917D01*
X438417Y412583D01*
X437917Y412500D01*
X437417Y412583D01*
X436917Y412833D01*
X436500Y413250D01*
G01X442183Y415833D02*
Y413500D01*
X442517Y412917D01*
X443017Y412583D01*
X443600Y412500D01*
X444183Y412583D01*
X444683Y412917D01*
X445017Y413500D01*
G01Y412500D02*
Y415833D01*
G01X449200Y417500D02*
Y412500D01*
G01X448033Y415833D02*
X450367D01*
G01X461900Y412500D02*
Y415833D01*
G01Y415250D02*
X461567Y415583D01*
X461067Y415750D01*
X460483Y415833D01*
X459900Y415667D01*
X459400Y415333D01*
X459067Y414833D01*
X458900Y414167D01*
X459067Y413500D01*
X459400Y413000D01*
X459900Y412667D01*
X460483Y412500D01*
X461067Y412583D01*
X461567Y412833D01*
X461900Y413167D01*
G01X464583Y412500D02*
Y415833D01*
G01Y415000D02*
X464917Y415417D01*
X465417Y415750D01*
X466083Y415833D01*
X466667Y415750D01*
X467167Y415417D01*
X467417Y414833D01*
Y412500D01*
G01X470183D02*
Y415833D01*
G01Y415000D02*
X470517Y415417D01*
X471017Y415750D01*
X471683Y415833D01*
X472267Y415750D01*
X472767Y415417D01*
X473017Y414833D01*
Y412500D01*
G01X475783Y415833D02*
Y413500D01*
X476117Y412917D01*
X476617Y412583D01*
X477200Y412500D01*
X477783Y412583D01*
X478283Y412917D01*
X478617Y413500D01*
G01Y412500D02*
Y415833D01*
G01X484300Y412500D02*
Y415833D01*
G01Y415250D02*
X483967Y415583D01*
X483467Y415750D01*
X482883Y415833D01*
X482300Y415667D01*
X481800Y415333D01*
X481467Y414833D01*
X481300Y414167D01*
X481467Y413500D01*
X481800Y413000D01*
X482300Y412667D01*
X482883Y412500D01*
X483467Y412583D01*
X483967Y412833D01*
X484300Y413167D01*
G01X488400Y412500D02*
Y417500D01*
G01X498433Y412500D02*
Y415833D01*
G01Y415167D02*
X498850Y415500D01*
X499267Y415750D01*
X499850Y415833D01*
X500267Y415750D01*
X500767Y415500D01*
G01X505200Y415833D02*
Y412500D01*
G01Y417167D02*
X505033Y417250D01*
Y417417D01*
X505200Y417500D01*
X505367Y417417D01*
Y417250D01*
X505200Y417167D01*
G01X509383Y412500D02*
Y415833D01*
G01Y415000D02*
X509717Y415417D01*
X510217Y415750D01*
X510883Y415833D01*
X511467Y415750D01*
X511967Y415417D01*
X512217Y414833D01*
Y412500D01*
G01X515233Y411250D02*
X515817Y410917D01*
X516483Y410833D01*
X517067Y410917D01*
X517567Y411333D01*
X517900Y411917D01*
Y415833D01*
G01Y415167D02*
X517567Y415500D01*
X517067Y415750D01*
X516483Y415833D01*
X515817Y415667D01*
X515400Y415333D01*
X515067Y414750D01*
X514900Y414167D01*
X514983Y413667D01*
X515317Y413083D01*
X515817Y412667D01*
X516483Y412500D01*
X516983Y412583D01*
X517567Y412917D01*
X517900Y413250D01*
G01X527600Y417500D02*
Y412500D01*
G01X526433Y415833D02*
X528767D01*
G01X534700Y412500D02*
Y415833D01*
G01Y415250D02*
X534367Y415583D01*
X533867Y415750D01*
X533283Y415833D01*
X532700Y415667D01*
X532200Y415333D01*
X531867Y414833D01*
X531700Y414167D01*
X531867Y413500D01*
X532200Y413000D01*
X532700Y412667D01*
X533283Y412500D01*
X533867Y412583D01*
X534367Y412833D01*
X534700Y413167D01*
G01X537383Y412500D02*
Y415833D01*
G01Y415000D02*
X537717Y415417D01*
X538217Y415750D01*
X538883Y415833D01*
X539467Y415750D01*
X539967Y415417D01*
X540217Y414833D01*
Y412500D01*
G01X543233Y411250D02*
X543817Y410917D01*
X544483Y410833D01*
X545067Y410917D01*
X545567Y411333D01*
X545900Y411917D01*
Y415833D01*
G01Y415167D02*
X545567Y415500D01*
X545067Y415750D01*
X544483Y415833D01*
X543817Y415667D01*
X543400Y415333D01*
X543067Y414750D01*
X542900Y414167D01*
X542983Y413667D01*
X543317Y413083D01*
X543817Y412667D01*
X544483Y412500D01*
X544983Y412583D01*
X545567Y412917D01*
X545900Y413250D01*
G01X548750Y414750D02*
X551417D01*
X551167Y415333D01*
X550750Y415667D01*
X550167Y415833D01*
X549583Y415750D01*
X549083Y415500D01*
X548750Y414917D01*
X548583Y414417D01*
Y413917D01*
X548750Y413417D01*
X549167Y412917D01*
X549667Y412583D01*
X550250Y412500D01*
X550833Y412667D01*
X551417Y413167D01*
G01X554183Y412500D02*
Y415833D01*
G01Y415000D02*
X554517Y415417D01*
X555017Y415750D01*
X555683Y415833D01*
X556267Y415750D01*
X556767Y415417D01*
X557017Y414833D01*
Y412500D01*
G01X562533Y415417D02*
X561950Y415750D01*
X561450Y415833D01*
X560783Y415667D01*
X560283Y415333D01*
X559950Y414750D01*
X559867Y414167D01*
X559950Y413583D01*
X560283Y413083D01*
X560783Y412667D01*
X561450Y412500D01*
X562033Y412667D01*
X562533Y413000D01*
G01X565050Y411000D02*
X565550Y410833D01*
X566217Y411000D01*
X566633Y411333D01*
X566967Y411750D01*
X567467Y413083D01*
X568550Y415833D01*
G01X565883D02*
X567467Y413083D01*
G01X578000Y415833D02*
Y412500D01*
G01Y417167D02*
X577833Y417250D01*
Y417417D01*
X578000Y417500D01*
X578167Y417417D01*
Y417250D01*
X578000Y417167D01*
G01X582350Y413083D02*
X582767Y412750D01*
X583350Y412500D01*
X583850D01*
X584350Y412667D01*
X584683Y412917D01*
X584850Y413250D01*
X584767Y413750D01*
X584433Y414000D01*
X582933Y414500D01*
X582600Y415083D01*
X582767Y415500D01*
X583100Y415750D01*
X583600Y415833D01*
X584100Y415750D01*
X584600Y415500D01*
G01X273000Y437500D02*
Y432500D01*
G01Y433250D02*
X272667Y432833D01*
X272167Y432583D01*
X271583Y432500D01*
X270917Y432667D01*
X270417Y433083D01*
X270083Y433583D01*
X270000Y434167D01*
X270083Y434750D01*
X270417Y435250D01*
X270917Y435667D01*
X271583Y435833D01*
X272167Y435750D01*
X272583Y435583D01*
X273000Y435250D01*
G01X275850Y434750D02*
X278517D01*
X278267Y435333D01*
X277850Y435667D01*
X277267Y435833D01*
X276683Y435750D01*
X276183Y435500D01*
X275850Y434917D01*
X275683Y434417D01*
Y433917D01*
X275850Y433417D01*
X276267Y432917D01*
X276767Y432583D01*
X277350Y432500D01*
X277933Y432667D01*
X278517Y433167D01*
G01X281200Y430833D02*
Y435833D01*
G01Y435083D02*
X281617Y435500D01*
X282033Y435750D01*
X282700Y435833D01*
X283283Y435750D01*
X283867Y435333D01*
X284117Y434750D01*
X284200Y434167D01*
X284117Y433583D01*
X283867Y433000D01*
X283367Y432667D01*
X282700Y432500D01*
X282117Y432583D01*
X281533Y432833D01*
X281200Y433167D01*
G01X288300Y437500D02*
Y432500D01*
G01X287133Y435833D02*
X289467D01*
G01X292483Y432500D02*
Y437500D01*
G01Y435083D02*
X292900Y435500D01*
X293317Y435750D01*
X293983Y435833D01*
X294483Y435750D01*
X295067Y435417D01*
X295317Y434917D01*
Y432500D01*
G01X305100Y437500D02*
Y432500D01*
G01X303933Y435833D02*
X306267D01*
G01X310700Y432500D02*
X310200Y432583D01*
X309700Y432917D01*
X309367Y433500D01*
X309200Y434167D01*
X309367Y434833D01*
X309700Y435417D01*
X310200Y435750D01*
X310700Y435833D01*
X311200Y435750D01*
X311700Y435417D01*
X312033Y434833D01*
X312117Y434167D01*
X312033Y433500D01*
X311700Y432917D01*
X311200Y432583D01*
X310700Y432500D01*
G01X316300D02*
Y437500D01*
G01X320650Y434750D02*
X323317D01*
X323067Y435333D01*
X322650Y435667D01*
X322067Y435833D01*
X321483Y435750D01*
X320983Y435500D01*
X320650Y434917D01*
X320483Y434417D01*
Y433917D01*
X320650Y433417D01*
X321067Y432917D01*
X321567Y432583D01*
X322150Y432500D01*
X322733Y432667D01*
X323317Y433167D01*
G01X326333Y432500D02*
Y435833D01*
G01Y435167D02*
X326750Y435500D01*
X327167Y435750D01*
X327750Y435833D01*
X328167Y435750D01*
X328667Y435500D01*
G01X334600Y432500D02*
Y435833D01*
G01Y435250D02*
X334267Y435583D01*
X333767Y435750D01*
X333183Y435833D01*
X332600Y435667D01*
X332100Y435333D01*
X331767Y434833D01*
X331600Y434167D01*
X331767Y433500D01*
X332100Y433000D01*
X332600Y432667D01*
X333183Y432500D01*
X333767Y432583D01*
X334267Y432833D01*
X334600Y433167D01*
G01X337283Y432500D02*
Y435833D01*
G01Y435000D02*
X337617Y435417D01*
X338117Y435750D01*
X338783Y435833D01*
X339367Y435750D01*
X339867Y435417D01*
X340117Y434833D01*
Y432500D01*
G01X345633Y435417D02*
X345050Y435750D01*
X344550Y435833D01*
X343883Y435667D01*
X343383Y435333D01*
X343050Y434750D01*
X342967Y434167D01*
X343050Y433583D01*
X343383Y433083D01*
X343883Y432667D01*
X344550Y432500D01*
X345133Y432667D01*
X345633Y433000D01*
G01X348650Y434750D02*
X351317D01*
X351067Y435333D01*
X350650Y435667D01*
X350067Y435833D01*
X349483Y435750D01*
X348983Y435500D01*
X348650Y434917D01*
X348483Y434417D01*
Y433917D01*
X348650Y433417D01*
X349067Y432917D01*
X349567Y432583D01*
X350150Y432500D01*
X350733Y432667D01*
X351317Y433167D01*
G01X270750Y453500D02*
Y458500D01*
G01X274250D02*
Y453500D01*
G01Y456000D02*
X270750D01*
G01X278100Y453500D02*
X277600Y453583D01*
X277100Y453917D01*
X276767Y454500D01*
X276600Y455167D01*
X276767Y455833D01*
X277100Y456417D01*
X277600Y456750D01*
X278100Y456833D01*
X278600Y456750D01*
X279100Y456417D01*
X279433Y455833D01*
X279517Y455167D01*
X279433Y454500D01*
X279100Y453917D01*
X278600Y453583D01*
X278100Y453500D01*
G01X283700D02*
Y458500D01*
G01X288050Y455750D02*
X290717D01*
X290467Y456333D01*
X290050Y456667D01*
X289467Y456833D01*
X288883Y456750D01*
X288383Y456500D01*
X288050Y455917D01*
X287883Y455417D01*
Y454917D01*
X288050Y454417D01*
X288467Y453917D01*
X288967Y453583D01*
X289550Y453500D01*
X290133Y453667D01*
X290717Y454167D01*
G01X298000Y458500D02*
X299167Y453500D01*
X300500Y458500D01*
X301833Y453500D01*
X303000Y458500D01*
G01X307600Y453500D02*
Y456833D01*
G01Y456250D02*
X307267Y456583D01*
X306767Y456750D01*
X306183Y456833D01*
X305600Y456667D01*
X305100Y456333D01*
X304767Y455833D01*
X304600Y455167D01*
X304767Y454500D01*
X305100Y454000D01*
X305600Y453667D01*
X306183Y453500D01*
X306767Y453583D01*
X307267Y453833D01*
X307600Y454167D01*
G01X311700Y453500D02*
Y458500D01*
G01X317300Y453500D02*
Y458500D01*
G01X326833Y453500D02*
Y458500D01*
X328917D01*
X329583Y458250D01*
X330000Y457917D01*
X330167Y457250D01*
X330000Y456583D01*
X329500Y456167D01*
X328917Y455917D01*
X326833D01*
G01X328917D02*
X330167Y453500D01*
G01X334100D02*
X333600Y453583D01*
X333100Y453917D01*
X332767Y454500D01*
X332600Y455167D01*
X332767Y455833D01*
X333100Y456417D01*
X333600Y456750D01*
X334100Y456833D01*
X334600Y456750D01*
X335100Y456417D01*
X335433Y455833D01*
X335517Y455167D01*
X335433Y454500D01*
X335100Y453917D01*
X334600Y453583D01*
X334100Y453500D01*
G01X338283Y456833D02*
Y454500D01*
X338617Y453917D01*
X339117Y453583D01*
X339700Y453500D01*
X340283Y453583D01*
X340783Y453917D01*
X341117Y454500D01*
G01Y453500D02*
Y456833D01*
G01X344133Y452250D02*
X344717Y451917D01*
X345383Y451833D01*
X345967Y451917D01*
X346467Y452333D01*
X346800Y452917D01*
Y456833D01*
G01Y456167D02*
X346467Y456500D01*
X345967Y456750D01*
X345383Y456833D01*
X344717Y456667D01*
X344300Y456333D01*
X343967Y455750D01*
X343800Y455167D01*
X343883Y454667D01*
X344217Y454083D01*
X344717Y453667D01*
X345383Y453500D01*
X345883Y453583D01*
X346467Y453917D01*
X346800Y454250D01*
G01X349483Y453500D02*
Y458500D01*
G01Y456083D02*
X349900Y456500D01*
X350317Y456750D01*
X350983Y456833D01*
X351483Y456750D01*
X352067Y456417D01*
X352317Y455917D01*
Y453500D01*
G01X355083D02*
Y456833D01*
G01Y456000D02*
X355417Y456417D01*
X355917Y456750D01*
X356583Y456833D01*
X357167Y456750D01*
X357667Y456417D01*
X357917Y455833D01*
Y453500D01*
G01X360850Y455750D02*
X363517D01*
X363267Y456333D01*
X362850Y456667D01*
X362267Y456833D01*
X361683Y456750D01*
X361183Y456500D01*
X360850Y455917D01*
X360683Y455417D01*
Y454917D01*
X360850Y454417D01*
X361267Y453917D01*
X361767Y453583D01*
X362350Y453500D01*
X362933Y453667D01*
X363517Y454167D01*
G01X366450Y454083D02*
X366867Y453750D01*
X367450Y453500D01*
X367950D01*
X368450Y453667D01*
X368783Y453917D01*
X368950Y454250D01*
X368867Y454750D01*
X368533Y455000D01*
X367033Y455500D01*
X366700Y456083D01*
X366867Y456500D01*
X367200Y456750D01*
X367700Y456833D01*
X368200Y456750D01*
X368700Y456500D01*
G01X372050Y454083D02*
X372467Y453750D01*
X373050Y453500D01*
X373550D01*
X374050Y453667D01*
X374383Y453917D01*
X374550Y454250D01*
X374467Y454750D01*
X374133Y455000D01*
X372633Y455500D01*
X372300Y456083D01*
X372467Y456500D01*
X372800Y456750D01*
X373300Y456833D01*
X373800Y456750D01*
X374300Y456500D01*
G01X272500Y470000D02*
X271833Y470083D01*
X271250Y470417D01*
X270750Y470917D01*
X270417Y471500D01*
X270250Y472167D01*
Y472833D01*
X270417Y473500D01*
X270750Y474083D01*
X271250Y474583D01*
X271833Y474917D01*
X272500Y475000D01*
X273167Y474917D01*
X273750Y474583D01*
X274250Y474083D01*
X274583Y473500D01*
X274750Y472833D01*
Y472167D01*
X274583Y471500D01*
X274250Y470917D01*
X273750Y470417D01*
X273167Y470083D01*
X272500Y470000D01*
G01X278100Y475000D02*
Y470000D01*
G01X276933Y473333D02*
X279267D01*
G01X282283Y470000D02*
Y475000D01*
G01Y472583D02*
X282700Y473000D01*
X283117Y473250D01*
X283783Y473333D01*
X284283Y473250D01*
X284867Y472917D01*
X285117Y472417D01*
Y470000D01*
G01X288050Y472250D02*
X290717D01*
X290467Y472833D01*
X290050Y473167D01*
X289467Y473333D01*
X288883Y473250D01*
X288383Y473000D01*
X288050Y472417D01*
X287883Y471917D01*
Y471417D01*
X288050Y470917D01*
X288467Y470417D01*
X288967Y470083D01*
X289550Y470000D01*
X290133Y470167D01*
X290717Y470667D01*
G01X293733Y470000D02*
Y473333D01*
G01Y472667D02*
X294150Y473000D01*
X294567Y473250D01*
X295150Y473333D01*
X295567Y473250D01*
X296067Y473000D01*
G01X299250Y470583D02*
X299667Y470250D01*
X300250Y470000D01*
X300750D01*
X301250Y470167D01*
X301583Y470417D01*
X301750Y470750D01*
X301667Y471250D01*
X301333Y471500D01*
X299833Y472000D01*
X299500Y472583D01*
X299667Y473000D01*
X300000Y473250D01*
X300500Y473333D01*
X301000Y473250D01*
X301500Y473000D01*
G01X311283Y468333D02*
X310450Y469167D01*
X310033Y470000D01*
Y473333D01*
X310450Y474167D01*
X311283Y475000D01*
G01X317300Y470000D02*
Y475000D01*
G01X322900Y473333D02*
Y470000D01*
G01Y474667D02*
X322733Y474750D01*
Y474917D01*
X322900Y475000D01*
X323067Y474917D01*
Y474750D01*
X322900Y474667D01*
G01X327083Y470000D02*
Y475000D01*
G01X329750Y473333D02*
X327083Y471417D01*
G01X328167Y472167D02*
X329917Y470000D01*
G01X332850Y472250D02*
X335517D01*
X335267Y472833D01*
X334850Y473167D01*
X334267Y473333D01*
X333683Y473250D01*
X333183Y473000D01*
X332850Y472417D01*
X332683Y471917D01*
Y471417D01*
X332850Y470917D01*
X333267Y470417D01*
X333767Y470083D01*
X334350Y470000D01*
X334933Y470167D01*
X335517Y470667D01*
G01X344050Y472250D02*
X346717D01*
X346467Y472833D01*
X346050Y473167D01*
X345467Y473333D01*
X344883Y473250D01*
X344383Y473000D01*
X344050Y472417D01*
X343883Y471917D01*
Y471417D01*
X344050Y470917D01*
X344467Y470417D01*
X344967Y470083D01*
X345550Y470000D01*
X346133Y470167D01*
X346717Y470667D01*
G01X350900Y470000D02*
Y475000D01*
G01X356500Y470000D02*
Y475000D01*
G01X362100Y473333D02*
Y470000D01*
G01Y474667D02*
X361933Y474750D01*
Y474917D01*
X362100Y475000D01*
X362267Y474917D01*
Y474750D01*
X362100Y474667D01*
G01X366200Y468333D02*
Y473333D01*
G01Y472583D02*
X366617Y473000D01*
X367033Y473250D01*
X367700Y473333D01*
X368283Y473250D01*
X368867Y472833D01*
X369117Y472250D01*
X369200Y471667D01*
X369117Y471083D01*
X368867Y470500D01*
X368367Y470167D01*
X367700Y470000D01*
X367117Y470083D01*
X366533Y470333D01*
X366200Y470667D01*
G01X372050Y470583D02*
X372467Y470250D01*
X373050Y470000D01*
X373550D01*
X374050Y470167D01*
X374383Y470417D01*
X374550Y470750D01*
X374467Y471250D01*
X374133Y471500D01*
X372633Y472000D01*
X372300Y472583D01*
X372467Y473000D01*
X372800Y473250D01*
X373300Y473333D01*
X373800Y473250D01*
X374300Y473000D01*
G01X377650Y472250D02*
X380317D01*
X380067Y472833D01*
X379650Y473167D01*
X379067Y473333D01*
X378483Y473250D01*
X377983Y473000D01*
X377650Y472417D01*
X377483Y471917D01*
Y471417D01*
X377650Y470917D01*
X378067Y470417D01*
X378567Y470083D01*
X379150Y470000D01*
X379733Y470167D01*
X380317Y470667D01*
G01X391600Y470000D02*
Y473333D01*
G01Y472750D02*
X391267Y473083D01*
X390767Y473250D01*
X390183Y473333D01*
X389600Y473167D01*
X389100Y472833D01*
X388767Y472333D01*
X388600Y471667D01*
X388767Y471000D01*
X389100Y470500D01*
X389600Y470167D01*
X390183Y470000D01*
X390767Y470083D01*
X391267Y470333D01*
X391600Y470667D01*
G01X394283Y470000D02*
Y473333D01*
G01Y472500D02*
X394617Y472917D01*
X395117Y473250D01*
X395783Y473333D01*
X396367Y473250D01*
X396867Y472917D01*
X397117Y472333D01*
Y470000D01*
G01X402800Y475000D02*
Y470000D01*
G01Y470750D02*
X402467Y470333D01*
X401967Y470083D01*
X401383Y470000D01*
X400717Y470167D01*
X400217Y470583D01*
X399883Y471083D01*
X399800Y471667D01*
X399883Y472250D01*
X400217Y472750D01*
X400717Y473167D01*
X401383Y473333D01*
X401967Y473250D01*
X402383Y473083D01*
X402800Y472750D01*
G01X412500Y470000D02*
X412000Y470083D01*
X411500Y470417D01*
X411167Y471000D01*
X411000Y471667D01*
X411167Y472333D01*
X411500Y472917D01*
X412000Y473250D01*
X412500Y473333D01*
X413000Y473250D01*
X413500Y472917D01*
X413833Y472333D01*
X413917Y471667D01*
X413833Y471000D01*
X413500Y470417D01*
X413000Y470083D01*
X412500Y470000D01*
G01X418100Y475000D02*
Y470000D01*
G01X416933Y473333D02*
X419267D01*
G01X422283Y470000D02*
Y475000D01*
G01Y472583D02*
X422700Y473000D01*
X423117Y473250D01*
X423783Y473333D01*
X424283Y473250D01*
X424867Y472917D01*
X425117Y472417D01*
Y470000D01*
G01X428050Y472250D02*
X430717D01*
X430467Y472833D01*
X430050Y473167D01*
X429467Y473333D01*
X428883Y473250D01*
X428383Y473000D01*
X428050Y472417D01*
X427883Y471917D01*
Y471417D01*
X428050Y470917D01*
X428467Y470417D01*
X428967Y470083D01*
X429550Y470000D01*
X430133Y470167D01*
X430717Y470667D01*
G01X433733Y470000D02*
Y473333D01*
G01Y472667D02*
X434150Y473000D01*
X434567Y473250D01*
X435150Y473333D01*
X435567Y473250D01*
X436067Y473000D01*
G01X439250Y470583D02*
X439667Y470250D01*
X440250Y470000D01*
X440750D01*
X441250Y470167D01*
X441583Y470417D01*
X441750Y470750D01*
X441667Y471250D01*
X441333Y471500D01*
X439833Y472000D01*
X439500Y472583D01*
X439667Y473000D01*
X440000Y473250D01*
X440500Y473333D01*
X441000Y473250D01*
X441500Y473000D01*
G01X446517Y468333D02*
X447350Y469167D01*
X447767Y470000D01*
Y473333D01*
X447350Y474167D01*
X446517Y475000D01*
G01X270833Y485000D02*
Y490000D01*
X272833D01*
X273500Y489750D01*
X274000Y489167D01*
X274167Y488500D01*
X274000Y487833D01*
X273583Y487333D01*
X272833Y487083D01*
X270833D01*
G01X278100Y490000D02*
Y485000D01*
G01X276183Y490000D02*
X280017D01*
G01X281950Y485000D02*
Y490000D01*
G01X285450D02*
Y485000D01*
G01Y487500D02*
X281950D01*
G01X287800Y484833D02*
X290800Y490000D01*
G01X292983Y485000D02*
Y490000D01*
X296817Y485000D01*
Y490000D01*
G01X298833Y485000D02*
Y490000D01*
X300833D01*
X301500Y489750D01*
X302000Y489167D01*
X302167Y488500D01*
X302000Y487833D01*
X301583Y487333D01*
X300833Y487083D01*
X298833D01*
G01X306100Y490000D02*
Y485000D01*
G01X304183Y490000D02*
X308017D01*
G01X309950Y485000D02*
Y490000D01*
G01X313450D02*
Y485000D01*
G01Y487500D02*
X309950D01*
G01X321233Y485000D02*
X324567Y486667D01*
X321233Y488333D01*
G01X327417Y485917D02*
X329583D01*
G01Y487417D02*
X327417D01*
G01X332267Y485750D02*
X332767Y485333D01*
X333350Y485083D01*
X334100Y485000D01*
X334850Y485167D01*
X335433Y485500D01*
X335850Y486083D01*
X335933Y486750D01*
X335767Y487417D01*
X335350Y487833D01*
X334767Y488167D01*
X334183Y488250D01*
X333600Y488167D01*
X332850Y487833D01*
X333100Y490000D01*
X335350D01*
G01X342800Y485000D02*
Y488333D01*
G01Y487417D02*
X343050Y487833D01*
X343467Y488167D01*
X344050Y488333D01*
X344633Y488167D01*
X345050Y487833D01*
X345300Y487417D01*
Y485000D01*
G01Y487417D02*
X345550Y487833D01*
X345967Y488167D01*
X346550Y488333D01*
X347133Y488167D01*
X347550Y487833D01*
X347800Y487333D01*
Y485000D01*
G01X348400D02*
Y488333D01*
G01Y487417D02*
X348650Y487833D01*
X349067Y488167D01*
X349650Y488333D01*
X350233Y488167D01*
X350650Y487833D01*
X350900Y487417D01*
Y485000D01*
G01Y487417D02*
X351150Y487833D01*
X351567Y488167D01*
X352150Y488333D01*
X352733Y488167D01*
X353150Y487833D01*
X353400Y487333D01*
Y485000D01*
G01X270583Y498500D02*
Y503500D01*
X274417Y498500D01*
Y503500D01*
G01X276433Y498500D02*
Y503500D01*
X278433D01*
X279100Y503250D01*
X279600Y502667D01*
X279767Y502000D01*
X279600Y501333D01*
X279183Y500833D01*
X278433Y500583D01*
X276433D01*
G01X283700Y503500D02*
Y498500D01*
G01X281783Y503500D02*
X285617D01*
G01X287550Y498500D02*
Y503500D01*
G01X291050D02*
Y498500D01*
G01Y501000D02*
X287550D01*
G01X298750Y499167D02*
X299417Y498750D01*
X300167Y498500D01*
X300833D01*
X301500Y498750D01*
X302000Y499167D01*
X302250Y499750D01*
X302083Y500333D01*
X301667Y500833D01*
X300917Y501167D01*
X299917Y501333D01*
X299333Y501667D01*
X299083Y502250D01*
X299250Y502833D01*
X299667Y503250D01*
X300250Y503500D01*
X300833D01*
X301417Y503333D01*
X301917Y502917D01*
G01X306100Y501833D02*
Y498500D01*
G01Y503167D02*
X305933Y503250D01*
Y503417D01*
X306100Y503500D01*
X306267Y503417D01*
Y503250D01*
X306100Y503167D01*
G01X310450Y501833D02*
X312950D01*
X310450Y498500D01*
X312950D01*
G01X316050Y500750D02*
X318717D01*
X318467Y501333D01*
X318050Y501667D01*
X317467Y501833D01*
X316883Y501750D01*
X316383Y501500D01*
X316050Y500917D01*
X315883Y500417D01*
Y499917D01*
X316050Y499417D01*
X316467Y498917D01*
X316967Y498583D01*
X317550Y498500D01*
X318133Y498667D01*
X318717Y499167D01*
G01X326667Y499500D02*
X327167Y498917D01*
X327833Y498583D01*
X328583Y498500D01*
X329250Y498583D01*
X329917Y499000D01*
X330333Y499500D01*
X330417Y500000D01*
X330250Y500583D01*
X329667Y501000D01*
X329083Y501167D01*
X328333D01*
G01X329083D02*
X329583Y501417D01*
X330000Y501833D01*
X330167Y502333D01*
X330000Y502833D01*
X329583Y503250D01*
X328833Y503500D01*
X328083Y503417D01*
X327333Y503083D01*
G01X334100Y498333D02*
X333933Y498417D01*
Y498583D01*
X334100Y498667D01*
X334267Y498583D01*
Y498417D01*
X334100Y498333D01*
G01X337867Y499250D02*
X338367Y498833D01*
X338950Y498583D01*
X339700Y498500D01*
X340450Y498667D01*
X341033Y499000D01*
X341450Y499583D01*
X341533Y500250D01*
X341367Y500917D01*
X340950Y501333D01*
X340367Y501667D01*
X339783Y501750D01*
X339200Y501667D01*
X338450Y501333D01*
X338700Y503500D01*
X340950D01*
G01X343467Y499250D02*
X343967Y498833D01*
X344550Y498583D01*
X345300Y498500D01*
X346050Y498667D01*
X346633Y499000D01*
X347050Y499583D01*
X347133Y500250D01*
X346967Y500917D01*
X346550Y501333D01*
X345967Y501667D01*
X345383Y501750D01*
X344800Y501667D01*
X344050Y501333D01*
X344300Y503500D01*
X346550D01*
G01X348400Y498500D02*
Y501833D01*
G01Y500917D02*
X348650Y501333D01*
X349067Y501667D01*
X349650Y501833D01*
X350233Y501667D01*
X350650Y501333D01*
X350900Y500917D01*
Y498500D01*
G01Y500917D02*
X351150Y501333D01*
X351567Y501667D01*
X352150Y501833D01*
X352733Y501667D01*
X353150Y501333D01*
X353400Y500833D01*
Y498500D01*
G01X354000D02*
Y501833D01*
G01Y500917D02*
X354250Y501333D01*
X354667Y501667D01*
X355250Y501833D01*
X355833Y501667D01*
X356250Y501333D01*
X356500Y500917D01*
Y498500D01*
G01Y500917D02*
X356750Y501333D01*
X357167Y501667D01*
X357750Y501833D01*
X358333Y501667D01*
X358750Y501333D01*
X359000Y500833D01*
Y498500D01*
G01X270583Y513500D02*
Y518500D01*
X274417Y513500D01*
Y518500D01*
G01X276433Y513500D02*
Y518500D01*
X278433D01*
X279100Y518250D01*
X279600Y517667D01*
X279767Y517000D01*
X279600Y516333D01*
X279183Y515833D01*
X278433Y515583D01*
X276433D01*
G01X283700Y518500D02*
Y513500D01*
G01X281783Y518500D02*
X285617D01*
G01X287550Y513500D02*
Y518500D01*
G01X291050D02*
Y513500D01*
G01Y516000D02*
X287550D01*
G01X298750Y514167D02*
X299417Y513750D01*
X300167Y513500D01*
X300833D01*
X301500Y513750D01*
X302000Y514167D01*
X302250Y514750D01*
X302083Y515333D01*
X301667Y515833D01*
X300917Y516167D01*
X299917Y516333D01*
X299333Y516667D01*
X299083Y517250D01*
X299250Y517833D01*
X299667Y518250D01*
X300250Y518500D01*
X300833D01*
X301417Y518333D01*
X301917Y517917D01*
G01X306100Y516833D02*
Y513500D01*
G01Y518167D02*
X305933Y518250D01*
Y518417D01*
X306100Y518500D01*
X306267Y518417D01*
Y518250D01*
X306100Y518167D01*
G01X310450Y516833D02*
X312950D01*
X310450Y513500D01*
X312950D01*
G01X316050Y515750D02*
X318717D01*
X318467Y516333D01*
X318050Y516667D01*
X317467Y516833D01*
X316883Y516750D01*
X316383Y516500D01*
X316050Y515917D01*
X315883Y515417D01*
Y514917D01*
X316050Y514417D01*
X316467Y513917D01*
X316967Y513583D01*
X317550Y513500D01*
X318133Y513667D01*
X318717Y514167D01*
G01X324567Y513500D02*
X321233Y515167D01*
X324567Y516833D01*
G01X332267Y514250D02*
X332767Y513833D01*
X333350Y513583D01*
X334100Y513500D01*
X334850Y513667D01*
X335433Y514000D01*
X335850Y514583D01*
X335933Y515250D01*
X335767Y515917D01*
X335350Y516333D01*
X334767Y516667D01*
X334183Y516750D01*
X333600Y516667D01*
X332850Y516333D01*
X333100Y518500D01*
X335350D01*
G01X337200Y513500D02*
Y516833D01*
G01Y515917D02*
X337450Y516333D01*
X337867Y516667D01*
X338450Y516833D01*
X339033Y516667D01*
X339450Y516333D01*
X339700Y515917D01*
Y513500D01*
G01Y515917D02*
X339950Y516333D01*
X340367Y516667D01*
X340950Y516833D01*
X341533Y516667D01*
X341950Y516333D01*
X342200Y515833D01*
Y513500D01*
G01X342800D02*
Y516833D01*
G01Y515917D02*
X343050Y516333D01*
X343467Y516667D01*
X344050Y516833D01*
X344633Y516667D01*
X345050Y516333D01*
X345300Y515917D01*
Y513500D01*
G01Y515917D02*
X345550Y516333D01*
X345967Y516667D01*
X346550Y516833D01*
X347133Y516667D01*
X347550Y516333D01*
X347800Y515833D01*
Y513500D01*
G01X270667Y535000D02*
Y531417D01*
X271000Y530667D01*
X271667Y530167D01*
X272500Y530000D01*
X273333Y530167D01*
X274000Y530667D01*
X274333Y531417D01*
Y535000D01*
G01X276683Y530000D02*
Y533333D01*
G01Y532500D02*
X277017Y532917D01*
X277517Y533250D01*
X278183Y533333D01*
X278767Y533250D01*
X279267Y532917D01*
X279517Y532333D01*
Y530000D01*
G01X282617Y531667D02*
X284783D01*
G01X287800Y528333D02*
Y533333D01*
G01Y532583D02*
X288217Y533000D01*
X288633Y533250D01*
X289300Y533333D01*
X289883Y533250D01*
X290467Y532833D01*
X290717Y532250D01*
X290800Y531667D01*
X290717Y531083D01*
X290467Y530500D01*
X289967Y530167D01*
X289300Y530000D01*
X288717Y530083D01*
X288133Y530333D01*
X287800Y530667D01*
G01X294900Y530000D02*
Y535000D01*
G01X299083Y533333D02*
Y531000D01*
X299417Y530417D01*
X299917Y530083D01*
X300500Y530000D01*
X301083Y530083D01*
X301583Y530417D01*
X301917Y531000D01*
G01Y530000D02*
Y533333D01*
G01X304933Y528750D02*
X305517Y528417D01*
X306183Y528333D01*
X306767Y528417D01*
X307267Y528833D01*
X307600Y529417D01*
Y533333D01*
G01Y532667D02*
X307267Y533000D01*
X306767Y533250D01*
X306183Y533333D01*
X305517Y533167D01*
X305100Y532833D01*
X304767Y532250D01*
X304600Y531667D01*
X304683Y531167D01*
X305017Y530583D01*
X305517Y530167D01*
X306183Y530000D01*
X306683Y530083D01*
X307267Y530417D01*
X307600Y530750D01*
G01X310533Y528750D02*
X311117Y528417D01*
X311783Y528333D01*
X312367Y528417D01*
X312867Y528833D01*
X313200Y529417D01*
Y533333D01*
G01Y532667D02*
X312867Y533000D01*
X312367Y533250D01*
X311783Y533333D01*
X311117Y533167D01*
X310700Y532833D01*
X310367Y532250D01*
X310200Y531667D01*
X310283Y531167D01*
X310617Y530583D01*
X311117Y530167D01*
X311783Y530000D01*
X312283Y530083D01*
X312867Y530417D01*
X313200Y530750D01*
G01X316050Y532250D02*
X318717D01*
X318467Y532833D01*
X318050Y533167D01*
X317467Y533333D01*
X316883Y533250D01*
X316383Y533000D01*
X316050Y532417D01*
X315883Y531917D01*
Y531417D01*
X316050Y530917D01*
X316467Y530417D01*
X316967Y530083D01*
X317550Y530000D01*
X318133Y530167D01*
X318717Y530667D01*
G01X324400Y535000D02*
Y530000D01*
G01Y530750D02*
X324067Y530333D01*
X323567Y530083D01*
X322983Y530000D01*
X322317Y530167D01*
X321817Y530583D01*
X321483Y531083D01*
X321400Y531667D01*
X321483Y532250D01*
X321817Y532750D01*
X322317Y533167D01*
X322983Y533333D01*
X323567Y533250D01*
X323983Y533083D01*
X324400Y532750D01*
G01X332433Y530000D02*
Y535000D01*
X334433D01*
X335100Y534750D01*
X335600Y534167D01*
X335767Y533500D01*
X335600Y532833D01*
X335183Y532333D01*
X334433Y532083D01*
X332433D01*
G01X339700Y535000D02*
Y530000D01*
G01X337783Y535000D02*
X341617D01*
G01X343550Y530000D02*
Y535000D01*
G01X347050D02*
Y530000D01*
G01Y532500D02*
X343550D01*
G01X356083Y528333D02*
X355250Y529167D01*
X354833Y530000D01*
Y533333D01*
X355250Y534167D01*
X356083Y535000D01*
G01X360350Y530000D02*
Y535000D01*
G01X363850D02*
Y530000D01*
G01Y532500D02*
X360350D01*
G01X367700Y530000D02*
X367200Y530083D01*
X366700Y530417D01*
X366367Y531000D01*
X366200Y531667D01*
X366367Y532333D01*
X366700Y532917D01*
X367200Y533250D01*
X367700Y533333D01*
X368200Y533250D01*
X368700Y532917D01*
X369033Y532333D01*
X369117Y531667D01*
X369033Y531000D01*
X368700Y530417D01*
X368200Y530083D01*
X367700Y530000D01*
G01X373300D02*
Y535000D01*
G01X377650Y532250D02*
X380317D01*
X380067Y532833D01*
X379650Y533167D01*
X379067Y533333D01*
X378483Y533250D01*
X377983Y533000D01*
X377650Y532417D01*
X377483Y531917D01*
Y531417D01*
X377650Y530917D01*
X378067Y530417D01*
X378567Y530083D01*
X379150Y530000D01*
X379733Y530167D01*
X380317Y530667D01*
G01X388350D02*
X389017Y530250D01*
X389767Y530000D01*
X390433D01*
X391100Y530250D01*
X391600Y530667D01*
X391850Y531250D01*
X391683Y531833D01*
X391267Y532333D01*
X390517Y532667D01*
X389517Y532833D01*
X388933Y533167D01*
X388683Y533750D01*
X388850Y534333D01*
X389267Y534750D01*
X389850Y535000D01*
X390433D01*
X391017Y534833D01*
X391517Y534417D01*
G01X395700Y533333D02*
Y530000D01*
G01Y534667D02*
X395533Y534750D01*
Y534917D01*
X395700Y535000D01*
X395867Y534917D01*
Y534750D01*
X395700Y534667D01*
G01X400050Y533333D02*
X402550D01*
X400050Y530000D01*
X402550D01*
G01X405650Y532250D02*
X408317D01*
X408067Y532833D01*
X407650Y533167D01*
X407067Y533333D01*
X406483Y533250D01*
X405983Y533000D01*
X405650Y532417D01*
X405483Y531917D01*
Y531417D01*
X405650Y530917D01*
X406067Y530417D01*
X406567Y530083D01*
X407150Y530000D01*
X407733Y530167D01*
X408317Y530667D01*
G01X414167Y530000D02*
X410833Y531667D01*
X414167Y533333D01*
G01X418100Y530000D02*
Y535000D01*
X417100Y534000D01*
G01Y530000D02*
X419100D01*
G01X422283Y530583D02*
X422867Y530167D01*
X423533Y530000D01*
X424200Y530167D01*
X424783Y530667D01*
X425200Y531417D01*
X425367Y532167D01*
Y533083D01*
X425200Y533833D01*
X424783Y534500D01*
X424283Y534833D01*
X423700Y535000D01*
X423033Y534833D01*
X422533Y534500D01*
X422200Y534000D01*
X422033Y533333D01*
X422200Y532750D01*
X422617Y532167D01*
X423117Y531833D01*
X423700Y531750D01*
X424367Y531917D01*
X424867Y532333D01*
X425367Y533083D01*
G01X429133Y530000D02*
X429300Y531083D01*
X429550Y532000D01*
X429883Y532833D01*
X430300Y533750D01*
X430967Y535000D01*
X427633D01*
G01X432400Y530000D02*
Y533333D01*
G01Y532417D02*
X432650Y532833D01*
X433067Y533167D01*
X433650Y533333D01*
X434233Y533167D01*
X434650Y532833D01*
X434900Y532417D01*
Y530000D01*
G01Y532417D02*
X435150Y532833D01*
X435567Y533167D01*
X436150Y533333D01*
X436733Y533167D01*
X437150Y532833D01*
X437400Y532333D01*
Y530000D01*
G01X440500Y533333D02*
Y530000D01*
G01Y534667D02*
X440333Y534750D01*
Y534917D01*
X440500Y535000D01*
X440667Y534917D01*
Y534750D01*
X440500Y534667D01*
G01X446100Y530000D02*
Y535000D01*
G01X455217Y533333D02*
X456217Y530000D01*
X457300Y533333D01*
X458383Y530000D01*
X459383Y533333D01*
G01X462900D02*
Y530000D01*
G01Y534667D02*
X462733Y534750D01*
Y534917D01*
X462900Y535000D01*
X463067Y534917D01*
Y534750D01*
X462900Y534667D01*
G01X468500Y535000D02*
Y530000D01*
G01X467333Y533333D02*
X469667D01*
G01X472683Y530000D02*
Y535000D01*
G01Y532583D02*
X473100Y533000D01*
X473517Y533250D01*
X474183Y533333D01*
X474683Y533250D01*
X475267Y532917D01*
X475517Y532417D01*
Y530000D01*
G01X483550D02*
Y535000D01*
G01X487050D02*
Y530000D01*
G01Y532500D02*
X483550D01*
G01X488817Y530000D02*
X490900Y535000D01*
X492983Y530000D01*
G01X492233Y531750D02*
X489567D01*
G01X494750Y530667D02*
X495417Y530250D01*
X496167Y530000D01*
X496833D01*
X497500Y530250D01*
X498000Y530667D01*
X498250Y531250D01*
X498083Y531833D01*
X497667Y532333D01*
X496917Y532667D01*
X495917Y532833D01*
X495333Y533167D01*
X495083Y533750D01*
X495250Y534333D01*
X495667Y534750D01*
X496250Y535000D01*
X496833D01*
X497417Y534833D01*
X497917Y534417D01*
G01X500433Y535000D02*
Y530000D01*
X503767D01*
G01X511800Y528333D02*
Y533333D01*
G01Y532583D02*
X512217Y533000D01*
X512633Y533250D01*
X513300Y533333D01*
X513883Y533250D01*
X514467Y532833D01*
X514717Y532250D01*
X514800Y531667D01*
X514717Y531083D01*
X514467Y530500D01*
X513967Y530167D01*
X513300Y530000D01*
X512717Y530083D01*
X512133Y530333D01*
X511800Y530667D01*
G01X517733Y530000D02*
Y533333D01*
G01Y532667D02*
X518150Y533000D01*
X518567Y533250D01*
X519150Y533333D01*
X519567Y533250D01*
X520067Y533000D01*
G01X524500Y530000D02*
X524000Y530083D01*
X523500Y530417D01*
X523167Y531000D01*
X523000Y531667D01*
X523167Y532333D01*
X523500Y532917D01*
X524000Y533250D01*
X524500Y533333D01*
X525000Y533250D01*
X525500Y532917D01*
X525833Y532333D01*
X525917Y531667D01*
X525833Y531000D01*
X525500Y530417D01*
X525000Y530083D01*
X524500Y530000D01*
G01X531600Y535000D02*
Y530000D01*
G01Y530750D02*
X531267Y530333D01*
X530767Y530083D01*
X530183Y530000D01*
X529517Y530167D01*
X529017Y530583D01*
X528683Y531083D01*
X528600Y531667D01*
X528683Y532250D01*
X529017Y532750D01*
X529517Y533167D01*
X530183Y533333D01*
X530767Y533250D01*
X531183Y533083D01*
X531600Y532750D01*
G01X534283Y533333D02*
Y531000D01*
X534617Y530417D01*
X535117Y530083D01*
X535700Y530000D01*
X536283Y530083D01*
X536783Y530417D01*
X537117Y531000D01*
G01Y530000D02*
Y533333D01*
G01X542633Y532917D02*
X542050Y533250D01*
X541550Y533333D01*
X540883Y533167D01*
X540383Y532833D01*
X540050Y532250D01*
X539967Y531667D01*
X540050Y531083D01*
X540383Y530583D01*
X540883Y530167D01*
X541550Y530000D01*
X542133Y530167D01*
X542633Y530500D01*
G01X546900Y535000D02*
Y530000D01*
G01X545733Y533333D02*
X548067D01*
G01X551250Y530583D02*
X551667Y530250D01*
X552250Y530000D01*
X552750D01*
X553250Y530167D01*
X553583Y530417D01*
X553750Y530750D01*
X553667Y531250D01*
X553333Y531500D01*
X551833Y532000D01*
X551500Y532583D01*
X551667Y533000D01*
X552000Y533250D01*
X552500Y533333D01*
X553000Y533250D01*
X553500Y533000D01*
G01X558517Y528333D02*
X559350Y529167D01*
X559767Y530000D01*
Y533333D01*
X559350Y534167D01*
X558517Y535000D01*
G01X270667Y550000D02*
Y546417D01*
X271000Y545667D01*
X271667Y545167D01*
X272500Y545000D01*
X273333Y545167D01*
X274000Y545667D01*
X274333Y546417D01*
Y550000D01*
G01X276683Y545000D02*
Y548333D01*
G01Y547500D02*
X277017Y547917D01*
X277517Y548250D01*
X278183Y548333D01*
X278767Y548250D01*
X279267Y547917D01*
X279517Y547333D01*
Y545000D01*
G01X282617Y546667D02*
X284783D01*
G01X287800Y543333D02*
Y548333D01*
G01Y547583D02*
X288217Y548000D01*
X288633Y548250D01*
X289300Y548333D01*
X289883Y548250D01*
X290467Y547833D01*
X290717Y547250D01*
X290800Y546667D01*
X290717Y546083D01*
X290467Y545500D01*
X289967Y545167D01*
X289300Y545000D01*
X288717Y545083D01*
X288133Y545333D01*
X287800Y545667D01*
G01X294900Y545000D02*
Y550000D01*
G01X299083Y548333D02*
Y546000D01*
X299417Y545417D01*
X299917Y545083D01*
X300500Y545000D01*
X301083Y545083D01*
X301583Y545417D01*
X301917Y546000D01*
G01Y545000D02*
Y548333D01*
G01X304933Y543750D02*
X305517Y543417D01*
X306183Y543333D01*
X306767Y543417D01*
X307267Y543833D01*
X307600Y544417D01*
Y548333D01*
G01Y547667D02*
X307267Y548000D01*
X306767Y548250D01*
X306183Y548333D01*
X305517Y548167D01*
X305100Y547833D01*
X304767Y547250D01*
X304600Y546667D01*
X304683Y546167D01*
X305017Y545583D01*
X305517Y545167D01*
X306183Y545000D01*
X306683Y545083D01*
X307267Y545417D01*
X307600Y545750D01*
G01X310533Y543750D02*
X311117Y543417D01*
X311783Y543333D01*
X312367Y543417D01*
X312867Y543833D01*
X313200Y544417D01*
Y548333D01*
G01Y547667D02*
X312867Y548000D01*
X312367Y548250D01*
X311783Y548333D01*
X311117Y548167D01*
X310700Y547833D01*
X310367Y547250D01*
X310200Y546667D01*
X310283Y546167D01*
X310617Y545583D01*
X311117Y545167D01*
X311783Y545000D01*
X312283Y545083D01*
X312867Y545417D01*
X313200Y545750D01*
G01X316050Y547250D02*
X318717D01*
X318467Y547833D01*
X318050Y548167D01*
X317467Y548333D01*
X316883Y548250D01*
X316383Y548000D01*
X316050Y547417D01*
X315883Y546917D01*
Y546417D01*
X316050Y545917D01*
X316467Y545417D01*
X316967Y545083D01*
X317550Y545000D01*
X318133Y545167D01*
X318717Y545667D01*
G01X324400Y550000D02*
Y545000D01*
G01Y545750D02*
X324067Y545333D01*
X323567Y545083D01*
X322983Y545000D01*
X322317Y545167D01*
X321817Y545583D01*
X321483Y546083D01*
X321400Y546667D01*
X321483Y547250D01*
X321817Y547750D01*
X322317Y548167D01*
X322983Y548333D01*
X323567Y548250D01*
X323983Y548083D01*
X324400Y547750D01*
G01X332433Y545000D02*
Y550000D01*
X334433D01*
X335100Y549750D01*
X335600Y549167D01*
X335767Y548500D01*
X335600Y547833D01*
X335183Y547333D01*
X334433Y547083D01*
X332433D01*
G01X339700Y550000D02*
Y545000D01*
G01X337783Y550000D02*
X341617D01*
G01X343550Y545000D02*
Y550000D01*
G01X347050D02*
Y545000D01*
G01Y547500D02*
X343550D01*
G01X356083Y543333D02*
X355250Y544167D01*
X354833Y545000D01*
Y548333D01*
X355250Y549167D01*
X356083Y550000D01*
G01X360350Y545000D02*
Y550000D01*
G01X363850D02*
Y545000D01*
G01Y547500D02*
X360350D01*
G01X367700Y545000D02*
X367200Y545083D01*
X366700Y545417D01*
X366367Y546000D01*
X366200Y546667D01*
X366367Y547333D01*
X366700Y547917D01*
X367200Y548250D01*
X367700Y548333D01*
X368200Y548250D01*
X368700Y547917D01*
X369033Y547333D01*
X369117Y546667D01*
X369033Y546000D01*
X368700Y545417D01*
X368200Y545083D01*
X367700Y545000D01*
G01X373300D02*
Y550000D01*
G01X377650Y547250D02*
X380317D01*
X380067Y547833D01*
X379650Y548167D01*
X379067Y548333D01*
X378483Y548250D01*
X377983Y548000D01*
X377650Y547417D01*
X377483Y546917D01*
Y546417D01*
X377650Y545917D01*
X378067Y545417D01*
X378567Y545083D01*
X379150Y545000D01*
X379733Y545167D01*
X380317Y545667D01*
G01X388350D02*
X389017Y545250D01*
X389767Y545000D01*
X390433D01*
X391100Y545250D01*
X391600Y545667D01*
X391850Y546250D01*
X391683Y546833D01*
X391267Y547333D01*
X390517Y547667D01*
X389517Y547833D01*
X388933Y548167D01*
X388683Y548750D01*
X388850Y549333D01*
X389267Y549750D01*
X389850Y550000D01*
X390433D01*
X391017Y549833D01*
X391517Y549417D01*
G01X395700Y548333D02*
Y545000D01*
G01Y549667D02*
X395533Y549750D01*
Y549917D01*
X395700Y550000D01*
X395867Y549917D01*
Y549750D01*
X395700Y549667D01*
G01X400050Y548333D02*
X402550D01*
X400050Y545000D01*
X402550D01*
G01X405650Y547250D02*
X408317D01*
X408067Y547833D01*
X407650Y548167D01*
X407067Y548333D01*
X406483Y548250D01*
X405983Y548000D01*
X405650Y547417D01*
X405483Y546917D01*
Y546417D01*
X405650Y545917D01*
X406067Y545417D01*
X406567Y545083D01*
X407150Y545000D01*
X407733Y545167D01*
X408317Y545667D01*
G01X414167Y545000D02*
X410833Y546667D01*
X414167Y548333D01*
G01X418100Y545000D02*
Y550000D01*
X417100Y549000D01*
G01Y545000D02*
X419100D01*
G01X422283Y545583D02*
X422867Y545167D01*
X423533Y545000D01*
X424200Y545167D01*
X424783Y545667D01*
X425200Y546417D01*
X425367Y547167D01*
Y548083D01*
X425200Y548833D01*
X424783Y549500D01*
X424283Y549833D01*
X423700Y550000D01*
X423033Y549833D01*
X422533Y549500D01*
X422200Y549000D01*
X422033Y548333D01*
X422200Y547750D01*
X422617Y547167D01*
X423117Y546833D01*
X423700Y546750D01*
X424367Y546917D01*
X424867Y547333D01*
X425367Y548083D01*
G01X429133Y545000D02*
X429300Y546083D01*
X429550Y547000D01*
X429883Y547833D01*
X430300Y548750D01*
X430967Y550000D01*
X427633D01*
G01X432400Y545000D02*
Y548333D01*
G01Y547417D02*
X432650Y547833D01*
X433067Y548167D01*
X433650Y548333D01*
X434233Y548167D01*
X434650Y547833D01*
X434900Y547417D01*
Y545000D01*
G01Y547417D02*
X435150Y547833D01*
X435567Y548167D01*
X436150Y548333D01*
X436733Y548167D01*
X437150Y547833D01*
X437400Y547333D01*
Y545000D01*
G01X440500Y548333D02*
Y545000D01*
G01Y549667D02*
X440333Y549750D01*
Y549917D01*
X440500Y550000D01*
X440667Y549917D01*
Y549750D01*
X440500Y549667D01*
G01X446100Y545000D02*
Y550000D01*
G01X455217Y548333D02*
X456217Y545000D01*
X457300Y548333D01*
X458383Y545000D01*
X459383Y548333D01*
G01X462900D02*
Y545000D01*
G01Y549667D02*
X462733Y549750D01*
Y549917D01*
X462900Y550000D01*
X463067Y549917D01*
Y549750D01*
X462900Y549667D01*
G01X468500Y550000D02*
Y545000D01*
G01X467333Y548333D02*
X469667D01*
G01X472683Y545000D02*
Y550000D01*
G01Y547583D02*
X473100Y548000D01*
X473517Y548250D01*
X474183Y548333D01*
X474683Y548250D01*
X475267Y547917D01*
X475517Y547417D01*
Y545000D01*
G01X483883D02*
Y548333D01*
G01Y547500D02*
X484217Y547917D01*
X484717Y548250D01*
X485383Y548333D01*
X485967Y548250D01*
X486467Y547917D01*
X486717Y547333D01*
Y545000D01*
G01X490900D02*
X490400Y545083D01*
X489900Y545417D01*
X489567Y546000D01*
X489400Y546667D01*
X489567Y547333D01*
X489900Y547917D01*
X490400Y548250D01*
X490900Y548333D01*
X491400Y548250D01*
X491900Y547917D01*
X492233Y547333D01*
X492317Y546667D01*
X492233Y546000D01*
X491900Y545417D01*
X491400Y545083D01*
X490900Y545000D01*
G01X495083D02*
Y548333D01*
G01Y547500D02*
X495417Y547917D01*
X495917Y548250D01*
X496583Y548333D01*
X497167Y548250D01*
X497667Y547917D01*
X497917Y547333D01*
Y545000D01*
G01X501017Y546667D02*
X503183D01*
G01X505950Y545000D02*
Y550000D01*
G01X509450D02*
Y545000D01*
G01Y547500D02*
X505950D01*
G01X511217Y545000D02*
X513300Y550000D01*
X515383Y545000D01*
G01X514633Y546750D02*
X511967D01*
G01X517150Y545667D02*
X517817Y545250D01*
X518567Y545000D01*
X519233D01*
X519900Y545250D01*
X520400Y545667D01*
X520650Y546250D01*
X520483Y546833D01*
X520067Y547333D01*
X519317Y547667D01*
X518317Y547833D01*
X517733Y548167D01*
X517483Y548750D01*
X517650Y549333D01*
X518067Y549750D01*
X518650Y550000D01*
X519233D01*
X519817Y549833D01*
X520317Y549417D01*
G01X522833Y550000D02*
Y545000D01*
X526167D01*
G01X534200Y543333D02*
Y548333D01*
G01Y547583D02*
X534617Y548000D01*
X535033Y548250D01*
X535700Y548333D01*
X536283Y548250D01*
X536867Y547833D01*
X537117Y547250D01*
X537200Y546667D01*
X537117Y546083D01*
X536867Y545500D01*
X536367Y545167D01*
X535700Y545000D01*
X535117Y545083D01*
X534533Y545333D01*
X534200Y545667D01*
G01X540133Y545000D02*
Y548333D01*
G01Y547667D02*
X540550Y548000D01*
X540967Y548250D01*
X541550Y548333D01*
X541967Y548250D01*
X542467Y548000D01*
G01X546900Y545000D02*
X546400Y545083D01*
X545900Y545417D01*
X545567Y546000D01*
X545400Y546667D01*
X545567Y547333D01*
X545900Y547917D01*
X546400Y548250D01*
X546900Y548333D01*
X547400Y548250D01*
X547900Y547917D01*
X548233Y547333D01*
X548317Y546667D01*
X548233Y546000D01*
X547900Y545417D01*
X547400Y545083D01*
X546900Y545000D01*
G01X554000Y550000D02*
Y545000D01*
G01Y545750D02*
X553667Y545333D01*
X553167Y545083D01*
X552583Y545000D01*
X551917Y545167D01*
X551417Y545583D01*
X551083Y546083D01*
X551000Y546667D01*
X551083Y547250D01*
X551417Y547750D01*
X551917Y548167D01*
X552583Y548333D01*
X553167Y548250D01*
X553583Y548083D01*
X554000Y547750D01*
G01X556683Y548333D02*
Y546000D01*
X557017Y545417D01*
X557517Y545083D01*
X558100Y545000D01*
X558683Y545083D01*
X559183Y545417D01*
X559517Y546000D01*
G01Y545000D02*
Y548333D01*
G01X565033Y547917D02*
X564450Y548250D01*
X563950Y548333D01*
X563283Y548167D01*
X562783Y547833D01*
X562450Y547250D01*
X562367Y546667D01*
X562450Y546083D01*
X562783Y545583D01*
X563283Y545167D01*
X563950Y545000D01*
X564533Y545167D01*
X565033Y545500D01*
G01X569300Y550000D02*
Y545000D01*
G01X568133Y548333D02*
X570467D01*
G01X573650Y545583D02*
X574067Y545250D01*
X574650Y545000D01*
X575150D01*
X575650Y545167D01*
X575983Y545417D01*
X576150Y545750D01*
X576067Y546250D01*
X575733Y546500D01*
X574233Y547000D01*
X573900Y547583D01*
X574067Y548000D01*
X574400Y548250D01*
X574900Y548333D01*
X575400Y548250D01*
X575900Y548000D01*
G01X580917Y543333D02*
X581750Y544167D01*
X582167Y545000D01*
Y548333D01*
X581750Y549167D01*
X580917Y550000D01*
G01X273000Y609000D02*
Y604000D01*
G01X271083Y609000D02*
X274917D01*
G01X277183Y604000D02*
Y609000D01*
G01Y606583D02*
X277600Y607000D01*
X278017Y607250D01*
X278683Y607333D01*
X279183Y607250D01*
X279767Y606917D01*
X280017Y606417D01*
Y604000D01*
G01X282950Y606250D02*
X285617D01*
X285367Y606833D01*
X284950Y607167D01*
X284367Y607333D01*
X283783Y607250D01*
X283283Y607000D01*
X282950Y606417D01*
X282783Y605917D01*
Y605417D01*
X282950Y604917D01*
X283367Y604417D01*
X283867Y604083D01*
X284450Y604000D01*
X285033Y604167D01*
X285617Y604667D01*
G01X288633Y604000D02*
Y607333D01*
G01Y606667D02*
X289050Y607000D01*
X289467Y607250D01*
X290050Y607333D01*
X290467Y607250D01*
X290967Y607000D01*
G01X292900Y604000D02*
Y607333D01*
G01Y606417D02*
X293150Y606833D01*
X293567Y607167D01*
X294150Y607333D01*
X294733Y607167D01*
X295150Y606833D01*
X295400Y606417D01*
Y604000D01*
G01Y606417D02*
X295650Y606833D01*
X296067Y607167D01*
X296650Y607333D01*
X297233Y607167D01*
X297650Y606833D01*
X297900Y606333D01*
Y604000D01*
G01X302500D02*
Y607333D01*
G01Y606750D02*
X302167Y607083D01*
X301667Y607250D01*
X301083Y607333D01*
X300500Y607167D01*
X300000Y606833D01*
X299667Y606333D01*
X299500Y605667D01*
X299667Y605000D01*
X300000Y604500D01*
X300500Y604167D01*
X301083Y604000D01*
X301667Y604083D01*
X302167Y604333D01*
X302500Y604667D01*
G01X306600Y604000D02*
Y609000D01*
G01X316300Y602333D02*
Y607333D01*
G01Y606583D02*
X316717Y607000D01*
X317133Y607250D01*
X317800Y607333D01*
X318383Y607250D01*
X318967Y606833D01*
X319217Y606250D01*
X319300Y605667D01*
X319217Y605083D01*
X318967Y604500D01*
X318467Y604167D01*
X317800Y604000D01*
X317217Y604083D01*
X316633Y604333D01*
X316300Y604667D01*
G01X324900Y604000D02*
Y607333D01*
G01Y606750D02*
X324567Y607083D01*
X324067Y607250D01*
X323483Y607333D01*
X322900Y607167D01*
X322400Y606833D01*
X322067Y606333D01*
X321900Y605667D01*
X322067Y605000D01*
X322400Y604500D01*
X322900Y604167D01*
X323483Y604000D01*
X324067Y604083D01*
X324567Y604333D01*
X324900Y604667D01*
G01X330500Y609000D02*
Y604000D01*
G01Y604750D02*
X330167Y604333D01*
X329667Y604083D01*
X329083Y604000D01*
X328417Y604167D01*
X327917Y604583D01*
X327583Y605083D01*
X327500Y605667D01*
X327583Y606250D01*
X327917Y606750D01*
X328417Y607167D01*
X329083Y607333D01*
X329667Y607250D01*
X330083Y607083D01*
X330500Y606750D01*
G01X341533Y606917D02*
X340950Y607250D01*
X340450Y607333D01*
X339783Y607167D01*
X339283Y606833D01*
X338950Y606250D01*
X338867Y605667D01*
X338950Y605083D01*
X339283Y604583D01*
X339783Y604167D01*
X340450Y604000D01*
X341033Y604167D01*
X341533Y604500D01*
G01X347300Y604000D02*
Y607333D01*
G01Y606750D02*
X346967Y607083D01*
X346467Y607250D01*
X345883Y607333D01*
X345300Y607167D01*
X344800Y606833D01*
X344467Y606333D01*
X344300Y605667D01*
X344467Y605000D01*
X344800Y604500D01*
X345300Y604167D01*
X345883Y604000D01*
X346467Y604083D01*
X346967Y604333D01*
X347300Y604667D01*
G01X349983Y604000D02*
Y607333D01*
G01Y606500D02*
X350317Y606917D01*
X350817Y607250D01*
X351483Y607333D01*
X352067Y607250D01*
X352567Y606917D01*
X352817Y606333D01*
Y604000D01*
G01X363933Y606917D02*
X363350Y607250D01*
X362850Y607333D01*
X362183Y607167D01*
X361683Y606833D01*
X361350Y606250D01*
X361267Y605667D01*
X361350Y605083D01*
X361683Y604583D01*
X362183Y604167D01*
X362850Y604000D01*
X363433Y604167D01*
X363933Y604500D01*
G01X366783Y604000D02*
Y609000D01*
G01Y606583D02*
X367200Y607000D01*
X367617Y607250D01*
X368283Y607333D01*
X368783Y607250D01*
X369367Y606917D01*
X369617Y606417D01*
Y604000D01*
G01X375300D02*
Y607333D01*
G01Y606750D02*
X374967Y607083D01*
X374467Y607250D01*
X373883Y607333D01*
X373300Y607167D01*
X372800Y606833D01*
X372467Y606333D01*
X372300Y605667D01*
X372467Y605000D01*
X372800Y604500D01*
X373300Y604167D01*
X373883Y604000D01*
X374467Y604083D01*
X374967Y604333D01*
X375300Y604667D01*
G01X377983Y604000D02*
Y607333D01*
G01Y606500D02*
X378317Y606917D01*
X378817Y607250D01*
X379483Y607333D01*
X380067Y607250D01*
X380567Y606917D01*
X380817Y606333D01*
Y604000D01*
G01X383833Y602750D02*
X384417Y602417D01*
X385083Y602333D01*
X385667Y602417D01*
X386167Y602833D01*
X386500Y603417D01*
Y607333D01*
G01Y606667D02*
X386167Y607000D01*
X385667Y607250D01*
X385083Y607333D01*
X384417Y607167D01*
X384000Y606833D01*
X383667Y606250D01*
X383500Y605667D01*
X383583Y605167D01*
X383917Y604583D01*
X384417Y604167D01*
X385083Y604000D01*
X385583Y604083D01*
X386167Y604417D01*
X386500Y604750D01*
G01X389350Y606250D02*
X392017D01*
X391767Y606833D01*
X391350Y607167D01*
X390767Y607333D01*
X390183Y607250D01*
X389683Y607000D01*
X389350Y606417D01*
X389183Y605917D01*
Y605417D01*
X389350Y604917D01*
X389767Y604417D01*
X390267Y604083D01*
X390850Y604000D01*
X391433Y604167D01*
X392017Y604667D01*
G01X401800Y607333D02*
Y604000D01*
G01Y608667D02*
X401633Y608750D01*
Y608917D01*
X401800Y609000D01*
X401967Y608917D01*
Y608750D01*
X401800Y608667D01*
G01X405983Y604000D02*
Y607333D01*
G01Y606500D02*
X406317Y606917D01*
X406817Y607250D01*
X407483Y607333D01*
X408067Y607250D01*
X408567Y606917D01*
X408817Y606333D01*
Y604000D01*
G01X413000Y609000D02*
Y604000D01*
G01X411833Y607333D02*
X414167D01*
G01X418600Y604000D02*
X418100Y604083D01*
X417600Y604417D01*
X417267Y605000D01*
X417100Y605667D01*
X417267Y606333D01*
X417600Y606917D01*
X418100Y607250D01*
X418600Y607333D01*
X419100Y607250D01*
X419600Y606917D01*
X419933Y606333D01*
X420017Y605667D01*
X419933Y605000D01*
X419600Y604417D01*
X419100Y604083D01*
X418600Y604000D01*
G01X429300D02*
Y608250D01*
X429467Y608667D01*
X429800Y608917D01*
X430300Y609000D01*
X430800Y608833D01*
X431050Y608417D01*
G01X430050Y607000D02*
X428383D01*
G01X433983Y607333D02*
Y605000D01*
X434317Y604417D01*
X434817Y604083D01*
X435400Y604000D01*
X435983Y604083D01*
X436483Y604417D01*
X436817Y605000D01*
G01Y604000D02*
Y607333D01*
G01X441000Y604000D02*
Y609000D01*
G01X446600Y604000D02*
Y609000D01*
G01X459133Y606917D02*
X458550Y607250D01*
X458050Y607333D01*
X457383Y607167D01*
X456883Y606833D01*
X456550Y606250D01*
X456467Y605667D01*
X456550Y605083D01*
X456883Y604583D01*
X457383Y604167D01*
X458050Y604000D01*
X458633Y604167D01*
X459133Y604500D01*
G01X463400Y604000D02*
X462900Y604083D01*
X462400Y604417D01*
X462067Y605000D01*
X461900Y605667D01*
X462067Y606333D01*
X462400Y606917D01*
X462900Y607250D01*
X463400Y607333D01*
X463900Y607250D01*
X464400Y606917D01*
X464733Y606333D01*
X464817Y605667D01*
X464733Y605000D01*
X464400Y604417D01*
X463900Y604083D01*
X463400Y604000D01*
G01X467583D02*
Y607333D01*
G01Y606500D02*
X467917Y606917D01*
X468417Y607250D01*
X469083Y607333D01*
X469667Y607250D01*
X470167Y606917D01*
X470417Y606333D01*
Y604000D01*
G01X474600Y609000D02*
Y604000D01*
G01X473433Y607333D02*
X475767D01*
G01X481700Y604000D02*
Y607333D01*
G01Y606750D02*
X481367Y607083D01*
X480867Y607250D01*
X480283Y607333D01*
X479700Y607167D01*
X479200Y606833D01*
X478867Y606333D01*
X478700Y605667D01*
X478867Y605000D01*
X479200Y604500D01*
X479700Y604167D01*
X480283Y604000D01*
X480867Y604083D01*
X481367Y604333D01*
X481700Y604667D01*
G01X487133Y606917D02*
X486550Y607250D01*
X486050Y607333D01*
X485383Y607167D01*
X484883Y606833D01*
X484550Y606250D01*
X484467Y605667D01*
X484550Y605083D01*
X484883Y604583D01*
X485383Y604167D01*
X486050Y604000D01*
X486633Y604167D01*
X487133Y604500D01*
G01X491400Y609000D02*
Y604000D01*
G01X490233Y607333D02*
X492567D01*
G01X270417Y588500D02*
X272500Y593500D01*
X274583Y588500D01*
G01X273833Y590250D02*
X271167D01*
G01X276683Y588500D02*
Y591833D01*
G01Y591000D02*
X277017Y591417D01*
X277517Y591750D01*
X278183Y591833D01*
X278767Y591750D01*
X279267Y591417D01*
X279517Y590833D01*
Y588500D01*
G01X281950Y587000D02*
X282450Y586833D01*
X283117Y587000D01*
X283533Y587333D01*
X283867Y587750D01*
X284367Y589083D01*
X285450Y591833D01*
G01X282783D02*
X284367Y589083D01*
G01X293483Y588500D02*
Y593500D01*
G01Y591083D02*
X293900Y591500D01*
X294317Y591750D01*
X294983Y591833D01*
X295483Y591750D01*
X296067Y591417D01*
X296317Y590917D01*
Y588500D01*
G01X300500D02*
X300000Y588583D01*
X299500Y588917D01*
X299167Y589500D01*
X299000Y590167D01*
X299167Y590833D01*
X299500Y591417D01*
X300000Y591750D01*
X300500Y591833D01*
X301000Y591750D01*
X301500Y591417D01*
X301833Y590833D01*
X301917Y590167D01*
X301833Y589500D01*
X301500Y588917D01*
X301000Y588583D01*
X300500Y588500D01*
G01X306100D02*
Y593500D01*
G01X310450Y590750D02*
X313117D01*
X312867Y591333D01*
X312450Y591667D01*
X311867Y591833D01*
X311283Y591750D01*
X310783Y591500D01*
X310450Y590917D01*
X310283Y590417D01*
Y589917D01*
X310450Y589417D01*
X310867Y588917D01*
X311367Y588583D01*
X311950Y588500D01*
X312533Y588667D01*
X313117Y589167D01*
G01X322900Y593500D02*
Y588500D01*
G01X321733Y591833D02*
X324067D01*
G01X328500Y588500D02*
X328000Y588583D01*
X327500Y588917D01*
X327167Y589500D01*
X327000Y590167D01*
X327167Y590833D01*
X327500Y591417D01*
X328000Y591750D01*
X328500Y591833D01*
X329000Y591750D01*
X329500Y591417D01*
X329833Y590833D01*
X329917Y590167D01*
X329833Y589500D01*
X329500Y588917D01*
X329000Y588583D01*
X328500Y588500D01*
G01X338283D02*
Y593500D01*
G01Y591083D02*
X338700Y591500D01*
X339117Y591750D01*
X339783Y591833D01*
X340283Y591750D01*
X340867Y591417D01*
X341117Y590917D01*
Y588500D01*
G01X345300D02*
X344800Y588583D01*
X344300Y588917D01*
X343967Y589500D01*
X343800Y590167D01*
X343967Y590833D01*
X344300Y591417D01*
X344800Y591750D01*
X345300Y591833D01*
X345800Y591750D01*
X346300Y591417D01*
X346633Y590833D01*
X346717Y590167D01*
X346633Y589500D01*
X346300Y588917D01*
X345800Y588583D01*
X345300Y588500D01*
G01X350900D02*
Y593500D01*
G01X355250Y590750D02*
X357917D01*
X357667Y591333D01*
X357250Y591667D01*
X356667Y591833D01*
X356083Y591750D01*
X355583Y591500D01*
X355250Y590917D01*
X355083Y590417D01*
Y589917D01*
X355250Y589417D01*
X355667Y588917D01*
X356167Y588583D01*
X356750Y588500D01*
X357333Y588667D01*
X357917Y589167D01*
G01X270833Y575000D02*
Y580000D01*
X272833D01*
X273500Y579750D01*
X274000Y579167D01*
X274167Y578500D01*
X274000Y577833D01*
X273583Y577333D01*
X272833Y577083D01*
X270833D01*
G01X278100Y575000D02*
Y580000D01*
G01X282283Y578333D02*
Y576000D01*
X282617Y575417D01*
X283117Y575083D01*
X283700Y575000D01*
X284283Y575083D01*
X284783Y575417D01*
X285117Y576000D01*
G01Y575000D02*
Y578333D01*
G01X288133Y573750D02*
X288717Y573417D01*
X289383Y573333D01*
X289967Y573417D01*
X290467Y573833D01*
X290800Y574417D01*
Y578333D01*
G01Y577667D02*
X290467Y578000D01*
X289967Y578250D01*
X289383Y578333D01*
X288717Y578167D01*
X288300Y577833D01*
X287967Y577250D01*
X287800Y576667D01*
X287883Y576167D01*
X288217Y575583D01*
X288717Y575167D01*
X289383Y575000D01*
X289883Y575083D01*
X290467Y575417D01*
X290800Y575750D01*
G01X293733Y573750D02*
X294317Y573417D01*
X294983Y573333D01*
X295567Y573417D01*
X296067Y573833D01*
X296400Y574417D01*
Y578333D01*
G01Y577667D02*
X296067Y578000D01*
X295567Y578250D01*
X294983Y578333D01*
X294317Y578167D01*
X293900Y577833D01*
X293567Y577250D01*
X293400Y576667D01*
X293483Y576167D01*
X293817Y575583D01*
X294317Y575167D01*
X294983Y575000D01*
X295483Y575083D01*
X296067Y575417D01*
X296400Y575750D01*
G01X299250Y577250D02*
X301917D01*
X301667Y577833D01*
X301250Y578167D01*
X300667Y578333D01*
X300083Y578250D01*
X299583Y578000D01*
X299250Y577417D01*
X299083Y576917D01*
Y576417D01*
X299250Y575917D01*
X299667Y575417D01*
X300167Y575083D01*
X300750Y575000D01*
X301333Y575167D01*
X301917Y575667D01*
G01X307600Y580000D02*
Y575000D01*
G01Y575750D02*
X307267Y575333D01*
X306767Y575083D01*
X306183Y575000D01*
X305517Y575167D01*
X305017Y575583D01*
X304683Y576083D01*
X304600Y576667D01*
X304683Y577250D01*
X305017Y577750D01*
X305517Y578167D01*
X306183Y578333D01*
X306767Y578250D01*
X307183Y578083D01*
X307600Y577750D01*
G01X315217Y580000D02*
X317300Y575000D01*
X319383Y580000D01*
G01X322900Y578333D02*
Y575000D01*
G01Y579667D02*
X322733Y579750D01*
Y579917D01*
X322900Y580000D01*
X323067Y579917D01*
Y579750D01*
X322900Y579667D01*
G01X330000Y575000D02*
Y578333D01*
G01Y577750D02*
X329667Y578083D01*
X329167Y578250D01*
X328583Y578333D01*
X328000Y578167D01*
X327500Y577833D01*
X327167Y577333D01*
X327000Y576667D01*
X327167Y576000D01*
X327500Y575500D01*
X328000Y575167D01*
X328583Y575000D01*
X329167Y575083D01*
X329667Y575333D01*
X330000Y575667D01*
G01X333683Y573333D02*
X332850Y574167D01*
X332433Y575000D01*
Y578333D01*
X332850Y579167D01*
X333683Y580000D01*
G01X338283Y575000D02*
Y580000D01*
G01Y577583D02*
X338700Y578000D01*
X339117Y578250D01*
X339783Y578333D01*
X340283Y578250D01*
X340867Y577917D01*
X341117Y577417D01*
Y575000D01*
G01X345300D02*
X344800Y575083D01*
X344300Y575417D01*
X343967Y576000D01*
X343800Y576667D01*
X343967Y577333D01*
X344300Y577917D01*
X344800Y578250D01*
X345300Y578333D01*
X345800Y578250D01*
X346300Y577917D01*
X346633Y577333D01*
X346717Y576667D01*
X346633Y576000D01*
X346300Y575417D01*
X345800Y575083D01*
X345300Y575000D01*
G01X350900D02*
Y580000D01*
G01X355250Y577250D02*
X357917D01*
X357667Y577833D01*
X357250Y578167D01*
X356667Y578333D01*
X356083Y578250D01*
X355583Y578000D01*
X355250Y577417D01*
X355083Y576917D01*
Y576417D01*
X355250Y575917D01*
X355667Y575417D01*
X356167Y575083D01*
X356750Y575000D01*
X357333Y575167D01*
X357917Y575667D01*
G01X366450Y575583D02*
X366867Y575250D01*
X367450Y575000D01*
X367950D01*
X368450Y575167D01*
X368783Y575417D01*
X368950Y575750D01*
X368867Y576250D01*
X368533Y576500D01*
X367033Y577000D01*
X366700Y577583D01*
X366867Y578000D01*
X367200Y578250D01*
X367700Y578333D01*
X368200Y578250D01*
X368700Y578000D01*
G01X373300Y578333D02*
Y575000D01*
G01Y579667D02*
X373133Y579750D01*
Y579917D01*
X373300Y580000D01*
X373467Y579917D01*
Y579750D01*
X373300Y579667D01*
G01X377650Y578333D02*
X380150D01*
X377650Y575000D01*
X380150D01*
G01X383250Y577250D02*
X385917D01*
X385667Y577833D01*
X385250Y578167D01*
X384667Y578333D01*
X384083Y578250D01*
X383583Y578000D01*
X383250Y577417D01*
X383083Y576917D01*
Y576417D01*
X383250Y575917D01*
X383667Y575417D01*
X384167Y575083D01*
X384750Y575000D01*
X385333Y575167D01*
X385917Y575667D01*
G01X391767Y575000D02*
X388433Y576667D01*
X391767Y578333D01*
G01X395700Y575000D02*
Y580000D01*
X394700Y579000D01*
G01Y575000D02*
X396700D01*
G01X399717Y577083D02*
X400300Y577667D01*
X400800Y578000D01*
X401467Y578167D01*
X402050Y578000D01*
X402467Y577667D01*
X402800Y577167D01*
X402883Y576583D01*
X402800Y576083D01*
X402467Y575583D01*
X401967Y575167D01*
X401383Y575000D01*
X400717Y575167D01*
X400133Y575667D01*
X399800Y576417D01*
X399717Y577250D01*
X399883Y578333D01*
X400133Y578917D01*
X400550Y579500D01*
X401133Y579917D01*
X401717Y580000D01*
X402300Y579833D01*
X402717Y579417D01*
G01X410000Y575000D02*
Y578333D01*
G01Y577417D02*
X410250Y577833D01*
X410667Y578167D01*
X411250Y578333D01*
X411833Y578167D01*
X412250Y577833D01*
X412500Y577417D01*
Y575000D01*
G01Y577417D02*
X412750Y577833D01*
X413167Y578167D01*
X413750Y578333D01*
X414333Y578167D01*
X414750Y577833D01*
X415000Y577333D01*
Y575000D01*
G01X418100Y578333D02*
Y575000D01*
G01Y579667D02*
X417933Y579750D01*
Y579917D01*
X418100Y580000D01*
X418267Y579917D01*
Y579750D01*
X418100Y579667D01*
G01X423700Y575000D02*
Y580000D01*
G01X429717Y573333D02*
X430550Y574167D01*
X430967Y575000D01*
Y578333D01*
X430550Y579167D01*
X429717Y580000D01*
G01X270833Y560000D02*
Y565000D01*
X272833D01*
X273500Y564750D01*
X274000Y564167D01*
X274167Y563500D01*
X274000Y562833D01*
X273583Y562333D01*
X272833Y562083D01*
X270833D01*
G01X278100Y560000D02*
Y565000D01*
G01X282283Y563333D02*
Y561000D01*
X282617Y560417D01*
X283117Y560083D01*
X283700Y560000D01*
X284283Y560083D01*
X284783Y560417D01*
X285117Y561000D01*
G01Y560000D02*
Y563333D01*
G01X288133Y558750D02*
X288717Y558417D01*
X289383Y558333D01*
X289967Y558417D01*
X290467Y558833D01*
X290800Y559417D01*
Y563333D01*
G01Y562667D02*
X290467Y563000D01*
X289967Y563250D01*
X289383Y563333D01*
X288717Y563167D01*
X288300Y562833D01*
X287967Y562250D01*
X287800Y561667D01*
X287883Y561167D01*
X288217Y560583D01*
X288717Y560167D01*
X289383Y560000D01*
X289883Y560083D01*
X290467Y560417D01*
X290800Y560750D01*
G01X293733Y558750D02*
X294317Y558417D01*
X294983Y558333D01*
X295567Y558417D01*
X296067Y558833D01*
X296400Y559417D01*
Y563333D01*
G01Y562667D02*
X296067Y563000D01*
X295567Y563250D01*
X294983Y563333D01*
X294317Y563167D01*
X293900Y562833D01*
X293567Y562250D01*
X293400Y561667D01*
X293483Y561167D01*
X293817Y560583D01*
X294317Y560167D01*
X294983Y560000D01*
X295483Y560083D01*
X296067Y560417D01*
X296400Y560750D01*
G01X299250Y562250D02*
X301917D01*
X301667Y562833D01*
X301250Y563167D01*
X300667Y563333D01*
X300083Y563250D01*
X299583Y563000D01*
X299250Y562417D01*
X299083Y561917D01*
Y561417D01*
X299250Y560917D01*
X299667Y560417D01*
X300167Y560083D01*
X300750Y560000D01*
X301333Y560167D01*
X301917Y560667D01*
G01X307600Y565000D02*
Y560000D01*
G01Y560750D02*
X307267Y560333D01*
X306767Y560083D01*
X306183Y560000D01*
X305517Y560167D01*
X305017Y560583D01*
X304683Y561083D01*
X304600Y561667D01*
X304683Y562250D01*
X305017Y562750D01*
X305517Y563167D01*
X306183Y563333D01*
X306767Y563250D01*
X307183Y563083D01*
X307600Y562750D01*
G01X315633Y560000D02*
Y565000D01*
X317633D01*
X318300Y564750D01*
X318800Y564167D01*
X318967Y563500D01*
X318800Y562833D01*
X318383Y562333D01*
X317633Y562083D01*
X315633D01*
G01X322900Y565000D02*
Y560000D01*
G01X320983Y565000D02*
X324817D01*
G01X326750Y560000D02*
Y565000D01*
G01X330250D02*
Y560000D01*
G01Y562500D02*
X326750D01*
G01X333683Y558333D02*
X332850Y559167D01*
X332433Y560000D01*
Y563333D01*
X332850Y564167D01*
X333683Y565000D01*
G01X338283Y560000D02*
Y565000D01*
G01Y562583D02*
X338700Y563000D01*
X339117Y563250D01*
X339783Y563333D01*
X340283Y563250D01*
X340867Y562917D01*
X341117Y562417D01*
Y560000D01*
G01X345300D02*
X344800Y560083D01*
X344300Y560417D01*
X343967Y561000D01*
X343800Y561667D01*
X343967Y562333D01*
X344300Y562917D01*
X344800Y563250D01*
X345300Y563333D01*
X345800Y563250D01*
X346300Y562917D01*
X346633Y562333D01*
X346717Y561667D01*
X346633Y561000D01*
X346300Y560417D01*
X345800Y560083D01*
X345300Y560000D01*
G01X350900D02*
Y565000D01*
G01X355250Y562250D02*
X357917D01*
X357667Y562833D01*
X357250Y563167D01*
X356667Y563333D01*
X356083Y563250D01*
X355583Y563000D01*
X355250Y562417D01*
X355083Y561917D01*
Y561417D01*
X355250Y560917D01*
X355667Y560417D01*
X356167Y560083D01*
X356750Y560000D01*
X357333Y560167D01*
X357917Y560667D01*
G01X366450Y560583D02*
X366867Y560250D01*
X367450Y560000D01*
X367950D01*
X368450Y560167D01*
X368783Y560417D01*
X368950Y560750D01*
X368867Y561250D01*
X368533Y561500D01*
X367033Y562000D01*
X366700Y562583D01*
X366867Y563000D01*
X367200Y563250D01*
X367700Y563333D01*
X368200Y563250D01*
X368700Y563000D01*
G01X373300Y563333D02*
Y560000D01*
G01Y564667D02*
X373133Y564750D01*
Y564917D01*
X373300Y565000D01*
X373467Y564917D01*
Y564750D01*
X373300Y564667D01*
G01X377650Y563333D02*
X380150D01*
X377650Y560000D01*
X380150D01*
G01X383250Y562250D02*
X385917D01*
X385667Y562833D01*
X385250Y563167D01*
X384667Y563333D01*
X384083Y563250D01*
X383583Y563000D01*
X383250Y562417D01*
X383083Y561917D01*
Y561417D01*
X383250Y560917D01*
X383667Y560417D01*
X384167Y560083D01*
X384750Y560000D01*
X385333Y560167D01*
X385917Y560667D01*
G01X388433Y560000D02*
X391767Y561667D01*
X388433Y563333D01*
G01X394617Y560917D02*
X396783D01*
G01Y562417D02*
X394617D01*
G01X401300Y560000D02*
Y565000D01*
X400300Y564000D01*
G01Y560000D02*
X402300D01*
G01X405317Y562083D02*
X405900Y562667D01*
X406400Y563000D01*
X407067Y563167D01*
X407650Y563000D01*
X408067Y562667D01*
X408400Y562167D01*
X408483Y561583D01*
X408400Y561083D01*
X408067Y560583D01*
X407567Y560167D01*
X406983Y560000D01*
X406317Y560167D01*
X405733Y560667D01*
X405400Y561417D01*
X405317Y562250D01*
X405483Y563333D01*
X405733Y563917D01*
X406150Y564500D01*
X406733Y564917D01*
X407317Y565000D01*
X407900Y564833D01*
X408317Y564417D01*
G01X415600Y560000D02*
Y563333D01*
G01Y562417D02*
X415850Y562833D01*
X416267Y563167D01*
X416850Y563333D01*
X417433Y563167D01*
X417850Y562833D01*
X418100Y562417D01*
Y560000D01*
G01Y562417D02*
X418350Y562833D01*
X418767Y563167D01*
X419350Y563333D01*
X419933Y563167D01*
X420350Y562833D01*
X420600Y562333D01*
Y560000D01*
G01X423700Y563333D02*
Y560000D01*
G01Y564667D02*
X423533Y564750D01*
Y564917D01*
X423700Y565000D01*
X423867Y564917D01*
Y564750D01*
X423700Y564667D01*
G01X429300Y560000D02*
Y565000D01*
G01X435317Y558333D02*
X436150Y559167D01*
X436567Y560000D01*
Y563333D01*
X436150Y564167D01*
X435317Y565000D01*
G01X270917Y619000D02*
X273000Y624000D01*
X275083Y619000D01*
G01X274333Y620750D02*
X271667D01*
G01X277183Y619000D02*
Y622333D01*
G01Y621500D02*
X277517Y621917D01*
X278017Y622250D01*
X278683Y622333D01*
X279267Y622250D01*
X279767Y621917D01*
X280017Y621333D01*
Y619000D01*
G01X284200Y624000D02*
Y619000D01*
G01X283033Y622333D02*
X285367D01*
G01X289800D02*
Y619000D01*
G01Y623667D02*
X289633Y623750D01*
Y623917D01*
X289800Y624000D01*
X289967Y623917D01*
Y623750D01*
X289800Y623667D01*
G01X294317Y620667D02*
X296483D01*
G01X299500Y617333D02*
Y622333D01*
G01Y621583D02*
X299917Y622000D01*
X300333Y622250D01*
X301000Y622333D01*
X301583Y622250D01*
X302167Y621833D01*
X302417Y621250D01*
X302500Y620667D01*
X302417Y620083D01*
X302167Y619500D01*
X301667Y619167D01*
X301000Y619000D01*
X300417Y619083D01*
X299833Y619333D01*
X299500Y619667D01*
G01X308100Y619000D02*
Y622333D01*
G01Y621750D02*
X307767Y622083D01*
X307267Y622250D01*
X306683Y622333D01*
X306100Y622167D01*
X305600Y621833D01*
X305267Y621333D01*
X305100Y620667D01*
X305267Y620000D01*
X305600Y619500D01*
X306100Y619167D01*
X306683Y619000D01*
X307267Y619083D01*
X307767Y619333D01*
X308100Y619667D01*
G01X313700Y624000D02*
Y619000D01*
G01Y619750D02*
X313367Y619333D01*
X312867Y619083D01*
X312283Y619000D01*
X311617Y619167D01*
X311117Y619583D01*
X310783Y620083D01*
X310700Y620667D01*
X310783Y621250D01*
X311117Y621750D01*
X311617Y622167D01*
X312283Y622333D01*
X312867Y622250D01*
X313283Y622083D01*
X313700Y621750D01*
G01X322150Y619583D02*
X322567Y619250D01*
X323150Y619000D01*
X323650D01*
X324150Y619167D01*
X324483Y619417D01*
X324650Y619750D01*
X324567Y620250D01*
X324233Y620500D01*
X322733Y621000D01*
X322400Y621583D01*
X322567Y622000D01*
X322900Y622250D01*
X323400Y622333D01*
X323900Y622250D01*
X324400Y622000D01*
G01X329000Y622333D02*
Y619000D01*
G01Y623667D02*
X328833Y623750D01*
Y623917D01*
X329000Y624000D01*
X329167Y623917D01*
Y623750D01*
X329000Y623667D01*
G01X333350Y622333D02*
X335850D01*
X333350Y619000D01*
X335850D01*
G01X338950Y621250D02*
X341617D01*
X341367Y621833D01*
X340950Y622167D01*
X340367Y622333D01*
X339783Y622250D01*
X339283Y622000D01*
X338950Y621417D01*
X338783Y620917D01*
Y620417D01*
X338950Y619917D01*
X339367Y619417D01*
X339867Y619083D01*
X340450Y619000D01*
X341033Y619167D01*
X341617Y619667D01*
G01X269717Y637573D02*
X270717Y634240D01*
X271800Y637573D01*
X272883Y634240D01*
X273883Y637573D01*
G01X277400D02*
Y634240D01*
G01Y638907D02*
X277233Y638990D01*
Y639157D01*
X277400Y639240D01*
X277567Y639157D01*
Y638990D01*
X277400Y638907D01*
G01X283000Y639240D02*
Y634240D01*
G01X281833Y637573D02*
X284167D01*
G01X287183Y634240D02*
Y639240D01*
G01Y636823D02*
X287600Y637240D01*
X288017Y637490D01*
X288683Y637573D01*
X289183Y637490D01*
X289767Y637157D01*
X290017Y636657D01*
Y634240D01*
G01X294200D02*
X293700Y634323D01*
X293200Y634657D01*
X292867Y635240D01*
X292700Y635907D01*
X292867Y636573D01*
X293200Y637157D01*
X293700Y637490D01*
X294200Y637573D01*
X294700Y637490D01*
X295200Y637157D01*
X295533Y636573D01*
X295617Y635907D01*
X295533Y635240D01*
X295200Y634657D01*
X294700Y634323D01*
X294200Y634240D01*
G01X298383Y637573D02*
Y635240D01*
X298717Y634657D01*
X299217Y634323D01*
X299800Y634240D01*
X300383Y634323D01*
X300883Y634657D01*
X301217Y635240D01*
G01Y634240D02*
Y637573D01*
G01X305400Y639240D02*
Y634240D01*
G01X304233Y637573D02*
X306567D01*
G01X317933Y637157D02*
X317350Y637490D01*
X316850Y637573D01*
X316183Y637407D01*
X315683Y637073D01*
X315350Y636490D01*
X315267Y635907D01*
X315350Y635323D01*
X315683Y634823D01*
X316183Y634407D01*
X316850Y634240D01*
X317433Y634407D01*
X317933Y634740D01*
G01X322200Y634240D02*
X321700Y634323D01*
X321200Y634657D01*
X320867Y635240D01*
X320700Y635907D01*
X320867Y636573D01*
X321200Y637157D01*
X321700Y637490D01*
X322200Y637573D01*
X322700Y637490D01*
X323200Y637157D01*
X323533Y636573D01*
X323617Y635907D01*
X323533Y635240D01*
X323200Y634657D01*
X322700Y634323D01*
X322200Y634240D01*
G01X326383D02*
Y637573D01*
G01Y636740D02*
X326717Y637157D01*
X327217Y637490D01*
X327883Y637573D01*
X328467Y637490D01*
X328967Y637157D01*
X329217Y636573D01*
Y634240D01*
G01X331983D02*
Y637573D01*
G01Y636740D02*
X332317Y637157D01*
X332817Y637490D01*
X333483Y637573D01*
X334067Y637490D01*
X334567Y637157D01*
X334817Y636573D01*
Y634240D01*
G01X337750Y636490D02*
X340417D01*
X340167Y637073D01*
X339750Y637407D01*
X339167Y637573D01*
X338583Y637490D01*
X338083Y637240D01*
X337750Y636657D01*
X337583Y636157D01*
Y635657D01*
X337750Y635157D01*
X338167Y634657D01*
X338667Y634323D01*
X339250Y634240D01*
X339833Y634407D01*
X340417Y634907D01*
G01X345933Y637157D02*
X345350Y637490D01*
X344850Y637573D01*
X344183Y637407D01*
X343683Y637073D01*
X343350Y636490D01*
X343267Y635907D01*
X343350Y635323D01*
X343683Y634823D01*
X344183Y634407D01*
X344850Y634240D01*
X345433Y634407D01*
X345933Y634740D01*
G01X350200Y639240D02*
Y634240D01*
G01X349033Y637573D02*
X351367D01*
G01X355800D02*
Y634240D01*
G01Y638907D02*
X355633Y638990D01*
Y639157D01*
X355800Y639240D01*
X355967Y639157D01*
Y638990D01*
X355800Y638907D01*
G01X359983Y634240D02*
Y637573D01*
G01Y636740D02*
X360317Y637157D01*
X360817Y637490D01*
X361483Y637573D01*
X362067Y637490D01*
X362567Y637157D01*
X362817Y636573D01*
Y634240D01*
G01X365833Y632990D02*
X366417Y632657D01*
X367083Y632573D01*
X367667Y632657D01*
X368167Y633073D01*
X368500Y633657D01*
Y637573D01*
G01Y636907D02*
X368167Y637240D01*
X367667Y637490D01*
X367083Y637573D01*
X366417Y637407D01*
X366000Y637073D01*
X365667Y636490D01*
X365500Y635907D01*
X365583Y635407D01*
X365917Y634823D01*
X366417Y634407D01*
X367083Y634240D01*
X367583Y634323D01*
X368167Y634657D01*
X368500Y634990D01*
G01X378200Y639240D02*
Y634240D01*
G01X377033Y637573D02*
X379367D01*
G01X383800Y634240D02*
X383300Y634323D01*
X382800Y634657D01*
X382467Y635240D01*
X382300Y635907D01*
X382467Y636573D01*
X382800Y637157D01*
X383300Y637490D01*
X383800Y637573D01*
X384300Y637490D01*
X384800Y637157D01*
X385133Y636573D01*
X385217Y635907D01*
X385133Y635240D01*
X384800Y634657D01*
X384300Y634323D01*
X383800Y634240D01*
G01X395000D02*
X394500Y634323D01*
X394000Y634657D01*
X393667Y635240D01*
X393500Y635907D01*
X393667Y636573D01*
X394000Y637157D01*
X394500Y637490D01*
X395000Y637573D01*
X395500Y637490D01*
X396000Y637157D01*
X396333Y636573D01*
X396417Y635907D01*
X396333Y635240D01*
X396000Y634657D01*
X395500Y634323D01*
X395000Y634240D01*
G01X400600Y639240D02*
Y634240D01*
G01X399433Y637573D02*
X401767D01*
G01X404783Y634240D02*
Y639240D01*
G01Y636823D02*
X405200Y637240D01*
X405617Y637490D01*
X406283Y637573D01*
X406783Y637490D01*
X407367Y637157D01*
X407617Y636657D01*
Y634240D01*
G01X410550Y636490D02*
X413217D01*
X412967Y637073D01*
X412550Y637407D01*
X411967Y637573D01*
X411383Y637490D01*
X410883Y637240D01*
X410550Y636657D01*
X410383Y636157D01*
Y635657D01*
X410550Y635157D01*
X410967Y634657D01*
X411467Y634323D01*
X412050Y634240D01*
X412633Y634407D01*
X413217Y634907D01*
G01X416233Y634240D02*
Y637573D01*
G01Y636907D02*
X416650Y637240D01*
X417067Y637490D01*
X417650Y637573D01*
X418067Y637490D01*
X418567Y637240D01*
G01X428600Y634240D02*
Y639240D01*
G01X435700Y634240D02*
Y637573D01*
G01Y636990D02*
X435367Y637323D01*
X434867Y637490D01*
X434283Y637573D01*
X433700Y637407D01*
X433200Y637073D01*
X432867Y636573D01*
X432700Y635907D01*
X432867Y635240D01*
X433200Y634740D01*
X433700Y634407D01*
X434283Y634240D01*
X434867Y634323D01*
X435367Y634573D01*
X435700Y634907D01*
G01X438050Y632740D02*
X438550Y632573D01*
X439217Y632740D01*
X439633Y633073D01*
X439967Y633490D01*
X440467Y634823D01*
X441550Y637573D01*
G01X438883D02*
X440467Y634823D01*
G01X444150Y636490D02*
X446817D01*
X446567Y637073D01*
X446150Y637407D01*
X445567Y637573D01*
X444983Y637490D01*
X444483Y637240D01*
X444150Y636657D01*
X443983Y636157D01*
Y635657D01*
X444150Y635157D01*
X444567Y634657D01*
X445067Y634323D01*
X445650Y634240D01*
X446233Y634407D01*
X446817Y634907D01*
G01X449833Y634240D02*
Y637573D01*
G01Y636907D02*
X450250Y637240D01*
X450667Y637490D01*
X451250Y637573D01*
X451667Y637490D01*
X452167Y637240D01*
G01X455350Y634823D02*
X455767Y634490D01*
X456350Y634240D01*
X456850D01*
X457350Y634407D01*
X457683Y634657D01*
X457850Y634990D01*
X457767Y635490D01*
X457433Y635740D01*
X455933Y636240D01*
X455600Y636823D01*
X455767Y637240D01*
X456100Y637490D01*
X456600Y637573D01*
X457100Y637490D01*
X457600Y637240D01*
G01X462617Y632573D02*
X463450Y633407D01*
X463867Y634240D01*
Y637573D01*
X463450Y638407D01*
X462617Y639240D01*
G01X270257Y644950D02*
Y649950D01*
X271923D01*
X272590Y649700D01*
X273090Y649367D01*
X273507Y648867D01*
X273840Y648283D01*
X273923Y647450D01*
X273840Y646617D01*
X273507Y646033D01*
X273090Y645533D01*
X272590Y645200D01*
X271923Y644950D01*
X270257D01*
G01X276440Y647200D02*
X279107D01*
X278857Y647783D01*
X278440Y648117D01*
X277857Y648283D01*
X277273Y648200D01*
X276773Y647950D01*
X276440Y647367D01*
X276273Y646867D01*
Y646367D01*
X276440Y645867D01*
X276857Y645367D01*
X277357Y645033D01*
X277940Y644950D01*
X278523Y645117D01*
X279107Y645617D01*
G01X283290Y644950D02*
Y649950D01*
G01X287640Y647200D02*
X290307D01*
X290057Y647783D01*
X289640Y648117D01*
X289057Y648283D01*
X288473Y648200D01*
X287973Y647950D01*
X287640Y647367D01*
X287473Y646867D01*
Y646367D01*
X287640Y645867D01*
X288057Y645367D01*
X288557Y645033D01*
X289140Y644950D01*
X289723Y645117D01*
X290307Y645617D01*
G01X294490Y649950D02*
Y644950D01*
G01X293323Y648283D02*
X295657D01*
G01X298840Y647200D02*
X301507D01*
X301257Y647783D01*
X300840Y648117D01*
X300257Y648283D01*
X299673Y648200D01*
X299173Y647950D01*
X298840Y647367D01*
X298673Y646867D01*
Y646367D01*
X298840Y645867D01*
X299257Y645367D01*
X299757Y645033D01*
X300340Y644950D01*
X300923Y645117D01*
X301507Y645617D01*
G01X309873Y644950D02*
Y648283D01*
G01Y647450D02*
X310207Y647867D01*
X310707Y648200D01*
X311373Y648283D01*
X311957Y648200D01*
X312457Y647867D01*
X312707Y647283D01*
Y644950D01*
G01X316890D02*
X316390Y645033D01*
X315890Y645367D01*
X315557Y645950D01*
X315390Y646617D01*
X315557Y647283D01*
X315890Y647867D01*
X316390Y648200D01*
X316890Y648283D01*
X317390Y648200D01*
X317890Y647867D01*
X318223Y647283D01*
X318307Y646617D01*
X318223Y645950D01*
X317890Y645367D01*
X317390Y645033D01*
X316890Y644950D01*
G01X321073D02*
Y648283D01*
G01Y647450D02*
X321407Y647867D01*
X321907Y648200D01*
X322573Y648283D01*
X323157Y648200D01*
X323657Y647867D01*
X323907Y647283D01*
Y644950D01*
G01X327007Y646617D02*
X329173D01*
G01X333190Y644950D02*
Y649200D01*
X333357Y649617D01*
X333690Y649867D01*
X334190Y649950D01*
X334690Y649783D01*
X334940Y649367D01*
G01X333940Y647950D02*
X332273D01*
G01X337873Y648283D02*
Y645950D01*
X338207Y645367D01*
X338707Y645033D01*
X339290Y644950D01*
X339873Y645033D01*
X340373Y645367D01*
X340707Y645950D01*
G01Y644950D02*
Y648283D01*
G01X343473Y644950D02*
Y648283D01*
G01Y647450D02*
X343807Y647867D01*
X344307Y648200D01*
X344973Y648283D01*
X345557Y648200D01*
X346057Y647867D01*
X346307Y647283D01*
Y644950D01*
G01X351823Y647867D02*
X351240Y648200D01*
X350740Y648283D01*
X350073Y648117D01*
X349573Y647783D01*
X349240Y647200D01*
X349157Y646617D01*
X349240Y646033D01*
X349573Y645533D01*
X350073Y645117D01*
X350740Y644950D01*
X351323Y645117D01*
X351823Y645450D01*
G01X356090Y649950D02*
Y644950D01*
G01X354923Y648283D02*
X357257D01*
G01X361690D02*
Y644950D01*
G01Y649617D02*
X361523Y649700D01*
Y649867D01*
X361690Y649950D01*
X361857Y649867D01*
Y649700D01*
X361690Y649617D01*
G01X367290Y644950D02*
X366790Y645033D01*
X366290Y645367D01*
X365957Y645950D01*
X365790Y646617D01*
X365957Y647283D01*
X366290Y647867D01*
X366790Y648200D01*
X367290Y648283D01*
X367790Y648200D01*
X368290Y647867D01*
X368623Y647283D01*
X368707Y646617D01*
X368623Y645950D01*
X368290Y645367D01*
X367790Y645033D01*
X367290Y644950D01*
G01X371473D02*
Y648283D01*
G01Y647450D02*
X371807Y647867D01*
X372307Y648200D01*
X372973Y648283D01*
X373557Y648200D01*
X374057Y647867D01*
X374307Y647283D01*
Y644950D01*
G01X379990D02*
Y648283D01*
G01Y647700D02*
X379657Y648033D01*
X379157Y648200D01*
X378573Y648283D01*
X377990Y648117D01*
X377490Y647783D01*
X377157Y647283D01*
X376990Y646617D01*
X377157Y645950D01*
X377490Y645450D01*
X377990Y645117D01*
X378573Y644950D01*
X379157Y645033D01*
X379657Y645283D01*
X379990Y645617D01*
G01X384090Y644950D02*
Y649950D01*
G01X393790Y643283D02*
Y648283D01*
G01Y647533D02*
X394207Y647950D01*
X394623Y648200D01*
X395290Y648283D01*
X395873Y648200D01*
X396457Y647783D01*
X396707Y647200D01*
X396790Y646617D01*
X396707Y646033D01*
X396457Y645450D01*
X395957Y645117D01*
X395290Y644950D01*
X394707Y645033D01*
X394123Y645283D01*
X393790Y645617D01*
G01X402390Y644950D02*
Y648283D01*
G01Y647700D02*
X402057Y648033D01*
X401557Y648200D01*
X400973Y648283D01*
X400390Y648117D01*
X399890Y647783D01*
X399557Y647283D01*
X399390Y646617D01*
X399557Y645950D01*
X399890Y645450D01*
X400390Y645117D01*
X400973Y644950D01*
X401557Y645033D01*
X402057Y645283D01*
X402390Y645617D01*
G01X407990Y649950D02*
Y644950D01*
G01Y645700D02*
X407657Y645283D01*
X407157Y645033D01*
X406573Y644950D01*
X405907Y645117D01*
X405407Y645533D01*
X405073Y646033D01*
X404990Y646617D01*
X405073Y647200D01*
X405407Y647700D01*
X405907Y648117D01*
X406573Y648283D01*
X407157Y648200D01*
X407573Y648033D01*
X407990Y647700D01*
G01X417690Y648283D02*
Y644950D01*
G01Y649617D02*
X417523Y649700D01*
Y649867D01*
X417690Y649950D01*
X417857Y649867D01*
Y649700D01*
X417690Y649617D01*
G01X421873Y644950D02*
Y648283D01*
G01Y647450D02*
X422207Y647867D01*
X422707Y648200D01*
X423373Y648283D01*
X423957Y648200D01*
X424457Y647867D01*
X424707Y647283D01*
Y644950D01*
G01X435990D02*
Y648283D01*
G01Y647700D02*
X435657Y648033D01*
X435157Y648200D01*
X434573Y648283D01*
X433990Y648117D01*
X433490Y647783D01*
X433157Y647283D01*
X432990Y646617D01*
X433157Y645950D01*
X433490Y645450D01*
X433990Y645117D01*
X434573Y644950D01*
X435157Y645033D01*
X435657Y645283D01*
X435990Y645617D01*
G01X440090Y644950D02*
Y649950D01*
G01X445690Y644950D02*
Y649950D01*
G01X455390Y643283D02*
Y648283D01*
G01Y647533D02*
X455807Y647950D01*
X456223Y648200D01*
X456890Y648283D01*
X457473Y648200D01*
X458057Y647783D01*
X458307Y647200D01*
X458390Y646617D01*
X458307Y646033D01*
X458057Y645450D01*
X457557Y645117D01*
X456890Y644950D01*
X456307Y645033D01*
X455723Y645283D01*
X455390Y645617D01*
G01X461323Y644950D02*
Y648283D01*
G01Y647617D02*
X461740Y647950D01*
X462157Y648200D01*
X462740Y648283D01*
X463157Y648200D01*
X463657Y647950D01*
G01X468090Y644950D02*
X467590Y645033D01*
X467090Y645367D01*
X466757Y645950D01*
X466590Y646617D01*
X466757Y647283D01*
X467090Y647867D01*
X467590Y648200D01*
X468090Y648283D01*
X468590Y648200D01*
X469090Y647867D01*
X469423Y647283D01*
X469507Y646617D01*
X469423Y645950D01*
X469090Y645367D01*
X468590Y645033D01*
X468090Y644950D01*
G01X475190Y649950D02*
Y644950D01*
G01Y645700D02*
X474857Y645283D01*
X474357Y645033D01*
X473773Y644950D01*
X473107Y645117D01*
X472607Y645533D01*
X472273Y646033D01*
X472190Y646617D01*
X472273Y647200D01*
X472607Y647700D01*
X473107Y648117D01*
X473773Y648283D01*
X474357Y648200D01*
X474773Y648033D01*
X475190Y647700D01*
G01X477873Y648283D02*
Y645950D01*
X478207Y645367D01*
X478707Y645033D01*
X479290Y644950D01*
X479873Y645033D01*
X480373Y645367D01*
X480707Y645950D01*
G01Y644950D02*
Y648283D01*
G01X486223Y647867D02*
X485640Y648200D01*
X485140Y648283D01*
X484473Y648117D01*
X483973Y647783D01*
X483640Y647200D01*
X483557Y646617D01*
X483640Y646033D01*
X483973Y645533D01*
X484473Y645117D01*
X485140Y644950D01*
X485723Y645117D01*
X486223Y645450D01*
G01X490490Y649950D02*
Y644950D01*
G01X489323Y648283D02*
X491657D01*
G01X494840Y645533D02*
X495257Y645200D01*
X495840Y644950D01*
X496340D01*
X496840Y645117D01*
X497173Y645367D01*
X497340Y645700D01*
X497257Y646200D01*
X496923Y646450D01*
X495423Y646950D01*
X495090Y647533D01*
X495257Y647950D01*
X495590Y648200D01*
X496090Y648283D01*
X496590Y648200D01*
X497090Y647950D01*
G01X501690Y644783D02*
X501523Y644867D01*
Y645033D01*
X501690Y645117D01*
X501857Y645033D01*
Y644867D01*
X501690Y644783D01*
G01X506873Y643283D02*
X506040Y644117D01*
X505623Y644950D01*
Y648283D01*
X506040Y649117D01*
X506873Y649950D01*
G01X511890D02*
X513890D01*
G01X512890D02*
Y644950D01*
G01X511890D02*
X513890D01*
G01X517240Y645533D02*
X517657Y645200D01*
X518240Y644950D01*
X518740D01*
X519240Y645117D01*
X519573Y645367D01*
X519740Y645700D01*
X519657Y646200D01*
X519323Y646450D01*
X517823Y646950D01*
X517490Y647533D01*
X517657Y647950D01*
X517990Y648200D01*
X518490Y648283D01*
X518990Y648200D01*
X519490Y647950D01*
G01X524090Y644950D02*
X523590Y645033D01*
X523090Y645367D01*
X522757Y645950D01*
X522590Y646617D01*
X522757Y647283D01*
X523090Y647867D01*
X523590Y648200D01*
X524090Y648283D01*
X524590Y648200D01*
X525090Y647867D01*
X525423Y647283D01*
X525507Y646617D01*
X525423Y645950D01*
X525090Y645367D01*
X524590Y645033D01*
X524090Y644950D01*
G01X529690D02*
Y649950D01*
G01X536790Y644950D02*
Y648283D01*
G01Y647700D02*
X536457Y648033D01*
X535957Y648200D01*
X535373Y648283D01*
X534790Y648117D01*
X534290Y647783D01*
X533957Y647283D01*
X533790Y646617D01*
X533957Y645950D01*
X534290Y645450D01*
X534790Y645117D01*
X535373Y644950D01*
X535957Y645033D01*
X536457Y645283D01*
X536790Y645617D01*
G01X540890Y649950D02*
Y644950D01*
G01X539723Y648283D02*
X542057D01*
G01X545240Y647200D02*
X547907D01*
X547657Y647783D01*
X547240Y648117D01*
X546657Y648283D01*
X546073Y648200D01*
X545573Y647950D01*
X545240Y647367D01*
X545073Y646867D01*
Y646367D01*
X545240Y645867D01*
X545657Y645367D01*
X546157Y645033D01*
X546740Y644950D01*
X547323Y645117D01*
X547907Y645617D01*
G01X556190Y643283D02*
Y648283D01*
G01Y647533D02*
X556607Y647950D01*
X557023Y648200D01*
X557690Y648283D01*
X558273Y648200D01*
X558857Y647783D01*
X559107Y647200D01*
X559190Y646617D01*
X559107Y646033D01*
X558857Y645450D01*
X558357Y645117D01*
X557690Y644950D01*
X557107Y645033D01*
X556523Y645283D01*
X556190Y645617D01*
G01X564790Y644950D02*
Y648283D01*
G01Y647700D02*
X564457Y648033D01*
X563957Y648200D01*
X563373Y648283D01*
X562790Y648117D01*
X562290Y647783D01*
X561957Y647283D01*
X561790Y646617D01*
X561957Y645950D01*
X562290Y645450D01*
X562790Y645117D01*
X563373Y644950D01*
X563957Y645033D01*
X564457Y645283D01*
X564790Y645617D01*
G01X570390Y649950D02*
Y644950D01*
G01Y645700D02*
X570057Y645283D01*
X569557Y645033D01*
X568973Y644950D01*
X568307Y645117D01*
X567807Y645533D01*
X567473Y646033D01*
X567390Y646617D01*
X567473Y647200D01*
X567807Y647700D01*
X568307Y648117D01*
X568973Y648283D01*
X569557Y648200D01*
X569973Y648033D01*
X570390Y647700D01*
G01X361117Y328537D02*
X360717Y328737D01*
X360250Y328870D01*
X359717D01*
X359117Y328670D01*
X358650Y328337D01*
X358317Y327937D01*
X358050Y327270D01*
X357983Y326670D01*
X358117Y326070D01*
X358317Y325670D01*
X358717Y325270D01*
X359183Y325003D01*
X359650Y324870D01*
X360117D01*
X360583Y325003D01*
X360983Y325203D01*
X361317Y325470D01*
G01X402977Y229887D02*
X403310Y230137D01*
X403560Y230553D01*
X403727Y231137D01*
X403560Y231637D01*
X403227Y231970D01*
X402643Y232220D01*
X400393D01*
Y227220D01*
X403143D01*
X403727Y227553D01*
X404060Y228053D01*
X404227Y228637D01*
X404060Y229220D01*
X403560Y229720D01*
X402977Y229887D01*
X400393D01*
G01X406493Y230553D02*
Y228220D01*
X406827Y227637D01*
X407327Y227303D01*
X407910Y227220D01*
X408493Y227303D01*
X408993Y227637D01*
X409327Y228220D01*
G01Y227220D02*
Y230553D01*
G01X411010Y227220D02*
Y230553D01*
G01Y229637D02*
X411260Y230053D01*
X411677Y230387D01*
X412260Y230553D01*
X412843Y230387D01*
X413260Y230053D01*
X413510Y229637D01*
Y227220D01*
G01Y229637D02*
X413760Y230053D01*
X414177Y230387D01*
X414760Y230553D01*
X415343Y230387D01*
X415760Y230053D01*
X416010Y229553D01*
Y227220D01*
G01X417610Y225553D02*
Y230553D01*
G01Y229803D02*
X418027Y230220D01*
X418443Y230470D01*
X419110Y230553D01*
X419693Y230470D01*
X420277Y230053D01*
X420527Y229470D01*
X420610Y228887D01*
X420527Y228303D01*
X420277Y227720D01*
X419777Y227387D01*
X419110Y227220D01*
X418527Y227303D01*
X417943Y227553D01*
X417610Y227887D01*
G01X395000Y364500D02*
Y175500D01*
G01X401520Y268213D02*
X403020Y264880D01*
X404520Y268213D01*
G01X408620D02*
Y264880D01*
G01Y269547D02*
X408453Y269630D01*
Y269797D01*
X408620Y269880D01*
X408787Y269797D01*
Y269630D01*
X408620Y269547D01*
G01X415720Y264880D02*
Y268213D01*
G01Y267630D02*
X415387Y267963D01*
X414887Y268130D01*
X414303Y268213D01*
X413720Y268047D01*
X413220Y267713D01*
X412887Y267213D01*
X412720Y266547D01*
X412887Y265880D01*
X413220Y265380D01*
X413720Y265047D01*
X414303Y264880D01*
X414887Y264963D01*
X415387Y265213D01*
X415720Y265547D01*
G01X401067Y277360D02*
Y282360D01*
X402733D01*
X403400Y282110D01*
X403900Y281777D01*
X404317Y281277D01*
X404650Y280693D01*
X404733Y279860D01*
X404650Y279027D01*
X404317Y278443D01*
X403900Y277943D01*
X403400Y277610D01*
X402733Y277360D01*
X401067D01*
G01X408500Y280693D02*
Y277360D01*
G01Y282027D02*
X408333Y282110D01*
Y282277D01*
X408500Y282360D01*
X408667Y282277D01*
Y282110D01*
X408500Y282027D01*
G01X411600Y277360D02*
Y280693D01*
G01Y279777D02*
X411850Y280193D01*
X412267Y280527D01*
X412850Y280693D01*
X413433Y280527D01*
X413850Y280193D01*
X414100Y279777D01*
Y277360D01*
G01Y279777D02*
X414350Y280193D01*
X414767Y280527D01*
X415350Y280693D01*
X415933Y280527D01*
X416350Y280193D01*
X416600Y279693D01*
Y277360D01*
G01X418200Y275693D02*
Y280693D01*
G01Y279943D02*
X418617Y280360D01*
X419033Y280610D01*
X419700Y280693D01*
X420283Y280610D01*
X420867Y280193D01*
X421117Y279610D01*
X421200Y279027D01*
X421117Y278443D01*
X420867Y277860D01*
X420367Y277527D01*
X419700Y277360D01*
X419117Y277443D01*
X418533Y277693D01*
X418200Y278027D01*
G01X425300Y277360D02*
Y282360D01*
G01X429650Y279610D02*
X432317D01*
X432067Y280193D01*
X431650Y280527D01*
X431067Y280693D01*
X430483Y280610D01*
X429983Y280360D01*
X429650Y279777D01*
X429483Y279277D01*
Y278777D01*
X429650Y278277D01*
X430067Y277777D01*
X430567Y277443D01*
X431150Y277360D01*
X431733Y277527D01*
X432317Y278027D01*
G01X441600Y277360D02*
Y281610D01*
X441767Y282027D01*
X442100Y282277D01*
X442600Y282360D01*
X443100Y282193D01*
X443350Y281777D01*
G01X442350Y280360D02*
X440683D01*
G01X447700Y277360D02*
X447200Y277443D01*
X446700Y277777D01*
X446367Y278360D01*
X446200Y279027D01*
X446367Y279693D01*
X446700Y280277D01*
X447200Y280610D01*
X447700Y280693D01*
X448200Y280610D01*
X448700Y280277D01*
X449033Y279693D01*
X449117Y279027D01*
X449033Y278360D01*
X448700Y277777D01*
X448200Y277443D01*
X447700Y277360D01*
G01X452133D02*
Y280693D01*
G01Y280027D02*
X452550Y280360D01*
X452967Y280610D01*
X453550Y280693D01*
X453967Y280610D01*
X454467Y280360D01*
G01X464500Y277360D02*
X464000Y277443D01*
X463500Y277777D01*
X463167Y278360D01*
X463000Y279027D01*
X463167Y279693D01*
X463500Y280277D01*
X464000Y280610D01*
X464500Y280693D01*
X465000Y280610D01*
X465500Y280277D01*
X465833Y279693D01*
X465917Y279027D01*
X465833Y278360D01*
X465500Y277777D01*
X465000Y277443D01*
X464500Y277360D01*
G01X468683Y280693D02*
Y278360D01*
X469017Y277777D01*
X469517Y277443D01*
X470100Y277360D01*
X470683Y277443D01*
X471183Y277777D01*
X471517Y278360D01*
G01Y277360D02*
Y280693D01*
G01X475700Y282360D02*
Y277360D01*
G01X474533Y280693D02*
X476867D01*
G01X480050Y279610D02*
X482717D01*
X482467Y280193D01*
X482050Y280527D01*
X481467Y280693D01*
X480883Y280610D01*
X480383Y280360D01*
X480050Y279777D01*
X479883Y279277D01*
Y278777D01*
X480050Y278277D01*
X480467Y277777D01*
X480967Y277443D01*
X481550Y277360D01*
X482133Y277527D01*
X482717Y278027D01*
G01X485733Y277360D02*
Y280693D01*
G01Y280027D02*
X486150Y280360D01*
X486567Y280610D01*
X487150Y280693D01*
X487567Y280610D01*
X488067Y280360D01*
G01X499600Y277360D02*
Y280693D01*
G01Y280110D02*
X499267Y280443D01*
X498767Y280610D01*
X498183Y280693D01*
X497600Y280527D01*
X497100Y280193D01*
X496767Y279693D01*
X496600Y279027D01*
X496767Y278360D01*
X497100Y277860D01*
X497600Y277527D01*
X498183Y277360D01*
X498767Y277443D01*
X499267Y277693D01*
X499600Y278027D01*
G01X502283Y277360D02*
Y280693D01*
G01Y279860D02*
X502617Y280277D01*
X503117Y280610D01*
X503783Y280693D01*
X504367Y280610D01*
X504867Y280277D01*
X505117Y279693D01*
Y277360D01*
G01X510800Y282360D02*
Y277360D01*
G01Y278110D02*
X510467Y277693D01*
X509967Y277443D01*
X509383Y277360D01*
X508717Y277527D01*
X508217Y277943D01*
X507883Y278443D01*
X507800Y279027D01*
X507883Y279610D01*
X508217Y280110D01*
X508717Y280527D01*
X509383Y280693D01*
X509967Y280610D01*
X510383Y280443D01*
X510800Y280110D01*
G01X520500Y280693D02*
Y277360D01*
G01Y282027D02*
X520333Y282110D01*
Y282277D01*
X520500Y282360D01*
X520667Y282277D01*
Y282110D01*
X520500Y282027D01*
G01X524683Y277360D02*
Y280693D01*
G01Y279860D02*
X525017Y280277D01*
X525517Y280610D01*
X526183Y280693D01*
X526767Y280610D01*
X527267Y280277D01*
X527517Y279693D01*
Y277360D01*
G01X530283D02*
Y280693D01*
G01Y279860D02*
X530617Y280277D01*
X531117Y280610D01*
X531783Y280693D01*
X532367Y280610D01*
X532867Y280277D01*
X533117Y279693D01*
Y277360D01*
G01X536050Y279610D02*
X538717D01*
X538467Y280193D01*
X538050Y280527D01*
X537467Y280693D01*
X536883Y280610D01*
X536383Y280360D01*
X536050Y279777D01*
X535883Y279277D01*
Y278777D01*
X536050Y278277D01*
X536467Y277777D01*
X536967Y277443D01*
X537550Y277360D01*
X538133Y277527D01*
X538717Y278027D01*
G01X541733Y277360D02*
Y280693D01*
G01Y280027D02*
X542150Y280360D01*
X542567Y280610D01*
X543150Y280693D01*
X543567Y280610D01*
X544067Y280360D01*
G01X554100Y277360D02*
Y282360D01*
G01X561200Y277360D02*
Y280693D01*
G01Y280110D02*
X560867Y280443D01*
X560367Y280610D01*
X559783Y280693D01*
X559200Y280527D01*
X558700Y280193D01*
X558367Y279693D01*
X558200Y279027D01*
X558367Y278360D01*
X558700Y277860D01*
X559200Y277527D01*
X559783Y277360D01*
X560367Y277443D01*
X560867Y277693D01*
X561200Y278027D01*
G01X564050Y277943D02*
X564467Y277610D01*
X565050Y277360D01*
X565550D01*
X566050Y277527D01*
X566383Y277777D01*
X566550Y278110D01*
X566467Y278610D01*
X566133Y278860D01*
X564633Y279360D01*
X564300Y279943D01*
X564467Y280360D01*
X564800Y280610D01*
X565300Y280693D01*
X565800Y280610D01*
X566300Y280360D01*
G01X569650Y279610D02*
X572317D01*
X572067Y280193D01*
X571650Y280527D01*
X571067Y280693D01*
X570483Y280610D01*
X569983Y280360D01*
X569650Y279777D01*
X569483Y279277D01*
Y278777D01*
X569650Y278277D01*
X570067Y277777D01*
X570567Y277443D01*
X571150Y277360D01*
X571733Y277527D01*
X572317Y278027D01*
G01X575333Y277360D02*
Y280693D01*
G01Y280027D02*
X575750Y280360D01*
X576167Y280610D01*
X576750Y280693D01*
X577167Y280610D01*
X577667Y280360D01*
G01X444197Y299927D02*
X443797Y300127D01*
X443330Y300260D01*
X442797D01*
X442197Y300060D01*
X441730Y299727D01*
X441397Y299327D01*
X441130Y298660D01*
X441063Y298060D01*
X441197Y297460D01*
X441397Y297060D01*
X441797Y296660D01*
X442263Y296393D01*
X442730Y296260D01*
X443197D01*
X443663Y296393D01*
X444063Y296593D01*
X444397Y296860D01*
G01X401827Y295540D02*
X403910Y300540D01*
X405993Y295540D01*
G01X405243Y297290D02*
X402577D01*
G01X408093Y295540D02*
Y298873D01*
G01Y298040D02*
X408427Y298457D01*
X408927Y298790D01*
X409593Y298873D01*
X410177Y298790D01*
X410677Y298457D01*
X410927Y297873D01*
Y295540D01*
G01X413943Y294290D02*
X414527Y293957D01*
X415193Y293873D01*
X415777Y293957D01*
X416277Y294373D01*
X416610Y294957D01*
Y298873D01*
G01Y298207D02*
X416277Y298540D01*
X415777Y298790D01*
X415193Y298873D01*
X414527Y298707D01*
X414110Y298373D01*
X413777Y297790D01*
X413610Y297207D01*
X413693Y296707D01*
X414027Y296123D01*
X414527Y295707D01*
X415193Y295540D01*
X415693Y295623D01*
X416277Y295957D01*
X416610Y296290D01*
G01X420710Y295540D02*
Y300540D01*
G01X425060Y297790D02*
X427727D01*
X427477Y298373D01*
X427060Y298707D01*
X426477Y298873D01*
X425893Y298790D01*
X425393Y298540D01*
X425060Y297957D01*
X424893Y297457D01*
Y296957D01*
X425060Y296457D01*
X425477Y295957D01*
X425977Y295623D01*
X426560Y295540D01*
X427143Y295707D01*
X427727Y296207D01*
G01X431493Y293873D02*
X430660Y294707D01*
X430243Y295540D01*
Y298873D01*
X430660Y299707D01*
X431493Y300540D01*
G01X449127Y293873D02*
X449960Y294707D01*
X450377Y295540D01*
Y298873D01*
X449960Y299707D01*
X449127Y300540D01*
G01X401777Y331927D02*
X402110Y332177D01*
X402360Y332593D01*
X402527Y333177D01*
X402360Y333677D01*
X402027Y334010D01*
X401443Y334260D01*
X399193D01*
Y329260D01*
X401943D01*
X402527Y329593D01*
X402860Y330093D01*
X403027Y330677D01*
X402860Y331260D01*
X402360Y331760D01*
X401777Y331927D01*
X399193D01*
G01X405210Y329093D02*
X408210Y334260D01*
G01X410227Y329260D02*
X412310Y334260D01*
X414393Y329260D01*
G01X413643Y331010D02*
X410977D01*
G01X400633Y358960D02*
Y353960D01*
X403967D01*
G01X409400D02*
Y357293D01*
G01Y356710D02*
X409067Y357043D01*
X408567Y357210D01*
X407983Y357293D01*
X407400Y357127D01*
X406900Y356793D01*
X406567Y356293D01*
X406400Y355627D01*
X406567Y354960D01*
X406900Y354460D01*
X407400Y354127D01*
X407983Y353960D01*
X408567Y354043D01*
X409067Y354293D01*
X409400Y354627D01*
G01X412250Y354543D02*
X412667Y354210D01*
X413250Y353960D01*
X413750D01*
X414250Y354127D01*
X414583Y354377D01*
X414750Y354710D01*
X414667Y355210D01*
X414333Y355460D01*
X412833Y355960D01*
X412500Y356543D01*
X412667Y356960D01*
X413000Y357210D01*
X413500Y357293D01*
X414000Y357210D01*
X414500Y356960D01*
G01X417850Y356210D02*
X420517D01*
X420267Y356793D01*
X419850Y357127D01*
X419267Y357293D01*
X418683Y357210D01*
X418183Y356960D01*
X417850Y356377D01*
X417683Y355877D01*
Y355377D01*
X417850Y354877D01*
X418267Y354377D01*
X418767Y354043D01*
X419350Y353960D01*
X419933Y354127D01*
X420517Y354627D01*
G01X423533Y353960D02*
Y357293D01*
G01Y356627D02*
X423950Y356960D01*
X424367Y357210D01*
X424950Y357293D01*
X425367Y357210D01*
X425867Y356960D01*
G01X434400Y357293D02*
X435900Y353960D01*
X437400Y357293D01*
G01X441500D02*
Y353960D01*
G01Y358627D02*
X441333Y358710D01*
Y358877D01*
X441500Y358960D01*
X441667Y358877D01*
Y358710D01*
X441500Y358627D01*
G01X448600Y353960D02*
Y357293D01*
G01Y356710D02*
X448267Y357043D01*
X447767Y357210D01*
X447183Y357293D01*
X446600Y357127D01*
X446100Y356793D01*
X445767Y356293D01*
X445600Y355627D01*
X445767Y354960D01*
X446100Y354460D01*
X446600Y354127D01*
X447183Y353960D01*
X447767Y354043D01*
X448267Y354293D01*
X448600Y354627D01*
G01X457050Y354543D02*
X457467Y354210D01*
X458050Y353960D01*
X458550D01*
X459050Y354127D01*
X459383Y354377D01*
X459550Y354710D01*
X459467Y355210D01*
X459133Y355460D01*
X457633Y355960D01*
X457300Y356543D01*
X457467Y356960D01*
X457800Y357210D01*
X458300Y357293D01*
X458800Y357210D01*
X459300Y356960D01*
G01X463900Y357293D02*
Y353960D01*
G01Y358627D02*
X463733Y358710D01*
Y358877D01*
X463900Y358960D01*
X464067Y358877D01*
Y358710D01*
X463900Y358627D01*
G01X468250Y357293D02*
X470750D01*
X468250Y353960D01*
X470750D01*
G01X473850Y356210D02*
X476517D01*
X476267Y356793D01*
X475850Y357127D01*
X475267Y357293D01*
X474683Y357210D01*
X474183Y356960D01*
X473850Y356377D01*
X473683Y355877D01*
Y355377D01*
X473850Y354877D01*
X474267Y354377D01*
X474767Y354043D01*
X475350Y353960D01*
X475933Y354127D01*
X476517Y354627D01*
G01X484217Y357293D02*
X485217Y353960D01*
X486300Y357293D01*
X487383Y353960D01*
X488383Y357293D01*
G01X491900D02*
Y353960D01*
G01Y358627D02*
X491733Y358710D01*
Y358877D01*
X491900Y358960D01*
X492067Y358877D01*
Y358710D01*
X491900Y358627D01*
G01X497500Y358960D02*
Y353960D01*
G01X496333Y357293D02*
X498667D01*
G01X501683Y353960D02*
Y358960D01*
G01Y356543D02*
X502100Y356960D01*
X502517Y357210D01*
X503183Y357293D01*
X503683Y357210D01*
X504267Y356877D01*
X504517Y356377D01*
Y353960D01*
G01X508700D02*
X508200Y354043D01*
X507700Y354377D01*
X507367Y354960D01*
X507200Y355627D01*
X507367Y356293D01*
X507700Y356877D01*
X508200Y357210D01*
X508700Y357293D01*
X509200Y357210D01*
X509700Y356877D01*
X510033Y356293D01*
X510117Y355627D01*
X510033Y354960D01*
X509700Y354377D01*
X509200Y354043D01*
X508700Y353960D01*
G01X512883Y357293D02*
Y354960D01*
X513217Y354377D01*
X513717Y354043D01*
X514300Y353960D01*
X514883Y354043D01*
X515383Y354377D01*
X515717Y354960D01*
G01Y353960D02*
Y357293D01*
G01X519900Y358960D02*
Y353960D01*
G01X518733Y357293D02*
X521067D01*
G01X529600Y352293D02*
Y357293D01*
G01Y356543D02*
X530017Y356960D01*
X530433Y357210D01*
X531100Y357293D01*
X531683Y357210D01*
X532267Y356793D01*
X532517Y356210D01*
X532600Y355627D01*
X532517Y355043D01*
X532267Y354460D01*
X531767Y354127D01*
X531100Y353960D01*
X530517Y354043D01*
X529933Y354293D01*
X529600Y354627D01*
G01X536700Y353960D02*
Y358960D01*
G01X543800Y353960D02*
Y357293D01*
G01Y356710D02*
X543467Y357043D01*
X542967Y357210D01*
X542383Y357293D01*
X541800Y357127D01*
X541300Y356793D01*
X540967Y356293D01*
X540800Y355627D01*
X540967Y354960D01*
X541300Y354460D01*
X541800Y354127D01*
X542383Y353960D01*
X542967Y354043D01*
X543467Y354293D01*
X543800Y354627D01*
G01X547900Y358960D02*
Y353960D01*
G01X546733Y357293D02*
X549067D01*
G01X553500D02*
Y353960D01*
G01Y358627D02*
X553333Y358710D01*
Y358877D01*
X553500Y358960D01*
X553667Y358877D01*
Y358710D01*
X553500Y358627D01*
G01X557683Y353960D02*
Y357293D01*
G01Y356460D02*
X558017Y356877D01*
X558517Y357210D01*
X559183Y357293D01*
X559767Y357210D01*
X560267Y356877D01*
X560517Y356293D01*
Y353960D01*
G01X563533Y352710D02*
X564117Y352377D01*
X564783Y352293D01*
X565367Y352377D01*
X565867Y352793D01*
X566200Y353377D01*
Y357293D01*
G01Y356627D02*
X565867Y356960D01*
X565367Y357210D01*
X564783Y357293D01*
X564117Y357127D01*
X563700Y356793D01*
X563367Y356210D01*
X563200Y355627D01*
X563283Y355127D01*
X563617Y354543D01*
X564117Y354127D01*
X564783Y353960D01*
X565283Y354043D01*
X565867Y354377D01*
X566200Y354710D01*
G01X575483Y352293D02*
X574650Y353127D01*
X574233Y353960D01*
Y357293D01*
X574650Y358127D01*
X575483Y358960D01*
G01X582167Y356627D02*
X582500Y356877D01*
X582750Y357293D01*
X582917Y357877D01*
X582750Y358377D01*
X582417Y358710D01*
X581833Y358960D01*
X579583D01*
Y353960D01*
X582333D01*
X582917Y354293D01*
X583250Y354793D01*
X583417Y355377D01*
X583250Y355960D01*
X582750Y356460D01*
X582167Y356627D01*
X579583D01*
G01X587517Y352293D02*
X588350Y353127D01*
X588767Y353960D01*
Y357293D01*
X588350Y358127D01*
X587517Y358960D01*
G01X395000Y305500D02*
X694500D01*
G01X395000Y337500D02*
X694500D01*
G01X404500Y666833D02*
Y663500D01*
G01Y668167D02*
X404333Y668250D01*
Y668417D01*
X404500Y668500D01*
X404667Y668417D01*
Y668250D01*
X404500Y668167D01*
G01X410100Y668500D02*
Y663500D01*
G01X408933Y666833D02*
X411267D01*
G01X414450Y665750D02*
X417117D01*
X416867Y666333D01*
X416450Y666667D01*
X415867Y666833D01*
X415283Y666750D01*
X414783Y666500D01*
X414450Y665917D01*
X414283Y665417D01*
Y664917D01*
X414450Y664417D01*
X414867Y663917D01*
X415367Y663583D01*
X415950Y663500D01*
X416533Y663667D01*
X417117Y664167D01*
G01X418800Y663500D02*
Y666833D01*
G01Y665917D02*
X419050Y666333D01*
X419467Y666667D01*
X420050Y666833D01*
X420633Y666667D01*
X421050Y666333D01*
X421300Y665917D01*
Y663500D01*
G01Y665917D02*
X421550Y666333D01*
X421967Y666667D01*
X422550Y666833D01*
X423133Y666667D01*
X423550Y666333D01*
X423800Y665833D01*
Y663500D01*
G01X607500Y-15000D02*
X606833Y-15167D01*
X606333Y-15583D01*
X606000Y-16083D01*
X605750Y-16750D01*
X605667Y-17500D01*
X605750Y-18250D01*
X606000Y-18917D01*
X606333Y-19417D01*
X606833Y-19833D01*
X607500Y-20000D01*
X608167Y-19833D01*
X608667Y-19417D01*
X609000Y-18917D01*
X609250Y-18250D01*
X609333Y-17500D01*
X609250Y-16750D01*
X609000Y-16083D01*
X608667Y-15583D01*
X608167Y-15167D01*
X607500Y-15000D01*
G01X613100Y-20167D02*
X612933Y-20083D01*
Y-19917D01*
X613100Y-19833D01*
X613267Y-19917D01*
Y-20083D01*
X613100Y-20167D01*
G01X616867Y-19000D02*
X617367Y-19583D01*
X618033Y-19917D01*
X618783Y-20000D01*
X619450Y-19917D01*
X620117Y-19500D01*
X620533Y-19000D01*
X620617Y-18500D01*
X620450Y-17917D01*
X619867Y-17500D01*
X619283Y-17333D01*
X618533D01*
G01X619283D02*
X619783Y-17083D01*
X620200Y-16667D01*
X620367Y-16167D01*
X620200Y-15667D01*
X619783Y-15250D01*
X619033Y-15000D01*
X618283Y-15083D01*
X617533Y-15417D01*
G01X621800Y-18333D02*
X622633Y-16667D01*
X623467D01*
X625133Y-20000D01*
X625967D01*
X626800Y-18333D01*
G01X629900Y-15000D02*
X629233Y-15167D01*
X628733Y-15583D01*
X628400Y-16083D01*
X628150Y-16750D01*
X628067Y-17500D01*
X628150Y-18250D01*
X628400Y-18917D01*
X628733Y-19417D01*
X629233Y-19833D01*
X629900Y-20000D01*
X630567Y-19833D01*
X631067Y-19417D01*
X631400Y-18917D01*
X631650Y-18250D01*
X631733Y-17500D01*
X631650Y-16750D01*
X631400Y-16083D01*
X631067Y-15583D01*
X630567Y-15167D01*
X629900Y-15000D01*
G01X635500Y-20167D02*
X635333Y-20083D01*
Y-19917D01*
X635500Y-19833D01*
X635667Y-19917D01*
Y-20083D01*
X635500Y-20167D01*
G01X640933Y-20000D02*
X641100Y-18917D01*
X641350Y-18000D01*
X641683Y-17167D01*
X642100Y-16250D01*
X642767Y-15000D01*
X639433D01*
G01X644200Y-20000D02*
Y-16667D01*
G01Y-17583D02*
X644450Y-17167D01*
X644867Y-16833D01*
X645450Y-16667D01*
X646033Y-16833D01*
X646450Y-17167D01*
X646700Y-17583D01*
Y-20000D01*
G01Y-17583D02*
X646950Y-17167D01*
X647367Y-16833D01*
X647950Y-16667D01*
X648533Y-16833D01*
X648950Y-17167D01*
X649200Y-17667D01*
Y-20000D01*
G01X652300Y-16667D02*
Y-20000D01*
G01Y-15333D02*
X652133Y-15250D01*
Y-15083D01*
X652300Y-15000D01*
X652467Y-15083D01*
Y-15250D01*
X652300Y-15333D01*
G01X657900Y-20000D02*
Y-15000D01*
G01X607500Y-28500D02*
X606833Y-28667D01*
X606333Y-29083D01*
X606000Y-29583D01*
X605750Y-30250D01*
X605667Y-31000D01*
X605750Y-31750D01*
X606000Y-32417D01*
X606333Y-32917D01*
X606833Y-33333D01*
X607500Y-33500D01*
X608167Y-33333D01*
X608667Y-32917D01*
X609000Y-32417D01*
X609250Y-31750D01*
X609333Y-31000D01*
X609250Y-30250D01*
X609000Y-29583D01*
X608667Y-29083D01*
X608167Y-28667D01*
X607500Y-28500D01*
G01X613100Y-33667D02*
X612933Y-33583D01*
Y-33417D01*
X613100Y-33333D01*
X613267Y-33417D01*
Y-33583D01*
X613100Y-33667D01*
G01X616867Y-32500D02*
X617367Y-33083D01*
X618033Y-33417D01*
X618783Y-33500D01*
X619450Y-33417D01*
X620117Y-33000D01*
X620533Y-32500D01*
X620617Y-32000D01*
X620450Y-31417D01*
X619867Y-31000D01*
X619283Y-30833D01*
X618533D01*
G01X619283D02*
X619783Y-30583D01*
X620200Y-30167D01*
X620367Y-29667D01*
X620200Y-29167D01*
X619783Y-28750D01*
X619033Y-28500D01*
X618283Y-28583D01*
X617533Y-28917D01*
G01X621800Y-31833D02*
X622633Y-30167D01*
X623467D01*
X625133Y-33500D01*
X625967D01*
X626800Y-31833D01*
G01X629900Y-28500D02*
X629233Y-28667D01*
X628733Y-29083D01*
X628400Y-29583D01*
X628150Y-30250D01*
X628067Y-31000D01*
X628150Y-31750D01*
X628400Y-32417D01*
X628733Y-32917D01*
X629233Y-33333D01*
X629900Y-33500D01*
X630567Y-33333D01*
X631067Y-32917D01*
X631400Y-32417D01*
X631650Y-31750D01*
X631733Y-31000D01*
X631650Y-30250D01*
X631400Y-29583D01*
X631067Y-29083D01*
X630567Y-28667D01*
X629900Y-28500D01*
G01X635500Y-33667D02*
X635333Y-33583D01*
Y-33417D01*
X635500Y-33333D01*
X635667Y-33417D01*
Y-33583D01*
X635500Y-33667D01*
G01X640933Y-33500D02*
X641100Y-32417D01*
X641350Y-31500D01*
X641683Y-30667D01*
X642100Y-29750D01*
X642767Y-28500D01*
X639433D01*
G01X644200Y-33500D02*
Y-30167D01*
G01Y-31083D02*
X644450Y-30667D01*
X644867Y-30333D01*
X645450Y-30167D01*
X646033Y-30333D01*
X646450Y-30667D01*
X646700Y-31083D01*
Y-33500D01*
G01Y-31083D02*
X646950Y-30667D01*
X647367Y-30333D01*
X647950Y-30167D01*
X648533Y-30333D01*
X648950Y-30667D01*
X649200Y-31167D01*
Y-33500D01*
G01X652300Y-30167D02*
Y-33500D01*
G01Y-28833D02*
X652133Y-28750D01*
Y-28583D01*
X652300Y-28500D01*
X652467Y-28583D01*
Y-28750D01*
X652300Y-28833D01*
G01X657900Y-33500D02*
Y-28500D01*
G01X609167Y-48500D02*
X605833Y-46833D01*
X609167Y-45167D01*
G01X612017Y-47583D02*
X614183D01*
G01Y-46083D02*
X612017D01*
G01X618700Y-48500D02*
Y-43500D01*
X617700Y-44500D01*
G01Y-48500D02*
X619700D01*
G01X624300Y-48667D02*
X624133Y-48583D01*
Y-48417D01*
X624300Y-48333D01*
X624467Y-48417D01*
Y-48583D01*
X624300Y-48667D01*
G01X630900Y-48500D02*
Y-43500D01*
X627817Y-47083D01*
X631983D01*
G01X633000Y-48500D02*
Y-45167D01*
G01Y-46083D02*
X633250Y-45667D01*
X633667Y-45333D01*
X634250Y-45167D01*
X634833Y-45333D01*
X635250Y-45667D01*
X635500Y-46083D01*
Y-48500D01*
G01Y-46083D02*
X635750Y-45667D01*
X636167Y-45333D01*
X636750Y-45167D01*
X637333Y-45333D01*
X637750Y-45667D01*
X638000Y-46167D01*
Y-48500D01*
G01X641100Y-45167D02*
Y-48500D01*
G01Y-43833D02*
X640933Y-43750D01*
Y-43583D01*
X641100Y-43500D01*
X641267Y-43583D01*
Y-43750D01*
X641100Y-43833D01*
G01X646700Y-48500D02*
Y-43500D01*
G01X605333Y-65000D02*
Y-60000D01*
X607500Y-64167D01*
X609667Y-60000D01*
Y-65000D01*
G01X611683Y-61667D02*
Y-64000D01*
X612017Y-64583D01*
X612517Y-64917D01*
X613100Y-65000D01*
X613683Y-64917D01*
X614183Y-64583D01*
X614517Y-64000D01*
G01Y-65000D02*
Y-61667D01*
G01X617450Y-64417D02*
X617867Y-64750D01*
X618450Y-65000D01*
X618950D01*
X619450Y-64833D01*
X619783Y-64583D01*
X619950Y-64250D01*
X619867Y-63750D01*
X619533Y-63500D01*
X618033Y-63000D01*
X617700Y-62417D01*
X617867Y-62000D01*
X618200Y-61750D01*
X618700Y-61667D01*
X619200Y-61750D01*
X619700Y-62000D01*
G01X624300Y-60000D02*
Y-65000D01*
G01X623133Y-61667D02*
X625467D01*
G01X635000Y-65000D02*
Y-60750D01*
X635167Y-60333D01*
X635500Y-60083D01*
X636000Y-60000D01*
X636500Y-60167D01*
X636750Y-60583D01*
G01X635750Y-62000D02*
X634083D01*
G01X641100Y-65000D02*
X640600Y-64917D01*
X640100Y-64583D01*
X639767Y-64000D01*
X639600Y-63333D01*
X639767Y-62667D01*
X640100Y-62083D01*
X640600Y-61750D01*
X641100Y-61667D01*
X641600Y-61750D01*
X642100Y-62083D01*
X642433Y-62667D01*
X642517Y-63333D01*
X642433Y-64000D01*
X642100Y-64583D01*
X641600Y-64917D01*
X641100Y-65000D01*
G01X646700D02*
Y-60000D01*
G01X652300Y-65000D02*
Y-60000D01*
G01X657900Y-65000D02*
X657400Y-64917D01*
X656900Y-64583D01*
X656567Y-64000D01*
X656400Y-63333D01*
X656567Y-62667D01*
X656900Y-62083D01*
X657400Y-61750D01*
X657900Y-61667D01*
X658400Y-61750D01*
X658900Y-62083D01*
X659233Y-62667D01*
X659317Y-63333D01*
X659233Y-64000D01*
X658900Y-64583D01*
X658400Y-64917D01*
X657900Y-65000D01*
G01X661417Y-61667D02*
X662417Y-65000D01*
X663500Y-61667D01*
X664583Y-65000D01*
X665583Y-61667D01*
G01X595500Y-69500D02*
Y438000D01*
G01X606583Y-1833D02*
X608583D01*
G01X607500Y-750D02*
Y-2917D01*
G01X611600Y-3667D02*
X614600Y1500D01*
G01X617617Y-1833D02*
X619783D01*
G01X624300Y-3500D02*
Y1500D01*
X623300Y500D01*
G01Y-3500D02*
X625300D01*
G01X627400D02*
Y-167D01*
G01Y-1083D02*
X627650Y-667D01*
X628067Y-333D01*
X628650Y-167D01*
X629233Y-333D01*
X629650Y-667D01*
X629900Y-1083D01*
Y-3500D01*
G01Y-1083D02*
X630150Y-667D01*
X630567Y-333D01*
X631150Y-167D01*
X631733Y-333D01*
X632150Y-667D01*
X632400Y-1167D01*
Y-3500D01*
G01X635500Y-167D02*
Y-3500D01*
G01Y1167D02*
X635333Y1250D01*
Y1417D01*
X635500Y1500D01*
X635667Y1417D01*
Y1250D01*
X635500Y1167D01*
G01X641100Y-3500D02*
Y1500D01*
G01X606583Y48667D02*
X608583D01*
G01X607500Y49750D02*
Y47583D01*
G01X611600Y46833D02*
X614600Y52000D01*
G01X617617Y48667D02*
X619783D01*
G01X622717Y51167D02*
X623217Y51667D01*
X623800Y51917D01*
X624467Y52000D01*
X625300Y51833D01*
X625883Y51417D01*
X626050Y50917D01*
X625967Y50417D01*
X625633Y50000D01*
X623967Y49167D01*
X623217Y48583D01*
X622717Y47750D01*
X622550Y47000D01*
X626050D01*
G01X627400D02*
Y50333D01*
G01Y49417D02*
X627650Y49833D01*
X628067Y50167D01*
X628650Y50333D01*
X629233Y50167D01*
X629650Y49833D01*
X629900Y49417D01*
Y47000D01*
G01Y49417D02*
X630150Y49833D01*
X630567Y50167D01*
X631150Y50333D01*
X631733Y50167D01*
X632150Y49833D01*
X632400Y49333D01*
Y47000D01*
G01X635500Y50333D02*
Y47000D01*
G01Y51667D02*
X635333Y51750D01*
Y51917D01*
X635500Y52000D01*
X635667Y51917D01*
Y51750D01*
X635500Y51667D01*
G01X641100Y47000D02*
Y52000D01*
G01X606583Y24667D02*
X608583D01*
G01X607500Y25750D02*
Y23583D01*
G01X611600Y22833D02*
X614600Y28000D01*
G01X617617Y24667D02*
X619783D01*
G01X624300Y23000D02*
Y28000D01*
X623300Y27000D01*
G01Y23000D02*
X625300D01*
G01X627400D02*
Y26333D01*
G01Y25417D02*
X627650Y25833D01*
X628067Y26167D01*
X628650Y26333D01*
X629233Y26167D01*
X629650Y25833D01*
X629900Y25417D01*
Y23000D01*
G01Y25417D02*
X630150Y25833D01*
X630567Y26167D01*
X631150Y26333D01*
X631733Y26167D01*
X632150Y25833D01*
X632400Y25333D01*
Y23000D01*
G01X635500Y26333D02*
Y23000D01*
G01Y27667D02*
X635333Y27750D01*
Y27917D01*
X635500Y28000D01*
X635667Y27917D01*
Y27750D01*
X635500Y27667D01*
G01X641100Y23000D02*
Y28000D01*
G01X606583Y13167D02*
X608583D01*
G01X607500Y14250D02*
Y12083D01*
G01X611600Y11333D02*
X614600Y16500D01*
G01X617617Y13167D02*
X619783D01*
G01X622717Y15667D02*
X623217Y16167D01*
X623800Y16417D01*
X624467Y16500D01*
X625300Y16333D01*
X625883Y15917D01*
X626050Y15417D01*
X625967Y14917D01*
X625633Y14500D01*
X623967Y13667D01*
X623217Y13083D01*
X622717Y12250D01*
X622550Y11500D01*
X626050D01*
G01X627400D02*
Y14833D01*
G01Y13917D02*
X627650Y14333D01*
X628067Y14667D01*
X628650Y14833D01*
X629233Y14667D01*
X629650Y14333D01*
X629900Y13917D01*
Y11500D01*
G01Y13917D02*
X630150Y14333D01*
X630567Y14667D01*
X631150Y14833D01*
X631733Y14667D01*
X632150Y14333D01*
X632400Y13833D01*
Y11500D01*
G01X635500Y14833D02*
Y11500D01*
G01Y16167D02*
X635333Y16250D01*
Y16417D01*
X635500Y16500D01*
X635667Y16417D01*
Y16250D01*
X635500Y16167D01*
G01X641100Y11500D02*
Y16500D01*
G01X606583Y98167D02*
X608583D01*
G01X607500Y99250D02*
Y97083D01*
G01X611600Y96333D02*
X614600Y101500D01*
G01X617617Y98167D02*
X619783D01*
G01X622717Y100667D02*
X623217Y101167D01*
X623800Y101417D01*
X624467Y101500D01*
X625300Y101333D01*
X625883Y100917D01*
X626050Y100417D01*
X625967Y99917D01*
X625633Y99500D01*
X623967Y98667D01*
X623217Y98083D01*
X622717Y97250D01*
X622550Y96500D01*
X626050D01*
G01X629900Y101500D02*
X629233Y101333D01*
X628733Y100917D01*
X628400Y100417D01*
X628150Y99750D01*
X628067Y99000D01*
X628150Y98250D01*
X628400Y97583D01*
X628733Y97083D01*
X629233Y96667D01*
X629900Y96500D01*
X630567Y96667D01*
X631067Y97083D01*
X631400Y97583D01*
X631650Y98250D01*
X631733Y99000D01*
X631650Y99750D01*
X631400Y100417D01*
X631067Y100917D01*
X630567Y101333D01*
X629900Y101500D01*
G01X634000Y96333D02*
X637000Y101500D01*
G01X634000D02*
X633500Y101333D01*
X633250Y101083D01*
X633083Y100583D01*
X633250Y100083D01*
X633500Y99833D01*
X634000Y99667D01*
X634500Y99833D01*
X634750Y100083D01*
X634917Y100583D01*
X634750Y101083D01*
X634500Y101333D01*
X634000Y101500D01*
G01X637000Y98167D02*
X636500Y98000D01*
X636250Y97750D01*
X636083Y97250D01*
X636250Y96750D01*
X636500Y96500D01*
X637000Y96333D01*
X637500Y96500D01*
X637750Y96750D01*
X637917Y97250D01*
X637750Y97750D01*
X637500Y98000D01*
X637000Y98167D01*
G01X606583Y68167D02*
X608583D01*
G01X607500Y69250D02*
Y67083D01*
G01X611600Y66333D02*
X614600Y71500D01*
G01X617617Y68167D02*
X619783D01*
G01X624300Y66500D02*
Y71500D01*
X623300Y70500D01*
G01Y66500D02*
X625300D01*
G01X628067Y67250D02*
X628567Y66833D01*
X629150Y66583D01*
X629900Y66500D01*
X630650Y66667D01*
X631233Y67000D01*
X631650Y67583D01*
X631733Y68250D01*
X631567Y68917D01*
X631150Y69333D01*
X630567Y69667D01*
X629983Y69750D01*
X629400Y69667D01*
X628650Y69333D01*
X628900Y71500D01*
X631150D01*
G01X634000Y66333D02*
X637000Y71500D01*
G01X634000D02*
X633500Y71333D01*
X633250Y71083D01*
X633083Y70583D01*
X633250Y70083D01*
X633500Y69833D01*
X634000Y69667D01*
X634500Y69833D01*
X634750Y70083D01*
X634917Y70583D01*
X634750Y71083D01*
X634500Y71333D01*
X634000Y71500D01*
G01X637000Y68167D02*
X636500Y68000D01*
X636250Y67750D01*
X636083Y67250D01*
X636250Y66750D01*
X636500Y66500D01*
X637000Y66333D01*
X637500Y66500D01*
X637750Y66750D01*
X637917Y67250D01*
X637750Y67750D01*
X637500Y68000D01*
X637000Y68167D01*
G01X606583Y113167D02*
X608583D01*
G01X607500Y114250D02*
Y112083D01*
G01X611600Y111333D02*
X614600Y116500D01*
G01X617617Y113167D02*
X619783D01*
G01X622467Y112500D02*
X622967Y111917D01*
X623633Y111583D01*
X624383Y111500D01*
X625050Y111583D01*
X625717Y112000D01*
X626133Y112500D01*
X626217Y113000D01*
X626050Y113583D01*
X625467Y114000D01*
X624883Y114167D01*
X624133D01*
G01X624883D02*
X625383Y114417D01*
X625800Y114833D01*
X625967Y115333D01*
X625800Y115833D01*
X625383Y116250D01*
X624633Y116500D01*
X623883Y116417D01*
X623133Y116083D01*
G01X627400Y111500D02*
Y114833D01*
G01Y113917D02*
X627650Y114333D01*
X628067Y114667D01*
X628650Y114833D01*
X629233Y114667D01*
X629650Y114333D01*
X629900Y113917D01*
Y111500D01*
G01Y113917D02*
X630150Y114333D01*
X630567Y114667D01*
X631150Y114833D01*
X631733Y114667D01*
X632150Y114333D01*
X632400Y113833D01*
Y111500D01*
G01X635500Y114833D02*
Y111500D01*
G01Y116167D02*
X635333Y116250D01*
Y116417D01*
X635500Y116500D01*
X635667Y116417D01*
Y116250D01*
X635500Y116167D01*
G01X641100Y111500D02*
Y116500D01*
G01X606583Y83167D02*
X608583D01*
G01X607500Y84250D02*
Y82083D01*
G01X611600Y81333D02*
X614600Y86500D01*
G01X617617Y83167D02*
X619783D01*
G01X624300Y81500D02*
Y86500D01*
X623300Y85500D01*
G01Y81500D02*
X625300D01*
G01X627400D02*
Y84833D01*
G01Y83917D02*
X627650Y84333D01*
X628067Y84667D01*
X628650Y84833D01*
X629233Y84667D01*
X629650Y84333D01*
X629900Y83917D01*
Y81500D01*
G01Y83917D02*
X630150Y84333D01*
X630567Y84667D01*
X631150Y84833D01*
X631733Y84667D01*
X632150Y84333D01*
X632400Y83833D01*
Y81500D01*
G01X635500Y84833D02*
Y81500D01*
G01Y86167D02*
X635333Y86250D01*
Y86417D01*
X635500Y86500D01*
X635667Y86417D01*
Y86250D01*
X635500Y86167D01*
G01X641100Y81500D02*
Y86500D01*
G01X605833Y166500D02*
X609167Y168167D01*
X605833Y169833D01*
G01X612017Y167417D02*
X614183D01*
G01Y168917D02*
X612017D01*
G01X618700Y166500D02*
Y171500D01*
X617700Y170500D01*
G01Y166500D02*
X619700D01*
G01X624300Y166333D02*
X624133Y166417D01*
Y166583D01*
X624300Y166667D01*
X624467Y166583D01*
Y166417D01*
X624300Y166333D01*
G01X628067Y167500D02*
X628567Y166917D01*
X629233Y166583D01*
X629983Y166500D01*
X630650Y166583D01*
X631317Y167000D01*
X631733Y167500D01*
X631817Y168000D01*
X631650Y168583D01*
X631067Y169000D01*
X630483Y169167D01*
X629733D01*
G01X630483D02*
X630983Y169417D01*
X631400Y169833D01*
X631567Y170333D01*
X631400Y170833D01*
X630983Y171250D01*
X630233Y171500D01*
X629483Y171417D01*
X628733Y171083D01*
G01X633000Y166500D02*
Y169833D01*
G01Y168917D02*
X633250Y169333D01*
X633667Y169667D01*
X634250Y169833D01*
X634833Y169667D01*
X635250Y169333D01*
X635500Y168917D01*
Y166500D01*
G01Y168917D02*
X635750Y169333D01*
X636167Y169667D01*
X636750Y169833D01*
X637333Y169667D01*
X637750Y169333D01*
X638000Y168833D01*
Y166500D01*
G01X641100Y169833D02*
Y166500D01*
G01Y171167D02*
X640933Y171250D01*
Y171417D01*
X641100Y171500D01*
X641267Y171417D01*
Y171250D01*
X641100Y171167D01*
G01X646700Y166500D02*
Y171500D01*
G01X605833Y144000D02*
X609167Y145667D01*
X605833Y147333D01*
G01X612017Y144917D02*
X614183D01*
G01Y146417D02*
X612017D01*
G01X618700Y144000D02*
Y149000D01*
X617700Y148000D01*
G01Y144000D02*
X619700D01*
G01X624300Y143833D02*
X624133Y143917D01*
Y144083D01*
X624300Y144167D01*
X624467Y144083D01*
Y143917D01*
X624300Y143833D01*
G01X628067Y144750D02*
X628567Y144333D01*
X629150Y144083D01*
X629900Y144000D01*
X630650Y144167D01*
X631233Y144500D01*
X631650Y145083D01*
X631733Y145750D01*
X631567Y146417D01*
X631150Y146833D01*
X630567Y147167D01*
X629983Y147250D01*
X629400Y147167D01*
X628650Y146833D01*
X628900Y149000D01*
X631150D01*
G01X633000Y144000D02*
Y147333D01*
G01Y146417D02*
X633250Y146833D01*
X633667Y147167D01*
X634250Y147333D01*
X634833Y147167D01*
X635250Y146833D01*
X635500Y146417D01*
Y144000D01*
G01Y146417D02*
X635750Y146833D01*
X636167Y147167D01*
X636750Y147333D01*
X637333Y147167D01*
X637750Y146833D01*
X638000Y146333D01*
Y144000D01*
G01X641100Y147333D02*
Y144000D01*
G01Y148667D02*
X640933Y148750D01*
Y148917D01*
X641100Y149000D01*
X641267Y148917D01*
Y148750D01*
X641100Y148667D01*
G01X646700Y144000D02*
Y149000D01*
G01X605833Y126500D02*
X609167Y128167D01*
X605833Y129833D01*
G01X612017Y127417D02*
X614183D01*
G01Y128917D02*
X612017D01*
G01X618700Y126500D02*
Y131500D01*
X617700Y130500D01*
G01Y126500D02*
X619700D01*
G01X624300Y126333D02*
X624133Y126417D01*
Y126583D01*
X624300Y126667D01*
X624467Y126583D01*
Y126417D01*
X624300Y126333D01*
G01X629900Y131500D02*
X629233Y131333D01*
X628733Y130917D01*
X628400Y130417D01*
X628150Y129750D01*
X628067Y129000D01*
X628150Y128250D01*
X628400Y127583D01*
X628733Y127083D01*
X629233Y126667D01*
X629900Y126500D01*
X630567Y126667D01*
X631067Y127083D01*
X631400Y127583D01*
X631650Y128250D01*
X631733Y129000D01*
X631650Y129750D01*
X631400Y130417D01*
X631067Y130917D01*
X630567Y131333D01*
X629900Y131500D01*
G01X633000Y126500D02*
Y129833D01*
G01Y128917D02*
X633250Y129333D01*
X633667Y129667D01*
X634250Y129833D01*
X634833Y129667D01*
X635250Y129333D01*
X635500Y128917D01*
Y126500D01*
G01Y128917D02*
X635750Y129333D01*
X636167Y129667D01*
X636750Y129833D01*
X637333Y129667D01*
X637750Y129333D01*
X638000Y128833D01*
Y126500D01*
G01X641100Y129833D02*
Y126500D01*
G01Y131167D02*
X640933Y131250D01*
Y131417D01*
X641100Y131500D01*
X641267Y131417D01*
Y131250D01*
X641100Y131167D01*
G01X646700Y126500D02*
Y131500D01*
G01X612977Y200490D02*
X609643Y202157D01*
X612977Y203823D01*
G01X616910Y205490D02*
X616243Y205323D01*
X615743Y204907D01*
X615410Y204407D01*
X615160Y203740D01*
X615077Y202990D01*
X615160Y202240D01*
X615410Y201573D01*
X615743Y201073D01*
X616243Y200657D01*
X616910Y200490D01*
X617577Y200657D01*
X618077Y201073D01*
X618410Y201573D01*
X618660Y202240D01*
X618743Y202990D01*
X618660Y203740D01*
X618410Y204407D01*
X618077Y204907D01*
X617577Y205323D01*
X616910Y205490D01*
G01X622510Y200323D02*
X622343Y200407D01*
Y200573D01*
X622510Y200657D01*
X622677Y200573D01*
Y200407D01*
X622510Y200323D01*
G01X626277Y201490D02*
X626777Y200907D01*
X627443Y200573D01*
X628193Y200490D01*
X628860Y200573D01*
X629527Y200990D01*
X629943Y201490D01*
X630027Y201990D01*
X629860Y202573D01*
X629277Y202990D01*
X628693Y203157D01*
X627943D01*
G01X628693D02*
X629193Y203407D01*
X629610Y203823D01*
X629777Y204323D01*
X629610Y204823D01*
X629193Y205240D01*
X628443Y205490D01*
X627693Y205407D01*
X626943Y205073D01*
G01X631210Y200490D02*
Y203823D01*
G01Y202907D02*
X631460Y203323D01*
X631877Y203657D01*
X632460Y203823D01*
X633043Y203657D01*
X633460Y203323D01*
X633710Y202907D01*
Y200490D01*
G01Y202907D02*
X633960Y203323D01*
X634377Y203657D01*
X634960Y203823D01*
X635543Y203657D01*
X635960Y203323D01*
X636210Y202823D01*
Y200490D01*
G01X639310Y203823D02*
Y200490D01*
G01Y205157D02*
X639143Y205240D01*
Y205407D01*
X639310Y205490D01*
X639477Y205407D01*
Y205240D01*
X639310Y205157D01*
G01X644910Y200490D02*
Y205490D01*
G01X612377Y255680D02*
X609043Y257347D01*
X612377Y259013D01*
G01X616310Y255680D02*
Y260680D01*
X615310Y259680D01*
G01Y255680D02*
X617310D01*
G01X619410D02*
Y259013D01*
G01Y258097D02*
X619660Y258513D01*
X620077Y258847D01*
X620660Y259013D01*
X621243Y258847D01*
X621660Y258513D01*
X621910Y258097D01*
Y255680D01*
G01Y258097D02*
X622160Y258513D01*
X622577Y258847D01*
X623160Y259013D01*
X623743Y258847D01*
X624160Y258513D01*
X624410Y258013D01*
Y255680D01*
G01X627510Y259013D02*
Y255680D01*
G01Y260347D02*
X627343Y260430D01*
Y260597D01*
X627510Y260680D01*
X627677Y260597D01*
Y260430D01*
X627510Y260347D01*
G01X633110Y255680D02*
Y260680D01*
G01X608397Y295230D02*
X605063Y296897D01*
X608397Y298563D01*
G01X610913Y295813D02*
X611497Y295397D01*
X612163Y295230D01*
X612830Y295397D01*
X613413Y295897D01*
X613830Y296647D01*
X613997Y297397D01*
Y298313D01*
X613830Y299063D01*
X613413Y299730D01*
X612913Y300063D01*
X612330Y300230D01*
X611663Y300063D01*
X611163Y299730D01*
X610830Y299230D01*
X610663Y298563D01*
X610830Y297980D01*
X611247Y297397D01*
X611747Y297063D01*
X612330Y296980D01*
X612997Y297147D01*
X613497Y297563D01*
X613997Y298313D01*
G01X617930Y300230D02*
X617263Y300063D01*
X616763Y299647D01*
X616430Y299147D01*
X616180Y298480D01*
X616097Y297730D01*
X616180Y296980D01*
X616430Y296313D01*
X616763Y295813D01*
X617263Y295397D01*
X617930Y295230D01*
X618597Y295397D01*
X619097Y295813D01*
X619430Y296313D01*
X619680Y296980D01*
X619763Y297730D01*
X619680Y298480D01*
X619430Y299147D01*
X619097Y299647D01*
X618597Y300063D01*
X617930Y300230D01*
G01X630630D02*
Y295230D01*
G01Y295980D02*
X630297Y295563D01*
X629797Y295313D01*
X629213Y295230D01*
X628547Y295397D01*
X628047Y295813D01*
X627713Y296313D01*
X627630Y296897D01*
X627713Y297480D01*
X628047Y297980D01*
X628547Y298397D01*
X629213Y298563D01*
X629797Y298480D01*
X630213Y298313D01*
X630630Y297980D01*
G01X633480Y297480D02*
X636147D01*
X635897Y298063D01*
X635480Y298397D01*
X634897Y298563D01*
X634313Y298480D01*
X633813Y298230D01*
X633480Y297647D01*
X633313Y297147D01*
Y296647D01*
X633480Y296147D01*
X633897Y295647D01*
X634397Y295313D01*
X634980Y295230D01*
X635563Y295397D01*
X636147Y295897D01*
G01X639163Y293980D02*
X639747Y293647D01*
X640413Y293563D01*
X640997Y293647D01*
X641497Y294063D01*
X641830Y294647D01*
Y298563D01*
G01Y297897D02*
X641497Y298230D01*
X640997Y298480D01*
X640413Y298563D01*
X639747Y298397D01*
X639330Y298063D01*
X638997Y297480D01*
X638830Y296897D01*
X638913Y296397D01*
X639247Y295813D01*
X639747Y295397D01*
X640413Y295230D01*
X640913Y295313D01*
X641497Y295647D01*
X641830Y295980D01*
G01X644763Y295230D02*
Y298563D01*
G01Y297897D02*
X645180Y298230D01*
X645597Y298480D01*
X646180Y298563D01*
X646597Y298480D01*
X647097Y298230D01*
G01X650280Y297480D02*
X652947D01*
X652697Y298063D01*
X652280Y298397D01*
X651697Y298563D01*
X651113Y298480D01*
X650613Y298230D01*
X650280Y297647D01*
X650113Y297147D01*
Y296647D01*
X650280Y296147D01*
X650697Y295647D01*
X651197Y295313D01*
X651780Y295230D01*
X652363Y295397D01*
X652947Y295897D01*
G01X655880Y297480D02*
X658547D01*
X658297Y298063D01*
X657880Y298397D01*
X657297Y298563D01*
X656713Y298480D01*
X656213Y298230D01*
X655880Y297647D01*
X655713Y297147D01*
Y296647D01*
X655880Y296147D01*
X656297Y295647D01*
X656797Y295313D01*
X657380Y295230D01*
X657963Y295397D01*
X658547Y295897D01*
G01X602120Y310470D02*
Y313803D01*
G01Y312887D02*
X602370Y313303D01*
X602787Y313637D01*
X603370Y313803D01*
X603953Y313637D01*
X604370Y313303D01*
X604620Y312887D01*
Y310470D01*
G01Y312887D02*
X604870Y313303D01*
X605287Y313637D01*
X605870Y313803D01*
X606453Y313637D01*
X606870Y313303D01*
X607120Y312803D01*
Y310470D01*
G01X608803Y313803D02*
Y311470D01*
X609137Y310887D01*
X609637Y310553D01*
X610220Y310470D01*
X610803Y310553D01*
X611303Y310887D01*
X611637Y311470D01*
G01Y310470D02*
Y313803D01*
G01X614570Y311053D02*
X614987Y310720D01*
X615570Y310470D01*
X616070D01*
X616570Y310637D01*
X616903Y310887D01*
X617070Y311220D01*
X616987Y311720D01*
X616653Y311970D01*
X615153Y312470D01*
X614820Y313053D01*
X614987Y313470D01*
X615320Y313720D01*
X615820Y313803D01*
X616320Y313720D01*
X616820Y313470D01*
G01X621420Y315470D02*
Y310470D01*
G01X620253Y313803D02*
X622587D01*
G01X628687Y310470D02*
X625353Y312137D01*
X628687Y313803D01*
G01X630537Y310470D02*
X632620Y315470D01*
X634703Y310470D01*
G01X633953Y312220D02*
X631287D01*
G01X645320Y315470D02*
Y310470D01*
G01Y311220D02*
X644987Y310803D01*
X644487Y310553D01*
X643903Y310470D01*
X643237Y310637D01*
X642737Y311053D01*
X642403Y311553D01*
X642320Y312137D01*
X642403Y312720D01*
X642737Y313220D01*
X643237Y313637D01*
X643903Y313803D01*
X644487Y313720D01*
X644903Y313553D01*
X645320Y313220D01*
G01X649420Y313803D02*
Y310470D01*
G01Y315137D02*
X649253Y315220D01*
Y315387D01*
X649420Y315470D01*
X649587Y315387D01*
Y315220D01*
X649420Y315137D01*
G01X656520Y310470D02*
Y313803D01*
G01Y313220D02*
X656187Y313553D01*
X655687Y313720D01*
X655103Y313803D01*
X654520Y313637D01*
X654020Y313303D01*
X653687Y312803D01*
X653520Y312137D01*
X653687Y311470D01*
X654020Y310970D01*
X654520Y310637D01*
X655103Y310470D01*
X655687Y310553D01*
X656187Y310803D01*
X656520Y311137D01*
G01X658120Y310470D02*
Y313803D01*
G01Y312887D02*
X658370Y313303D01*
X658787Y313637D01*
X659370Y313803D01*
X659953Y313637D01*
X660370Y313303D01*
X660620Y312887D01*
Y310470D01*
G01Y312887D02*
X660870Y313303D01*
X661287Y313637D01*
X661870Y313803D01*
X662453Y313637D01*
X662870Y313303D01*
X663120Y312803D01*
Y310470D01*
G01X664970Y312720D02*
X667637D01*
X667387Y313303D01*
X666970Y313637D01*
X666387Y313803D01*
X665803Y313720D01*
X665303Y313470D01*
X664970Y312887D01*
X664803Y312387D01*
Y311887D01*
X664970Y311387D01*
X665387Y310887D01*
X665887Y310553D01*
X666470Y310470D01*
X667053Y310637D01*
X667637Y311137D01*
G01X671820Y315470D02*
Y310470D01*
G01X670653Y313803D02*
X672987D01*
G01X676170Y312720D02*
X678837D01*
X678587Y313303D01*
X678170Y313637D01*
X677587Y313803D01*
X677003Y313720D01*
X676503Y313470D01*
X676170Y312887D01*
X676003Y312387D01*
Y311887D01*
X676170Y311387D01*
X676587Y310887D01*
X677087Y310553D01*
X677670Y310470D01*
X678253Y310637D01*
X678837Y311137D01*
G01X681853Y310470D02*
Y313803D01*
G01Y313137D02*
X682270Y313470D01*
X682687Y313720D01*
X683270Y313803D01*
X683687Y313720D01*
X684187Y313470D01*
G01X602700Y319240D02*
Y324240D01*
G01Y321740D02*
X603117Y322240D01*
X603617Y322490D01*
X604117Y322573D01*
X604867Y322407D01*
X605367Y322073D01*
X605700Y321490D01*
Y320823D01*
X605533Y320157D01*
X605200Y319657D01*
X604617Y319323D01*
X604117Y319240D01*
X603617Y319323D01*
X603117Y319573D01*
X602700Y319990D01*
G01X608383Y322573D02*
Y320240D01*
X608717Y319657D01*
X609217Y319323D01*
X609800Y319240D01*
X610383Y319323D01*
X610883Y319657D01*
X611217Y320240D01*
G01Y319240D02*
Y322573D01*
G01X615400Y324240D02*
Y319240D01*
G01X614233Y322573D02*
X616567D01*
G01X627267Y321907D02*
X627600Y322157D01*
X627850Y322573D01*
X628017Y323157D01*
X627850Y323657D01*
X627517Y323990D01*
X626933Y324240D01*
X624683D01*
Y319240D01*
X627433D01*
X628017Y319573D01*
X628350Y320073D01*
X628517Y320657D01*
X628350Y321240D01*
X627850Y321740D01*
X627267Y321907D01*
X624683D01*
G01X639300Y324240D02*
Y319240D01*
G01Y319990D02*
X638967Y319573D01*
X638467Y319323D01*
X637883Y319240D01*
X637217Y319407D01*
X636717Y319823D01*
X636383Y320323D01*
X636300Y320907D01*
X636383Y321490D01*
X636717Y321990D01*
X637217Y322407D01*
X637883Y322573D01*
X638467Y322490D01*
X638883Y322323D01*
X639300Y321990D01*
G01X643400Y322573D02*
Y319240D01*
G01Y323907D02*
X643233Y323990D01*
Y324157D01*
X643400Y324240D01*
X643567Y324157D01*
Y323990D01*
X643400Y323907D01*
G01X650500Y319240D02*
Y322573D01*
G01Y321990D02*
X650167Y322323D01*
X649667Y322490D01*
X649083Y322573D01*
X648500Y322407D01*
X648000Y322073D01*
X647667Y321573D01*
X647500Y320907D01*
X647667Y320240D01*
X648000Y319740D01*
X648500Y319407D01*
X649083Y319240D01*
X649667Y319323D01*
X650167Y319573D01*
X650500Y319907D01*
G01X652100Y319240D02*
Y322573D01*
G01Y321657D02*
X652350Y322073D01*
X652767Y322407D01*
X653350Y322573D01*
X653933Y322407D01*
X654350Y322073D01*
X654600Y321657D01*
Y319240D01*
G01Y321657D02*
X654850Y322073D01*
X655267Y322407D01*
X655850Y322573D01*
X656433Y322407D01*
X656850Y322073D01*
X657100Y321573D01*
Y319240D01*
G01X658950Y321490D02*
X661617D01*
X661367Y322073D01*
X660950Y322407D01*
X660367Y322573D01*
X659783Y322490D01*
X659283Y322240D01*
X658950Y321657D01*
X658783Y321157D01*
Y320657D01*
X658950Y320157D01*
X659367Y319657D01*
X659867Y319323D01*
X660450Y319240D01*
X661033Y319407D01*
X661617Y319907D01*
G01X665800Y324240D02*
Y319240D01*
G01X664633Y322573D02*
X666967D01*
G01X670150Y321490D02*
X672817D01*
X672567Y322073D01*
X672150Y322407D01*
X671567Y322573D01*
X670983Y322490D01*
X670483Y322240D01*
X670150Y321657D01*
X669983Y321157D01*
Y320657D01*
X670150Y320157D01*
X670567Y319657D01*
X671067Y319323D01*
X671650Y319240D01*
X672233Y319407D01*
X672817Y319907D01*
G01X675833Y319240D02*
Y322573D01*
G01Y321907D02*
X676250Y322240D01*
X676667Y322490D01*
X677250Y322573D01*
X677667Y322490D01*
X678167Y322240D01*
G01X603783Y329260D02*
X607117Y330927D01*
X603783Y332593D01*
G01X609967Y330177D02*
X612133D01*
G01Y331677D02*
X609967D01*
G01X616483Y329260D02*
X616650Y330343D01*
X616900Y331260D01*
X617233Y332093D01*
X617650Y333010D01*
X618317Y334260D01*
X614983D01*
G01X622250D02*
X621583Y334093D01*
X621083Y333677D01*
X620750Y333177D01*
X620500Y332510D01*
X620417Y331760D01*
X620500Y331010D01*
X620750Y330343D01*
X621083Y329843D01*
X621583Y329427D01*
X622250Y329260D01*
X622917Y329427D01*
X623417Y329843D01*
X623750Y330343D01*
X624000Y331010D01*
X624083Y331760D01*
X624000Y332510D01*
X623750Y333177D01*
X623417Y333677D01*
X622917Y334093D01*
X622250Y334260D01*
G01X626350Y329093D02*
X629350Y334260D01*
G01X626350D02*
X625850Y334093D01*
X625600Y333843D01*
X625433Y333343D01*
X625600Y332843D01*
X625850Y332593D01*
X626350Y332427D01*
X626850Y332593D01*
X627100Y332843D01*
X627267Y333343D01*
X627100Y333843D01*
X626850Y334093D01*
X626350Y334260D01*
G01X629350Y330927D02*
X628850Y330760D01*
X628600Y330510D01*
X628433Y330010D01*
X628600Y329510D01*
X628850Y329260D01*
X629350Y329093D01*
X629850Y329260D01*
X630100Y329510D01*
X630267Y330010D01*
X630100Y330510D01*
X629850Y330760D01*
X629350Y330927D01*
G01X633283Y328343D02*
X633617Y329427D01*
G01X605763Y349687D02*
X607763D01*
G01X606680Y350770D02*
Y348603D01*
G01X610780Y347853D02*
X613780Y353020D01*
G01X616797Y349687D02*
X618963D01*
G01X623480Y348020D02*
Y353020D01*
X622480Y352020D01*
G01Y348020D02*
X624480D01*
G01X626580D02*
Y351353D01*
G01Y350437D02*
X626830Y350853D01*
X627247Y351187D01*
X627830Y351353D01*
X628413Y351187D01*
X628830Y350853D01*
X629080Y350437D01*
Y348020D01*
G01Y350437D02*
X629330Y350853D01*
X629747Y351187D01*
X630330Y351353D01*
X630913Y351187D01*
X631330Y350853D01*
X631580Y350353D01*
Y348020D01*
G01X634680Y351353D02*
Y348020D01*
G01Y352687D02*
X634513Y352770D01*
Y352937D01*
X634680Y353020D01*
X634847Y352937D01*
Y352770D01*
X634680Y352687D01*
G01X640280Y348020D02*
Y353020D01*
G01X608333Y393000D02*
Y398000D01*
X610500Y393833D01*
X612667Y398000D01*
Y393000D01*
G01X614683Y396333D02*
Y394000D01*
X615017Y393417D01*
X615517Y393083D01*
X616100Y393000D01*
X616683Y393083D01*
X617183Y393417D01*
X617517Y394000D01*
G01Y393000D02*
Y396333D01*
G01X620450Y393583D02*
X620867Y393250D01*
X621450Y393000D01*
X621950D01*
X622450Y393167D01*
X622783Y393417D01*
X622950Y393750D01*
X622867Y394250D01*
X622533Y394500D01*
X621033Y395000D01*
X620700Y395583D01*
X620867Y396000D01*
X621200Y396250D01*
X621700Y396333D01*
X622200Y396250D01*
X622700Y396000D01*
G01X627300Y398000D02*
Y393000D01*
G01X626133Y396333D02*
X628467D01*
G01X638000Y393000D02*
Y397250D01*
X638167Y397667D01*
X638500Y397917D01*
X639000Y398000D01*
X639500Y397833D01*
X639750Y397417D01*
G01X638750Y396000D02*
X637083D01*
G01X644100Y393000D02*
X643600Y393083D01*
X643100Y393417D01*
X642767Y394000D01*
X642600Y394667D01*
X642767Y395333D01*
X643100Y395917D01*
X643600Y396250D01*
X644100Y396333D01*
X644600Y396250D01*
X645100Y395917D01*
X645433Y395333D01*
X645517Y394667D01*
X645433Y394000D01*
X645100Y393417D01*
X644600Y393083D01*
X644100Y393000D01*
G01X649700D02*
Y398000D01*
G01X655300Y393000D02*
Y398000D01*
G01X660900Y393000D02*
X660400Y393083D01*
X659900Y393417D01*
X659567Y394000D01*
X659400Y394667D01*
X659567Y395333D01*
X659900Y395917D01*
X660400Y396250D01*
X660900Y396333D01*
X661400Y396250D01*
X661900Y395917D01*
X662233Y395333D01*
X662317Y394667D01*
X662233Y394000D01*
X661900Y393417D01*
X661400Y393083D01*
X660900Y393000D01*
G01X664417Y396333D02*
X665417Y393000D01*
X666500Y396333D01*
X667583Y393000D01*
X668583Y396333D01*
G01X595500Y679000D02*
Y396000D01*
G01X605810Y429990D02*
Y434240D01*
X605977Y434657D01*
X606310Y434907D01*
X606810Y434990D01*
X607310Y434823D01*
X607560Y434407D01*
G01X606560Y432990D02*
X604893D01*
G01X611910Y429990D02*
X611410Y430073D01*
X610910Y430407D01*
X610577Y430990D01*
X610410Y431657D01*
X610577Y432323D01*
X610910Y432907D01*
X611410Y433240D01*
X611910Y433323D01*
X612410Y433240D01*
X612910Y432907D01*
X613243Y432323D01*
X613327Y431657D01*
X613243Y430990D01*
X612910Y430407D01*
X612410Y430073D01*
X611910Y429990D01*
G01X617510D02*
Y434990D01*
G01X623110Y429990D02*
Y434990D01*
G01X628710Y429990D02*
X628210Y430073D01*
X627710Y430407D01*
X627377Y430990D01*
X627210Y431657D01*
X627377Y432323D01*
X627710Y432907D01*
X628210Y433240D01*
X628710Y433323D01*
X629210Y433240D01*
X629710Y432907D01*
X630043Y432323D01*
X630127Y431657D01*
X630043Y430990D01*
X629710Y430407D01*
X629210Y430073D01*
X628710Y429990D01*
G01X632227Y433323D02*
X633227Y429990D01*
X634310Y433323D01*
X635393Y429990D01*
X636393Y433323D01*
G01X647010Y434990D02*
Y429990D01*
G01Y430740D02*
X646677Y430323D01*
X646177Y430073D01*
X645593Y429990D01*
X644927Y430157D01*
X644427Y430573D01*
X644093Y431073D01*
X644010Y431657D01*
X644093Y432240D01*
X644427Y432740D01*
X644927Y433157D01*
X645593Y433323D01*
X646177Y433240D01*
X646593Y433073D01*
X647010Y432740D01*
G01X649943Y429990D02*
Y433323D01*
G01Y432657D02*
X650360Y432990D01*
X650777Y433240D01*
X651360Y433323D01*
X651777Y433240D01*
X652277Y432990D01*
G01X658210Y429990D02*
Y433323D01*
G01Y432740D02*
X657877Y433073D01*
X657377Y433240D01*
X656793Y433323D01*
X656210Y433157D01*
X655710Y432823D01*
X655377Y432323D01*
X655210Y431657D01*
X655377Y430990D01*
X655710Y430490D01*
X656210Y430157D01*
X656793Y429990D01*
X657377Y430073D01*
X657877Y430323D01*
X658210Y430657D01*
G01X660227Y433323D02*
X661227Y429990D01*
X662310Y433323D01*
X663393Y429990D01*
X664393Y433323D01*
G01X667910D02*
Y429990D01*
G01Y434657D02*
X667743Y434740D01*
Y434907D01*
X667910Y434990D01*
X668077Y434907D01*
Y434740D01*
X667910Y434657D01*
G01X672093Y429990D02*
Y433323D01*
G01Y432490D02*
X672427Y432907D01*
X672927Y433240D01*
X673593Y433323D01*
X674177Y433240D01*
X674677Y432907D01*
X674927Y432323D01*
Y429990D01*
G01X677943Y428740D02*
X678527Y428407D01*
X679193Y428323D01*
X679777Y428407D01*
X680277Y428823D01*
X680610Y429407D01*
Y433323D01*
G01Y432657D02*
X680277Y432990D01*
X679777Y433240D01*
X679193Y433323D01*
X678527Y433157D01*
X678110Y432823D01*
X677777Y432240D01*
X677610Y431657D01*
X677693Y431157D01*
X678027Y430573D01*
X678527Y430157D01*
X679193Y429990D01*
X679693Y430073D01*
X680277Y430407D01*
X680610Y430740D01*
G01X685127Y428323D02*
X685960Y429157D01*
X686377Y429990D01*
Y433323D01*
X685960Y434157D01*
X685127Y434990D01*
G01X606903Y440587D02*
X608903D01*
G01X607820Y441670D02*
Y439503D01*
G01X611920Y438753D02*
X614920Y443920D01*
G01X617937Y440587D02*
X620103D01*
G01X622787Y439670D02*
X623287Y439253D01*
X623870Y439003D01*
X624620Y438920D01*
X625370Y439087D01*
X625953Y439420D01*
X626370Y440003D01*
X626453Y440670D01*
X626287Y441337D01*
X625870Y441753D01*
X625287Y442087D01*
X624703Y442170D01*
X624120Y442087D01*
X623370Y441753D01*
X623620Y443920D01*
X625870D01*
G01X627720Y438920D02*
Y442253D01*
G01Y441337D02*
X627970Y441753D01*
X628387Y442087D01*
X628970Y442253D01*
X629553Y442087D01*
X629970Y441753D01*
X630220Y441337D01*
Y438920D01*
G01Y441337D02*
X630470Y441753D01*
X630887Y442087D01*
X631470Y442253D01*
X632053Y442087D01*
X632470Y441753D01*
X632720Y441253D01*
Y438920D01*
G01X635820Y442253D02*
Y438920D01*
G01Y443587D02*
X635653Y443670D01*
Y443837D01*
X635820Y443920D01*
X635987Y443837D01*
Y443670D01*
X635820Y443587D01*
G01X641420Y438920D02*
Y443920D01*
G01X607500Y452000D02*
Y457000D01*
X606500Y456000D01*
G01Y452000D02*
X608500D01*
G01X613100Y451833D02*
X612933Y451917D01*
Y452083D01*
X613100Y452167D01*
X613267Y452083D01*
Y451917D01*
X613100Y451833D01*
G01X618700Y457000D02*
X618033Y456833D01*
X617533Y456417D01*
X617200Y455917D01*
X616950Y455250D01*
X616867Y454500D01*
X616950Y453750D01*
X617200Y453083D01*
X617533Y452583D01*
X618033Y452167D01*
X618700Y452000D01*
X619367Y452167D01*
X619867Y452583D01*
X620200Y453083D01*
X620450Y453750D01*
X620533Y454500D01*
X620450Y455250D01*
X620200Y455917D01*
X619867Y456417D01*
X619367Y456833D01*
X618700Y457000D01*
G01X621800Y452000D02*
Y455333D01*
G01Y454417D02*
X622050Y454833D01*
X622467Y455167D01*
X623050Y455333D01*
X623633Y455167D01*
X624050Y454833D01*
X624300Y454417D01*
Y452000D01*
G01Y454417D02*
X624550Y454833D01*
X624967Y455167D01*
X625550Y455333D01*
X626133Y455167D01*
X626550Y454833D01*
X626800Y454333D01*
Y452000D01*
G01X629900Y455333D02*
Y452000D01*
G01Y456667D02*
X629733Y456750D01*
Y456917D01*
X629900Y457000D01*
X630067Y456917D01*
Y456750D01*
X629900Y456667D01*
G01X635500Y452000D02*
Y457000D01*
G01X644200Y452000D02*
Y455333D01*
G01Y454417D02*
X644450Y454833D01*
X644867Y455167D01*
X645450Y455333D01*
X646033Y455167D01*
X646450Y454833D01*
X646700Y454417D01*
Y452000D01*
G01Y454417D02*
X646950Y454833D01*
X647367Y455167D01*
X647950Y455333D01*
X648533Y455167D01*
X648950Y454833D01*
X649200Y454333D01*
Y452000D01*
G01X653800D02*
Y455333D01*
G01Y454750D02*
X653467Y455083D01*
X652967Y455250D01*
X652383Y455333D01*
X651800Y455167D01*
X651300Y454833D01*
X650967Y454333D01*
X650800Y453667D01*
X650967Y453000D01*
X651300Y452500D01*
X651800Y452167D01*
X652383Y452000D01*
X652967Y452083D01*
X653467Y452333D01*
X653800Y452667D01*
G01X656650Y455333D02*
X659150Y452000D01*
G01Y455333D02*
X656650Y452000D01*
G01X606583Y471667D02*
X608583D01*
G01X607500Y472750D02*
Y470583D01*
G01X611600Y469833D02*
X614600Y475000D01*
G01X617617Y471667D02*
X619783D01*
G01X622467Y470750D02*
X622967Y470333D01*
X623550Y470083D01*
X624300Y470000D01*
X625050Y470167D01*
X625633Y470500D01*
X626050Y471083D01*
X626133Y471750D01*
X625967Y472417D01*
X625550Y472833D01*
X624967Y473167D01*
X624383Y473250D01*
X623800Y473167D01*
X623050Y472833D01*
X623300Y475000D01*
X625550D01*
G01X627400Y470000D02*
Y473333D01*
G01Y472417D02*
X627650Y472833D01*
X628067Y473167D01*
X628650Y473333D01*
X629233Y473167D01*
X629650Y472833D01*
X629900Y472417D01*
Y470000D01*
G01Y472417D02*
X630150Y472833D01*
X630567Y473167D01*
X631150Y473333D01*
X631733Y473167D01*
X632150Y472833D01*
X632400Y472333D01*
Y470000D01*
G01X635500Y473333D02*
Y470000D01*
G01Y474667D02*
X635333Y474750D01*
Y474917D01*
X635500Y475000D01*
X635667Y474917D01*
Y474750D01*
X635500Y474667D01*
G01X641100Y470000D02*
Y475000D01*
G01X606583Y486667D02*
X608583D01*
G01X607500Y487750D02*
Y485583D01*
G01X611600Y484833D02*
X614600Y490000D01*
G01X617617Y486667D02*
X619783D01*
G01X622467Y485750D02*
X622967Y485333D01*
X623550Y485083D01*
X624300Y485000D01*
X625050Y485167D01*
X625633Y485500D01*
X626050Y486083D01*
X626133Y486750D01*
X625967Y487417D01*
X625550Y487833D01*
X624967Y488167D01*
X624383Y488250D01*
X623800Y488167D01*
X623050Y487833D01*
X623300Y490000D01*
X625550D01*
G01X627400Y485000D02*
Y488333D01*
G01Y487417D02*
X627650Y487833D01*
X628067Y488167D01*
X628650Y488333D01*
X629233Y488167D01*
X629650Y487833D01*
X629900Y487417D01*
Y485000D01*
G01Y487417D02*
X630150Y487833D01*
X630567Y488167D01*
X631150Y488333D01*
X631733Y488167D01*
X632150Y487833D01*
X632400Y487333D01*
Y485000D01*
G01X635500Y488333D02*
Y485000D01*
G01Y489667D02*
X635333Y489750D01*
Y489917D01*
X635500Y490000D01*
X635667Y489917D01*
Y489750D01*
X635500Y489667D01*
G01X641100Y485000D02*
Y490000D01*
G01X606583Y546667D02*
X608583D01*
G01X607500Y547750D02*
Y545583D01*
G01X611600Y544833D02*
X614600Y550000D01*
G01X617617Y546667D02*
X619783D01*
G01X622717Y549167D02*
X623217Y549667D01*
X623800Y549917D01*
X624467Y550000D01*
X625300Y549833D01*
X625883Y549417D01*
X626050Y548917D01*
X625967Y548417D01*
X625633Y548000D01*
X623967Y547167D01*
X623217Y546583D01*
X622717Y545750D01*
X622550Y545000D01*
X626050D01*
G01X627400D02*
Y548333D01*
G01Y547417D02*
X627650Y547833D01*
X628067Y548167D01*
X628650Y548333D01*
X629233Y548167D01*
X629650Y547833D01*
X629900Y547417D01*
Y545000D01*
G01Y547417D02*
X630150Y547833D01*
X630567Y548167D01*
X631150Y548333D01*
X631733Y548167D01*
X632150Y547833D01*
X632400Y547333D01*
Y545000D01*
G01X635500Y548333D02*
Y545000D01*
G01Y549667D02*
X635333Y549750D01*
Y549917D01*
X635500Y550000D01*
X635667Y549917D01*
Y549750D01*
X635500Y549667D01*
G01X641100Y545000D02*
Y550000D01*
G01X606583Y501667D02*
X608583D01*
G01X607500Y502750D02*
Y500583D01*
G01X611267Y501000D02*
X611767Y500417D01*
X612433Y500083D01*
X613183Y500000D01*
X613850Y500083D01*
X614517Y500500D01*
X614933Y501000D01*
X615017Y501500D01*
X614850Y502083D01*
X614267Y502500D01*
X613683Y502667D01*
X612933D01*
G01X613683D02*
X614183Y502917D01*
X614600Y503333D01*
X614767Y503833D01*
X614600Y504333D01*
X614183Y504750D01*
X613433Y505000D01*
X612683Y504917D01*
X611933Y504583D01*
G01X617200Y499833D02*
X620200Y505000D01*
G01X623217Y501667D02*
X625383D01*
G01X629900Y505000D02*
X629233Y504833D01*
X628733Y504417D01*
X628400Y503917D01*
X628150Y503250D01*
X628067Y502500D01*
X628150Y501750D01*
X628400Y501083D01*
X628733Y500583D01*
X629233Y500167D01*
X629900Y500000D01*
X630567Y500167D01*
X631067Y500583D01*
X631400Y501083D01*
X631650Y501750D01*
X631733Y502500D01*
X631650Y503250D01*
X631400Y503917D01*
X631067Y504417D01*
X630567Y504833D01*
X629900Y505000D01*
G01X633000Y500000D02*
Y503333D01*
G01Y502417D02*
X633250Y502833D01*
X633667Y503167D01*
X634250Y503333D01*
X634833Y503167D01*
X635250Y502833D01*
X635500Y502417D01*
Y500000D01*
G01Y502417D02*
X635750Y502833D01*
X636167Y503167D01*
X636750Y503333D01*
X637333Y503167D01*
X637750Y502833D01*
X638000Y502333D01*
Y500000D01*
G01X641100Y503333D02*
Y500000D01*
G01Y504667D02*
X640933Y504750D01*
Y504917D01*
X641100Y505000D01*
X641267Y504917D01*
Y504750D01*
X641100Y504667D01*
G01X646700Y500000D02*
Y505000D01*
G01X606583Y516667D02*
X608583D01*
G01X607500Y517750D02*
Y515583D01*
G01X611600Y514833D02*
X614600Y520000D01*
G01X617617Y516667D02*
X619783D01*
G01X622717Y519167D02*
X623217Y519667D01*
X623800Y519917D01*
X624467Y520000D01*
X625300Y519833D01*
X625883Y519417D01*
X626050Y518917D01*
X625967Y518417D01*
X625633Y518000D01*
X623967Y517167D01*
X623217Y516583D01*
X622717Y515750D01*
X622550Y515000D01*
X626050D01*
G01X627400D02*
Y518333D01*
G01Y517417D02*
X627650Y517833D01*
X628067Y518167D01*
X628650Y518333D01*
X629233Y518167D01*
X629650Y517833D01*
X629900Y517417D01*
Y515000D01*
G01Y517417D02*
X630150Y517833D01*
X630567Y518167D01*
X631150Y518333D01*
X631733Y518167D01*
X632150Y517833D01*
X632400Y517333D01*
Y515000D01*
G01X635500Y518333D02*
Y515000D01*
G01Y519667D02*
X635333Y519750D01*
Y519917D01*
X635500Y520000D01*
X635667Y519917D01*
Y519750D01*
X635500Y519667D01*
G01X641100Y515000D02*
Y520000D01*
G01X606583Y530167D02*
X608583D01*
G01X607500Y531250D02*
Y529083D01*
G01X611600Y528333D02*
X614600Y533500D01*
G01X617617Y530167D02*
X619783D01*
G01X622467Y529500D02*
X622967Y528917D01*
X623633Y528583D01*
X624383Y528500D01*
X625050Y528583D01*
X625717Y529000D01*
X626133Y529500D01*
X626217Y530000D01*
X626050Y530583D01*
X625467Y531000D01*
X624883Y531167D01*
X624133D01*
G01X624883D02*
X625383Y531417D01*
X625800Y531833D01*
X625967Y532333D01*
X625800Y532833D01*
X625383Y533250D01*
X624633Y533500D01*
X623883Y533417D01*
X623133Y533083D01*
G01X627400Y528500D02*
Y531833D01*
G01Y530917D02*
X627650Y531333D01*
X628067Y531667D01*
X628650Y531833D01*
X629233Y531667D01*
X629650Y531333D01*
X629900Y530917D01*
Y528500D01*
G01Y530917D02*
X630150Y531333D01*
X630567Y531667D01*
X631150Y531833D01*
X631733Y531667D01*
X632150Y531333D01*
X632400Y530833D01*
Y528500D01*
G01X635500Y531833D02*
Y528500D01*
G01Y533167D02*
X635333Y533250D01*
Y533417D01*
X635500Y533500D01*
X635667Y533417D01*
Y533250D01*
X635500Y533167D01*
G01X641100Y528500D02*
Y533500D01*
G01X606583Y591667D02*
X608583D01*
G01X607500Y592750D02*
Y590583D01*
G01X611600Y589833D02*
X614600Y595000D01*
G01X617617Y591667D02*
X619783D01*
G01X622467Y591000D02*
X622967Y590417D01*
X623633Y590083D01*
X624383Y590000D01*
X625050Y590083D01*
X625717Y590500D01*
X626133Y591000D01*
X626217Y591500D01*
X626050Y592083D01*
X625467Y592500D01*
X624883Y592667D01*
X624133D01*
G01X624883D02*
X625383Y592917D01*
X625800Y593333D01*
X625967Y593833D01*
X625800Y594333D01*
X625383Y594750D01*
X624633Y595000D01*
X623883Y594917D01*
X623133Y594583D01*
G01X627400Y590000D02*
Y593333D01*
G01Y592417D02*
X627650Y592833D01*
X628067Y593167D01*
X628650Y593333D01*
X629233Y593167D01*
X629650Y592833D01*
X629900Y592417D01*
Y590000D01*
G01Y592417D02*
X630150Y592833D01*
X630567Y593167D01*
X631150Y593333D01*
X631733Y593167D01*
X632150Y592833D01*
X632400Y592333D01*
Y590000D01*
G01X635500Y593333D02*
Y590000D01*
G01Y594667D02*
X635333Y594750D01*
Y594917D01*
X635500Y595000D01*
X635667Y594917D01*
Y594750D01*
X635500Y594667D01*
G01X641100Y590000D02*
Y595000D01*
G01X605417Y603500D02*
X607500Y608500D01*
X609583Y603500D01*
G01X608833Y605250D02*
X606167D01*
G01X613100Y603500D02*
Y608500D01*
G01X618700Y603500D02*
Y608500D01*
G01X624300Y603500D02*
X623800Y603583D01*
X623300Y603917D01*
X622967Y604500D01*
X622800Y605167D01*
X622967Y605833D01*
X623300Y606417D01*
X623800Y606750D01*
X624300Y606833D01*
X624800Y606750D01*
X625300Y606417D01*
X625633Y605833D01*
X625717Y605167D01*
X625633Y604500D01*
X625300Y603917D01*
X624800Y603583D01*
X624300Y603500D01*
G01X627817Y606833D02*
X628817Y603500D01*
X629900Y606833D01*
X630983Y603500D01*
X631983Y606833D01*
G01X606583Y575167D02*
X608583D01*
G01X607500Y576250D02*
Y574083D01*
G01X611517Y577667D02*
X612017Y578167D01*
X612600Y578417D01*
X613267Y578500D01*
X614100Y578333D01*
X614683Y577917D01*
X614850Y577417D01*
X614767Y576917D01*
X614433Y576500D01*
X612767Y575667D01*
X612017Y575083D01*
X611517Y574250D01*
X611350Y573500D01*
X614850D01*
G01X617200Y573333D02*
X620200Y578500D01*
G01X623217Y575167D02*
X625383D01*
G01X630900Y573500D02*
Y578500D01*
X627817Y574917D01*
X631983D01*
G01X633000Y573500D02*
Y576833D01*
G01Y575917D02*
X633250Y576333D01*
X633667Y576667D01*
X634250Y576833D01*
X634833Y576667D01*
X635250Y576333D01*
X635500Y575917D01*
Y573500D01*
G01Y575917D02*
X635750Y576333D01*
X636167Y576667D01*
X636750Y576833D01*
X637333Y576667D01*
X637750Y576333D01*
X638000Y575833D01*
Y573500D01*
G01X641100Y576833D02*
Y573500D01*
G01Y578167D02*
X640933Y578250D01*
Y578417D01*
X641100Y578500D01*
X641267Y578417D01*
Y578250D01*
X641100Y578167D01*
G01X646700Y573500D02*
Y578500D01*
G01X606583Y561667D02*
X608583D01*
G01X607500Y562750D02*
Y560583D01*
G01X611600Y559833D02*
X614600Y565000D01*
G01X617617Y561667D02*
X619783D01*
G01X622717Y564167D02*
X623217Y564667D01*
X623800Y564917D01*
X624467Y565000D01*
X625300Y564833D01*
X625883Y564417D01*
X626050Y563917D01*
X625967Y563417D01*
X625633Y563000D01*
X623967Y562167D01*
X623217Y561583D01*
X622717Y560750D01*
X622550Y560000D01*
X626050D01*
G01X627400D02*
Y563333D01*
G01Y562417D02*
X627650Y562833D01*
X628067Y563167D01*
X628650Y563333D01*
X629233Y563167D01*
X629650Y562833D01*
X629900Y562417D01*
Y560000D01*
G01Y562417D02*
X630150Y562833D01*
X630567Y563167D01*
X631150Y563333D01*
X631733Y563167D01*
X632150Y562833D01*
X632400Y562333D01*
Y560000D01*
G01X635500Y563333D02*
Y560000D01*
G01Y564667D02*
X635333Y564750D01*
Y564917D01*
X635500Y565000D01*
X635667Y564917D01*
Y564750D01*
X635500Y564667D01*
G01X641100Y560000D02*
Y565000D01*
G01X606583Y620167D02*
X608583D01*
G01X607500Y621250D02*
Y619083D01*
G01X611600Y618333D02*
X614600Y623500D01*
G01X617617Y620167D02*
X619783D01*
G01X622717Y622667D02*
X623217Y623167D01*
X623800Y623417D01*
X624467Y623500D01*
X625300Y623333D01*
X625883Y622917D01*
X626050Y622417D01*
X625967Y621917D01*
X625633Y621500D01*
X623967Y620667D01*
X623217Y620083D01*
X622717Y619250D01*
X622550Y618500D01*
X626050D01*
G01X627400D02*
Y621833D01*
G01Y620917D02*
X627650Y621333D01*
X628067Y621667D01*
X628650Y621833D01*
X629233Y621667D01*
X629650Y621333D01*
X629900Y620917D01*
Y618500D01*
G01Y620917D02*
X630150Y621333D01*
X630567Y621667D01*
X631150Y621833D01*
X631733Y621667D01*
X632150Y621333D01*
X632400Y620833D01*
Y618500D01*
G01X635500Y621833D02*
Y618500D01*
G01Y623167D02*
X635333Y623250D01*
Y623417D01*
X635500Y623500D01*
X635667Y623417D01*
Y623250D01*
X635500Y623167D01*
G01X641100Y618500D02*
Y623500D01*
G01X617500Y668500D02*
Y663500D01*
G01X615583Y668500D02*
X619417D01*
G01X623100Y663500D02*
X622600Y663583D01*
X622100Y663917D01*
X621767Y664500D01*
X621600Y665167D01*
X621767Y665833D01*
X622100Y666417D01*
X622600Y666750D01*
X623100Y666833D01*
X623600Y666750D01*
X624100Y666417D01*
X624433Y665833D01*
X624517Y665167D01*
X624433Y664500D01*
X624100Y663917D01*
X623600Y663583D01*
X623100Y663500D01*
G01X628700D02*
Y668500D01*
G01X633050Y665750D02*
X635717D01*
X635467Y666333D01*
X635050Y666667D01*
X634467Y666833D01*
X633883Y666750D01*
X633383Y666500D01*
X633050Y665917D01*
X632883Y665417D01*
Y664917D01*
X633050Y664417D01*
X633467Y663917D01*
X633967Y663583D01*
X634550Y663500D01*
X635133Y663667D01*
X635717Y664167D01*
G01X638733Y663500D02*
Y666833D01*
G01Y666167D02*
X639150Y666500D01*
X639567Y666750D01*
X640150Y666833D01*
X640567Y666750D01*
X641067Y666500D01*
G01X647000Y663500D02*
Y666833D01*
G01Y666250D02*
X646667Y666583D01*
X646167Y666750D01*
X645583Y666833D01*
X645000Y666667D01*
X644500Y666333D01*
X644167Y665833D01*
X644000Y665167D01*
X644167Y664500D01*
X644500Y664000D01*
X645000Y663667D01*
X645583Y663500D01*
X646167Y663583D01*
X646667Y663833D01*
X647000Y664167D01*
G01X649683Y663500D02*
Y666833D01*
G01Y666000D02*
X650017Y666417D01*
X650517Y666750D01*
X651183Y666833D01*
X651767Y666750D01*
X652267Y666417D01*
X652517Y665833D01*
Y663500D01*
G01X658033Y666417D02*
X657450Y666750D01*
X656950Y666833D01*
X656283Y666667D01*
X655783Y666333D01*
X655450Y665750D01*
X655367Y665167D01*
X655450Y664583D01*
X655783Y664083D01*
X656283Y663667D01*
X656950Y663500D01*
X657533Y663667D01*
X658033Y664000D01*
G01X661050Y665750D02*
X663717D01*
X663467Y666333D01*
X663050Y666667D01*
X662467Y666833D01*
X661883Y666750D01*
X661383Y666500D01*
X661050Y665917D01*
X660883Y665417D01*
Y664917D01*
X661050Y664417D01*
X661467Y663917D01*
X661967Y663583D01*
X662550Y663500D01*
X663133Y663667D01*
X663717Y664167D01*
G01X605353Y638700D02*
Y643700D01*
X607520Y639533D01*
X609687Y643700D01*
Y638700D01*
G01X611703Y642033D02*
Y639700D01*
X612037Y639117D01*
X612537Y638783D01*
X613120Y638700D01*
X613703Y638783D01*
X614203Y639117D01*
X614537Y639700D01*
G01Y638700D02*
Y642033D01*
G01X617470Y639283D02*
X617887Y638950D01*
X618470Y638700D01*
X618970D01*
X619470Y638867D01*
X619803Y639117D01*
X619970Y639450D01*
X619887Y639950D01*
X619553Y640200D01*
X618053Y640700D01*
X617720Y641283D01*
X617887Y641700D01*
X618220Y641950D01*
X618720Y642033D01*
X619220Y641950D01*
X619720Y641700D01*
G01X624320Y643700D02*
Y638700D01*
G01X623153Y642033D02*
X625487D01*
G01X635020Y638700D02*
Y642950D01*
X635187Y643367D01*
X635520Y643617D01*
X636020Y643700D01*
X636520Y643533D01*
X636770Y643117D01*
G01X635770Y641700D02*
X634103D01*
G01X641120Y638700D02*
X640620Y638783D01*
X640120Y639117D01*
X639787Y639700D01*
X639620Y640367D01*
X639787Y641033D01*
X640120Y641617D01*
X640620Y641950D01*
X641120Y642033D01*
X641620Y641950D01*
X642120Y641617D01*
X642453Y641033D01*
X642537Y640367D01*
X642453Y639700D01*
X642120Y639117D01*
X641620Y638783D01*
X641120Y638700D01*
G01X646720D02*
Y643700D01*
G01X652320Y638700D02*
Y643700D01*
G01X657920Y638700D02*
X657420Y638783D01*
X656920Y639117D01*
X656587Y639700D01*
X656420Y640367D01*
X656587Y641033D01*
X656920Y641617D01*
X657420Y641950D01*
X657920Y642033D01*
X658420Y641950D01*
X658920Y641617D01*
X659253Y641033D01*
X659337Y640367D01*
X659253Y639700D01*
X658920Y639117D01*
X658420Y638783D01*
X657920Y638700D01*
G01X661437Y642033D02*
X662437Y638700D01*
X663520Y642033D01*
X664603Y638700D01*
X665603Y642033D01*
G01X590417Y860000D02*
X592500Y855000D01*
X594583Y860000D01*
G01X596267Y856000D02*
X596767Y855417D01*
X597433Y855083D01*
X598183Y855000D01*
X598850Y855083D01*
X599517Y855500D01*
X599933Y856000D01*
X600017Y856500D01*
X599850Y857083D01*
X599267Y857500D01*
X598683Y857667D01*
X597933D01*
G01X598683D02*
X599183Y857917D01*
X599600Y858333D01*
X599767Y858833D01*
X599600Y859333D01*
X599183Y859750D01*
X598433Y860000D01*
X597683Y859917D01*
X596933Y859583D01*
G01X603700Y854833D02*
X603533Y854917D01*
Y855083D01*
X603700Y855167D01*
X603867Y855083D01*
Y854917D01*
X603700Y854833D01*
G01X610300Y855000D02*
Y860000D01*
X607217Y856417D01*
X611383D01*
G01X614900Y854833D02*
X614733Y854917D01*
Y855083D01*
X614900Y855167D01*
X615067Y855083D01*
Y854917D01*
X614900Y854833D01*
G01X620500Y855000D02*
Y860000D01*
X619500Y859000D01*
G01Y855000D02*
X621500D01*
G01X641317Y859167D02*
X641817Y859667D01*
X642400Y859917D01*
X643067Y860000D01*
X643900Y859833D01*
X644483Y859417D01*
X644650Y858917D01*
X644567Y858417D01*
X644233Y858000D01*
X642567Y857167D01*
X641817Y856583D01*
X641317Y855750D01*
X641150Y855000D01*
X644650D01*
G01X648500Y860000D02*
X647833Y859833D01*
X647333Y859417D01*
X647000Y858917D01*
X646750Y858250D01*
X646667Y857500D01*
X646750Y856750D01*
X647000Y856083D01*
X647333Y855583D01*
X647833Y855167D01*
X648500Y855000D01*
X649167Y855167D01*
X649667Y855583D01*
X650000Y856083D01*
X650250Y856750D01*
X650333Y857500D01*
X650250Y858250D01*
X650000Y858917D01*
X649667Y859417D01*
X649167Y859833D01*
X648500Y860000D01*
G01X654100Y855000D02*
Y860000D01*
X653100Y859000D01*
G01Y855000D02*
X655100D01*
G01X657867Y855750D02*
X658367Y855333D01*
X658950Y855083D01*
X659700Y855000D01*
X660450Y855167D01*
X661033Y855500D01*
X661450Y856083D01*
X661533Y856750D01*
X661367Y857417D01*
X660950Y857833D01*
X660367Y858167D01*
X659783Y858250D01*
X659200Y858167D01*
X658450Y857833D01*
X658700Y860000D01*
X660950D01*
G01X663800Y854833D02*
X666800Y860000D01*
G01X670900D02*
X670233Y859833D01*
X669733Y859417D01*
X669400Y858917D01*
X669150Y858250D01*
X669067Y857500D01*
X669150Y856750D01*
X669400Y856083D01*
X669733Y855583D01*
X670233Y855167D01*
X670900Y855000D01*
X671567Y855167D01*
X672067Y855583D01*
X672400Y856083D01*
X672650Y856750D01*
X672733Y857500D01*
X672650Y858250D01*
X672400Y858917D01*
X672067Y859417D01*
X671567Y859833D01*
X670900Y860000D01*
G01X674917Y857083D02*
X675500Y857667D01*
X676000Y858000D01*
X676667Y858167D01*
X677250Y858000D01*
X677667Y857667D01*
X678000Y857167D01*
X678083Y856583D01*
X678000Y856083D01*
X677667Y855583D01*
X677167Y855167D01*
X676583Y855000D01*
X675917Y855167D01*
X675333Y855667D01*
X675000Y856417D01*
X674917Y857250D01*
X675083Y858333D01*
X675333Y858917D01*
X675750Y859500D01*
X676333Y859917D01*
X676917Y860000D01*
X677500Y859833D01*
X677917Y859417D01*
G01X694500Y716000D02*
Y-69500D01*
G01X650853Y438153D02*
X650020Y438987D01*
X649603Y439820D01*
Y443153D01*
X650020Y443987D01*
X650853Y444820D01*
G01X656870Y439820D02*
X656370Y439903D01*
X655870Y440237D01*
X655537Y440820D01*
X655370Y441487D01*
X655537Y442153D01*
X655870Y442737D01*
X656370Y443070D01*
X656870Y443153D01*
X657370Y443070D01*
X657870Y442737D01*
X658203Y442153D01*
X658287Y441487D01*
X658203Y440820D01*
X657870Y440237D01*
X657370Y439903D01*
X656870Y439820D01*
G01X661303D02*
Y443153D01*
G01Y442487D02*
X661720Y442820D01*
X662137Y443070D01*
X662720Y443153D01*
X663137Y443070D01*
X663637Y442820D01*
G01X713000Y850500D02*
Y-73000D01*
X1343000D01*
Y782000D01*
X713000D01*
G01X736937Y-65320D02*
X737437Y-65737D01*
X738020Y-65987D01*
X738770Y-66070D01*
X739520Y-65903D01*
X740103Y-65570D01*
X740520Y-64987D01*
X740603Y-64320D01*
X740437Y-63653D01*
X740020Y-63237D01*
X739437Y-62903D01*
X738853Y-62820D01*
X738270Y-62903D01*
X737520Y-63237D01*
X737770Y-61070D01*
X740020D01*
G01X744370Y-66237D02*
X744203Y-66153D01*
Y-65987D01*
X744370Y-65903D01*
X744537Y-65987D01*
Y-66153D01*
X744370Y-66237D01*
G01X749970Y-66070D02*
Y-61070D01*
X748970Y-62070D01*
G01Y-66070D02*
X750970D01*
G01X760170Y-61070D02*
X762170D01*
G01X761170D02*
Y-66070D01*
G01X760170D02*
X762170D01*
G01X766270D02*
Y-61820D01*
X766437Y-61403D01*
X766770Y-61153D01*
X767270Y-61070D01*
X767770Y-61237D01*
X768020Y-61653D01*
G01X767020Y-63070D02*
X765353D01*
G01X778470Y-63570D02*
X780137D01*
Y-65070D01*
X779637Y-65570D01*
X779053Y-65903D01*
X778220Y-66070D01*
X777387Y-65903D01*
X776803Y-65570D01*
X776303Y-65070D01*
X775970Y-64487D01*
X775803Y-63820D01*
Y-63237D01*
X775970Y-62737D01*
X776303Y-62153D01*
X776803Y-61653D01*
X777303Y-61320D01*
X777970Y-61070D01*
X778553D01*
X779220Y-61237D01*
X779720Y-61570D01*
G01X782320Y-63820D02*
X784987D01*
X784737Y-63237D01*
X784320Y-62903D01*
X783737Y-62737D01*
X783153Y-62820D01*
X782653Y-63070D01*
X782320Y-63653D01*
X782153Y-64153D01*
Y-64653D01*
X782320Y-65153D01*
X782737Y-65653D01*
X783237Y-65987D01*
X783820Y-66070D01*
X784403Y-65903D01*
X784987Y-65403D01*
G01X788003Y-66070D02*
Y-62737D01*
G01Y-63403D02*
X788420Y-63070D01*
X788837Y-62820D01*
X789420Y-62737D01*
X789837Y-62820D01*
X790337Y-63070D01*
G01X793270Y-66070D02*
Y-61070D01*
G01Y-63570D02*
X793687Y-63070D01*
X794187Y-62820D01*
X794687Y-62737D01*
X795437Y-62903D01*
X795937Y-63237D01*
X796270Y-63820D01*
Y-64487D01*
X796103Y-65153D01*
X795770Y-65653D01*
X795187Y-65987D01*
X794687Y-66070D01*
X794187Y-65987D01*
X793687Y-65737D01*
X793270Y-65320D01*
G01X799120Y-63820D02*
X801787D01*
X801537Y-63237D01*
X801120Y-62903D01*
X800537Y-62737D01*
X799953Y-62820D01*
X799453Y-63070D01*
X799120Y-63653D01*
X798953Y-64153D01*
Y-64653D01*
X799120Y-65153D01*
X799537Y-65653D01*
X800037Y-65987D01*
X800620Y-66070D01*
X801203Y-65903D01*
X801787Y-65403D01*
G01X804803Y-66070D02*
Y-62737D01*
G01Y-63403D02*
X805220Y-63070D01*
X805637Y-62820D01*
X806220Y-62737D01*
X806637Y-62820D01*
X807137Y-63070D01*
G01X815753Y-66070D02*
Y-61070D01*
G01Y-63487D02*
X816170Y-63070D01*
X816587Y-62820D01*
X817253Y-62737D01*
X817753Y-62820D01*
X818337Y-63153D01*
X818587Y-63653D01*
Y-66070D01*
G01X824270D02*
Y-62737D01*
G01Y-63320D02*
X823937Y-62987D01*
X823437Y-62820D01*
X822853Y-62737D01*
X822270Y-62903D01*
X821770Y-63237D01*
X821437Y-63737D01*
X821270Y-64403D01*
X821437Y-65070D01*
X821770Y-65570D01*
X822270Y-65903D01*
X822853Y-66070D01*
X823437Y-65987D01*
X823937Y-65737D01*
X824270Y-65403D01*
G01X827120Y-65487D02*
X827537Y-65820D01*
X828120Y-66070D01*
X828620D01*
X829120Y-65903D01*
X829453Y-65653D01*
X829620Y-65320D01*
X829537Y-64820D01*
X829203Y-64570D01*
X827703Y-64070D01*
X827370Y-63487D01*
X827537Y-63070D01*
X827870Y-62820D01*
X828370Y-62737D01*
X828870Y-62820D01*
X829370Y-63070D01*
G01X839570Y-61070D02*
Y-66070D01*
G01X838403Y-62737D02*
X840737D01*
G01X843753Y-66070D02*
Y-61070D01*
G01Y-63487D02*
X844170Y-63070D01*
X844587Y-62820D01*
X845253Y-62737D01*
X845753Y-62820D01*
X846337Y-63153D01*
X846587Y-63653D01*
Y-66070D01*
G01X850770Y-62737D02*
Y-66070D01*
G01Y-61403D02*
X850603Y-61320D01*
Y-61153D01*
X850770Y-61070D01*
X850937Y-61153D01*
Y-61320D01*
X850770Y-61403D01*
G01X855120Y-65487D02*
X855537Y-65820D01*
X856120Y-66070D01*
X856620D01*
X857120Y-65903D01*
X857453Y-65653D01*
X857620Y-65320D01*
X857537Y-64820D01*
X857203Y-64570D01*
X855703Y-64070D01*
X855370Y-63487D01*
X855537Y-63070D01*
X855870Y-62820D01*
X856370Y-62737D01*
X856870Y-62820D01*
X857370Y-63070D01*
G01X866153Y-66070D02*
Y-61070D01*
G01X868820Y-62737D02*
X866153Y-64653D01*
G01X867237Y-63903D02*
X868987Y-66070D01*
G01X873170Y-62737D02*
Y-66070D01*
G01Y-61403D02*
X873003Y-61320D01*
Y-61153D01*
X873170Y-61070D01*
X873337Y-61153D01*
Y-61320D01*
X873170Y-61403D01*
G01X877353Y-66070D02*
Y-62737D01*
G01Y-63570D02*
X877687Y-63153D01*
X878187Y-62820D01*
X878853Y-62737D01*
X879437Y-62820D01*
X879937Y-63153D01*
X880187Y-63737D01*
Y-66070D01*
G01X885870Y-61070D02*
Y-66070D01*
G01Y-65320D02*
X885537Y-65737D01*
X885037Y-65987D01*
X884453Y-66070D01*
X883787Y-65903D01*
X883287Y-65487D01*
X882953Y-64987D01*
X882870Y-64403D01*
X882953Y-63820D01*
X883287Y-63320D01*
X883787Y-62903D01*
X884453Y-62737D01*
X885037Y-62820D01*
X885453Y-62987D01*
X885870Y-63320D01*
G01X895570Y-66070D02*
X895070Y-65987D01*
X894570Y-65653D01*
X894237Y-65070D01*
X894070Y-64403D01*
X894237Y-63737D01*
X894570Y-63153D01*
X895070Y-62820D01*
X895570Y-62737D01*
X896070Y-62820D01*
X896570Y-63153D01*
X896903Y-63737D01*
X896987Y-64403D01*
X896903Y-65070D01*
X896570Y-65653D01*
X896070Y-65987D01*
X895570Y-66070D01*
G01X900670D02*
Y-61820D01*
X900837Y-61403D01*
X901170Y-61153D01*
X901670Y-61070D01*
X902170Y-61237D01*
X902420Y-61653D01*
G01X901420Y-63070D02*
X899753D01*
G01X913870Y-61070D02*
Y-66070D01*
G01Y-65320D02*
X913537Y-65737D01*
X913037Y-65987D01*
X912453Y-66070D01*
X911787Y-65903D01*
X911287Y-65487D01*
X910953Y-64987D01*
X910870Y-64403D01*
X910953Y-63820D01*
X911287Y-63320D01*
X911787Y-62903D01*
X912453Y-62737D01*
X913037Y-62820D01*
X913453Y-62987D01*
X913870Y-63320D01*
G01X916720Y-63820D02*
X919387D01*
X919137Y-63237D01*
X918720Y-62903D01*
X918137Y-62737D01*
X917553Y-62820D01*
X917053Y-63070D01*
X916720Y-63653D01*
X916553Y-64153D01*
Y-64653D01*
X916720Y-65153D01*
X917137Y-65653D01*
X917637Y-65987D01*
X918220Y-66070D01*
X918803Y-65903D01*
X919387Y-65403D01*
G01X922320Y-65487D02*
X922737Y-65820D01*
X923320Y-66070D01*
X923820D01*
X924320Y-65903D01*
X924653Y-65653D01*
X924820Y-65320D01*
X924737Y-64820D01*
X924403Y-64570D01*
X922903Y-64070D01*
X922570Y-63487D01*
X922737Y-63070D01*
X923070Y-62820D01*
X923570Y-62737D01*
X924070Y-62820D01*
X924570Y-63070D01*
G01X929170Y-62737D02*
Y-66070D01*
G01Y-61403D02*
X929003Y-61320D01*
Y-61153D01*
X929170Y-61070D01*
X929337Y-61153D01*
Y-61320D01*
X929170Y-61403D01*
G01X933603Y-67320D02*
X934187Y-67653D01*
X934853Y-67737D01*
X935437Y-67653D01*
X935937Y-67237D01*
X936270Y-66653D01*
Y-62737D01*
G01Y-63403D02*
X935937Y-63070D01*
X935437Y-62820D01*
X934853Y-62737D01*
X934187Y-62903D01*
X933770Y-63237D01*
X933437Y-63820D01*
X933270Y-64403D01*
X933353Y-64903D01*
X933687Y-65487D01*
X934187Y-65903D01*
X934853Y-66070D01*
X935353Y-65987D01*
X935937Y-65653D01*
X936270Y-65320D01*
G01X938953Y-66070D02*
Y-62737D01*
G01Y-63570D02*
X939287Y-63153D01*
X939787Y-62820D01*
X940453Y-62737D01*
X941037Y-62820D01*
X941537Y-63153D01*
X941787Y-63737D01*
Y-66070D01*
G01X945803Y-66987D02*
X946137Y-65903D01*
G01X955670Y-67737D02*
Y-62737D01*
G01Y-63487D02*
X956087Y-63070D01*
X956503Y-62820D01*
X957170Y-62737D01*
X957753Y-62820D01*
X958337Y-63237D01*
X958587Y-63820D01*
X958670Y-64403D01*
X958587Y-64987D01*
X958337Y-65570D01*
X957837Y-65903D01*
X957170Y-66070D01*
X956587Y-65987D01*
X956003Y-65737D01*
X955670Y-65403D01*
G01X962770Y-66070D02*
Y-61070D01*
G01X967120Y-63820D02*
X969787D01*
X969537Y-63237D01*
X969120Y-62903D01*
X968537Y-62737D01*
X967953Y-62820D01*
X967453Y-63070D01*
X967120Y-63653D01*
X966953Y-64153D01*
Y-64653D01*
X967120Y-65153D01*
X967537Y-65653D01*
X968037Y-65987D01*
X968620Y-66070D01*
X969203Y-65903D01*
X969787Y-65403D01*
G01X975470Y-66070D02*
Y-62737D01*
G01Y-63320D02*
X975137Y-62987D01*
X974637Y-62820D01*
X974053Y-62737D01*
X973470Y-62903D01*
X972970Y-63237D01*
X972637Y-63737D01*
X972470Y-64403D01*
X972637Y-65070D01*
X972970Y-65570D01*
X973470Y-65903D01*
X974053Y-66070D01*
X974637Y-65987D01*
X975137Y-65737D01*
X975470Y-65403D01*
G01X978320Y-65487D02*
X978737Y-65820D01*
X979320Y-66070D01*
X979820D01*
X980320Y-65903D01*
X980653Y-65653D01*
X980820Y-65320D01*
X980737Y-64820D01*
X980403Y-64570D01*
X978903Y-64070D01*
X978570Y-63487D01*
X978737Y-63070D01*
X979070Y-62820D01*
X979570Y-62737D01*
X980070Y-62820D01*
X980570Y-63070D01*
G01X983920Y-63820D02*
X986587D01*
X986337Y-63237D01*
X985920Y-62903D01*
X985337Y-62737D01*
X984753Y-62820D01*
X984253Y-63070D01*
X983920Y-63653D01*
X983753Y-64153D01*
Y-64653D01*
X983920Y-65153D01*
X984337Y-65653D01*
X984837Y-65987D01*
X985420Y-66070D01*
X986003Y-65903D01*
X986587Y-65403D01*
G01X995870Y-66070D02*
Y-61820D01*
X996037Y-61403D01*
X996370Y-61153D01*
X996870Y-61070D01*
X997370Y-61237D01*
X997620Y-61653D01*
G01X996620Y-63070D02*
X994953D01*
G01X1001970Y-66070D02*
X1001470Y-65987D01*
X1000970Y-65653D01*
X1000637Y-65070D01*
X1000470Y-64403D01*
X1000637Y-63737D01*
X1000970Y-63153D01*
X1001470Y-62820D01*
X1001970Y-62737D01*
X1002470Y-62820D01*
X1002970Y-63153D01*
X1003303Y-63737D01*
X1003387Y-64403D01*
X1003303Y-65070D01*
X1002970Y-65653D01*
X1002470Y-65987D01*
X1001970Y-66070D01*
G01X1007570D02*
Y-61070D01*
G01X1013170Y-66070D02*
Y-61070D01*
G01X1018770Y-66070D02*
X1018270Y-65987D01*
X1017770Y-65653D01*
X1017437Y-65070D01*
X1017270Y-64403D01*
X1017437Y-63737D01*
X1017770Y-63153D01*
X1018270Y-62820D01*
X1018770Y-62737D01*
X1019270Y-62820D01*
X1019770Y-63153D01*
X1020103Y-63737D01*
X1020187Y-64403D01*
X1020103Y-65070D01*
X1019770Y-65653D01*
X1019270Y-65987D01*
X1018770Y-66070D01*
G01X1022287Y-62737D02*
X1023287Y-66070D01*
X1024370Y-62737D01*
X1025453Y-66070D01*
X1026453Y-62737D01*
G01X1029970Y-66237D02*
X1029803Y-66153D01*
Y-65987D01*
X1029970Y-65903D01*
X1030137Y-65987D01*
Y-66153D01*
X1029970Y-66237D01*
G01X1040170Y-61070D02*
X1042170D01*
G01X1041170D02*
Y-66070D01*
G01X1040170D02*
X1042170D01*
G01X1046270D02*
Y-61820D01*
X1046437Y-61403D01*
X1046770Y-61153D01*
X1047270Y-61070D01*
X1047770Y-61237D01*
X1048020Y-61653D01*
G01X1047020Y-63070D02*
X1045353D01*
G01X1056553Y-66070D02*
Y-62737D01*
G01Y-63570D02*
X1056887Y-63153D01*
X1057387Y-62820D01*
X1058053Y-62737D01*
X1058637Y-62820D01*
X1059137Y-63153D01*
X1059387Y-63737D01*
Y-66070D01*
G01X1063570D02*
X1063070Y-65987D01*
X1062570Y-65653D01*
X1062237Y-65070D01*
X1062070Y-64403D01*
X1062237Y-63737D01*
X1062570Y-63153D01*
X1063070Y-62820D01*
X1063570Y-62737D01*
X1064070Y-62820D01*
X1064570Y-63153D01*
X1064903Y-63737D01*
X1064987Y-64403D01*
X1064903Y-65070D01*
X1064570Y-65653D01*
X1064070Y-65987D01*
X1063570Y-66070D01*
G01X1069170Y-61070D02*
Y-66070D01*
G01X1068003Y-62737D02*
X1070337D01*
G01X1074603Y-66987D02*
X1074937Y-65903D01*
G01X1084470Y-67737D02*
Y-62737D01*
G01Y-63487D02*
X1084887Y-63070D01*
X1085303Y-62820D01*
X1085970Y-62737D01*
X1086553Y-62820D01*
X1087137Y-63237D01*
X1087387Y-63820D01*
X1087470Y-64403D01*
X1087387Y-64987D01*
X1087137Y-65570D01*
X1086637Y-65903D01*
X1085970Y-66070D01*
X1085387Y-65987D01*
X1084803Y-65737D01*
X1084470Y-65403D01*
G01X1091570Y-66070D02*
Y-61070D01*
G01X1095920Y-63820D02*
X1098587D01*
X1098337Y-63237D01*
X1097920Y-62903D01*
X1097337Y-62737D01*
X1096753Y-62820D01*
X1096253Y-63070D01*
X1095920Y-63653D01*
X1095753Y-64153D01*
Y-64653D01*
X1095920Y-65153D01*
X1096337Y-65653D01*
X1096837Y-65987D01*
X1097420Y-66070D01*
X1098003Y-65903D01*
X1098587Y-65403D01*
G01X1104270Y-66070D02*
Y-62737D01*
G01Y-63320D02*
X1103937Y-62987D01*
X1103437Y-62820D01*
X1102853Y-62737D01*
X1102270Y-62903D01*
X1101770Y-63237D01*
X1101437Y-63737D01*
X1101270Y-64403D01*
X1101437Y-65070D01*
X1101770Y-65570D01*
X1102270Y-65903D01*
X1102853Y-66070D01*
X1103437Y-65987D01*
X1103937Y-65737D01*
X1104270Y-65403D01*
G01X1107120Y-65487D02*
X1107537Y-65820D01*
X1108120Y-66070D01*
X1108620D01*
X1109120Y-65903D01*
X1109453Y-65653D01*
X1109620Y-65320D01*
X1109537Y-64820D01*
X1109203Y-64570D01*
X1107703Y-64070D01*
X1107370Y-63487D01*
X1107537Y-63070D01*
X1107870Y-62820D01*
X1108370Y-62737D01*
X1108870Y-62820D01*
X1109370Y-63070D01*
G01X1112720Y-63820D02*
X1115387D01*
X1115137Y-63237D01*
X1114720Y-62903D01*
X1114137Y-62737D01*
X1113553Y-62820D01*
X1113053Y-63070D01*
X1112720Y-63653D01*
X1112553Y-64153D01*
Y-64653D01*
X1112720Y-65153D01*
X1113137Y-65653D01*
X1113637Y-65987D01*
X1114220Y-66070D01*
X1114803Y-65903D01*
X1115387Y-65403D01*
G01X1125170Y-62737D02*
Y-66070D01*
G01Y-61403D02*
X1125003Y-61320D01*
Y-61153D01*
X1125170Y-61070D01*
X1125337Y-61153D01*
Y-61320D01*
X1125170Y-61403D01*
G01X1132270Y-67737D02*
Y-62737D01*
G01Y-63487D02*
X1131853Y-63070D01*
X1131353Y-62820D01*
X1130770Y-62737D01*
X1130270Y-62820D01*
X1129687Y-63237D01*
X1129353Y-63820D01*
X1129270Y-64403D01*
X1129353Y-64987D01*
X1129687Y-65570D01*
X1130270Y-65987D01*
X1130770Y-66070D01*
X1131353Y-65987D01*
X1131853Y-65737D01*
X1132270Y-65320D01*
G01X1134953Y-66070D02*
Y-62737D01*
G01Y-63570D02*
X1135287Y-63153D01*
X1135787Y-62820D01*
X1136453Y-62737D01*
X1137037Y-62820D01*
X1137537Y-63153D01*
X1137787Y-63737D01*
Y-66070D01*
G01X1141970D02*
X1141470Y-65987D01*
X1140970Y-65653D01*
X1140637Y-65070D01*
X1140470Y-64403D01*
X1140637Y-63737D01*
X1140970Y-63153D01*
X1141470Y-62820D01*
X1141970Y-62737D01*
X1142470Y-62820D01*
X1142970Y-63153D01*
X1143303Y-63737D01*
X1143387Y-64403D01*
X1143303Y-65070D01*
X1142970Y-65653D01*
X1142470Y-65987D01*
X1141970Y-66070D01*
G01X1146403D02*
Y-62737D01*
G01Y-63403D02*
X1146820Y-63070D01*
X1147237Y-62820D01*
X1147820Y-62737D01*
X1148237Y-62820D01*
X1148737Y-63070D01*
G01X1151920Y-63820D02*
X1154587D01*
X1154337Y-63237D01*
X1153920Y-62903D01*
X1153337Y-62737D01*
X1152753Y-62820D01*
X1152253Y-63070D01*
X1151920Y-63653D01*
X1151753Y-64153D01*
Y-64653D01*
X1151920Y-65153D01*
X1152337Y-65653D01*
X1152837Y-65987D01*
X1153420Y-66070D01*
X1154003Y-65903D01*
X1154587Y-65403D01*
G01X1164370Y-61070D02*
Y-66070D01*
G01X1163203Y-62737D02*
X1165537D01*
G01X1168553Y-66070D02*
Y-61070D01*
G01Y-63487D02*
X1168970Y-63070D01*
X1169387Y-62820D01*
X1170053Y-62737D01*
X1170553Y-62820D01*
X1171137Y-63153D01*
X1171387Y-63653D01*
Y-66070D01*
G01X1175570Y-62737D02*
Y-66070D01*
G01Y-61403D02*
X1175403Y-61320D01*
Y-61153D01*
X1175570Y-61070D01*
X1175737Y-61153D01*
Y-61320D01*
X1175570Y-61403D01*
G01X1179920Y-65487D02*
X1180337Y-65820D01*
X1180920Y-66070D01*
X1181420D01*
X1181920Y-65903D01*
X1182253Y-65653D01*
X1182420Y-65320D01*
X1182337Y-64820D01*
X1182003Y-64570D01*
X1180503Y-64070D01*
X1180170Y-63487D01*
X1180337Y-63070D01*
X1180670Y-62820D01*
X1181170Y-62737D01*
X1181670Y-62820D01*
X1182170Y-63070D01*
G01X1191203Y-66070D02*
Y-62737D01*
G01Y-63403D02*
X1191620Y-63070D01*
X1192037Y-62820D01*
X1192620Y-62737D01*
X1193037Y-62820D01*
X1193537Y-63070D01*
G01X1196720Y-63820D02*
X1199387D01*
X1199137Y-63237D01*
X1198720Y-62903D01*
X1198137Y-62737D01*
X1197553Y-62820D01*
X1197053Y-63070D01*
X1196720Y-63653D01*
X1196553Y-64153D01*
Y-64653D01*
X1196720Y-65153D01*
X1197137Y-65653D01*
X1197637Y-65987D01*
X1198220Y-66070D01*
X1198803Y-65903D01*
X1199387Y-65403D01*
G01X1205070Y-67737D02*
Y-62737D01*
G01Y-63487D02*
X1204653Y-63070D01*
X1204153Y-62820D01*
X1203570Y-62737D01*
X1203070Y-62820D01*
X1202487Y-63237D01*
X1202153Y-63820D01*
X1202070Y-64403D01*
X1202153Y-64987D01*
X1202487Y-65570D01*
X1203070Y-65987D01*
X1203570Y-66070D01*
X1204153Y-65987D01*
X1204653Y-65737D01*
X1205070Y-65320D01*
G01X1207753Y-62737D02*
Y-65070D01*
X1208087Y-65653D01*
X1208587Y-65987D01*
X1209170Y-66070D01*
X1209753Y-65987D01*
X1210253Y-65653D01*
X1210587Y-65070D01*
G01Y-66070D02*
Y-62737D01*
G01X1213520Y-63820D02*
X1216187D01*
X1215937Y-63237D01*
X1215520Y-62903D01*
X1214937Y-62737D01*
X1214353Y-62820D01*
X1213853Y-63070D01*
X1213520Y-63653D01*
X1213353Y-64153D01*
Y-64653D01*
X1213520Y-65153D01*
X1213937Y-65653D01*
X1214437Y-65987D01*
X1215020Y-66070D01*
X1215603Y-65903D01*
X1216187Y-65403D01*
G01X1219120Y-65487D02*
X1219537Y-65820D01*
X1220120Y-66070D01*
X1220620D01*
X1221120Y-65903D01*
X1221453Y-65653D01*
X1221620Y-65320D01*
X1221537Y-64820D01*
X1221203Y-64570D01*
X1219703Y-64070D01*
X1219370Y-63487D01*
X1219537Y-63070D01*
X1219870Y-62820D01*
X1220370Y-62737D01*
X1220870Y-62820D01*
X1221370Y-63070D01*
G01X1225970Y-61070D02*
Y-66070D01*
G01X1224803Y-62737D02*
X1227137D01*
G01X1231570Y-66237D02*
X1231403Y-66153D01*
Y-65987D01*
X1231570Y-65903D01*
X1231737Y-65987D01*
Y-66153D01*
X1231570Y-66237D01*
G01X722667Y-38250D02*
X723167Y-38667D01*
X723750Y-38917D01*
X724500Y-39000D01*
X725250Y-38833D01*
X725833Y-38500D01*
X726250Y-37917D01*
X726333Y-37250D01*
X726167Y-36583D01*
X725750Y-36167D01*
X725167Y-35833D01*
X724583Y-35750D01*
X724000Y-35833D01*
X723250Y-36167D01*
X723500Y-34000D01*
X725750D01*
G01X730100Y-39167D02*
X729933Y-39083D01*
Y-38917D01*
X730100Y-38833D01*
X730267Y-38917D01*
Y-39083D01*
X730100Y-39167D01*
G01X739633Y-39000D02*
Y-34000D01*
X741717D01*
X742383Y-34250D01*
X742800Y-34583D01*
X742967Y-35250D01*
X742800Y-35917D01*
X742300Y-36333D01*
X741717Y-36583D01*
X739633D01*
G01X741717D02*
X742967Y-39000D01*
G01X745650Y-36750D02*
X748317D01*
X748067Y-36167D01*
X747650Y-35833D01*
X747067Y-35667D01*
X746483Y-35750D01*
X745983Y-36000D01*
X745650Y-36583D01*
X745483Y-37083D01*
Y-37583D01*
X745650Y-38083D01*
X746067Y-38583D01*
X746567Y-38917D01*
X747150Y-39000D01*
X747733Y-38833D01*
X748317Y-38333D01*
G01X750000Y-39000D02*
Y-35667D01*
G01Y-36583D02*
X750250Y-36167D01*
X750667Y-35833D01*
X751250Y-35667D01*
X751833Y-35833D01*
X752250Y-36167D01*
X752500Y-36583D01*
Y-39000D01*
G01Y-36583D02*
X752750Y-36167D01*
X753167Y-35833D01*
X753750Y-35667D01*
X754333Y-35833D01*
X754750Y-36167D01*
X755000Y-36667D01*
Y-39000D01*
G01X759600D02*
Y-35667D01*
G01Y-36250D02*
X759267Y-35917D01*
X758767Y-35750D01*
X758183Y-35667D01*
X757600Y-35833D01*
X757100Y-36167D01*
X756767Y-36667D01*
X756600Y-37333D01*
X756767Y-38000D01*
X757100Y-38500D01*
X757600Y-38833D01*
X758183Y-39000D01*
X758767Y-38917D01*
X759267Y-38667D01*
X759600Y-38333D01*
G01X762533Y-39000D02*
Y-35667D01*
G01Y-36333D02*
X762950Y-36000D01*
X763367Y-35750D01*
X763950Y-35667D01*
X764367Y-35750D01*
X764867Y-36000D01*
G01X767883Y-39000D02*
Y-34000D01*
G01X770550Y-35667D02*
X767883Y-37583D01*
G01X768967Y-36833D02*
X770717Y-39000D01*
G01X773067Y-39167D02*
X776733Y-35500D01*
G01X774900Y-34833D02*
Y-39833D01*
G01X776733Y-39167D02*
X773067Y-35500D01*
G01X772400Y-37333D02*
X777400D01*
G01X713000Y-53000D02*
X1343000D01*
G01X713000Y-23000D02*
X1343000D01*
G01X713000Y85500D02*
X1343000D01*
G01X725500Y349500D02*
Y354500D01*
X722417Y350917D01*
X726583D01*
G01X730100Y349333D02*
X729933Y349417D01*
Y349583D01*
X730100Y349667D01*
X730267Y349583D01*
Y349417D01*
X730100Y349333D01*
G01X739800Y349500D02*
Y354500D01*
G01Y352000D02*
X740217Y352500D01*
X740717Y352750D01*
X741217Y352833D01*
X741967Y352667D01*
X742467Y352333D01*
X742800Y351750D01*
Y351083D01*
X742633Y350417D01*
X742300Y349917D01*
X741717Y349583D01*
X741217Y349500D01*
X740717Y349583D01*
X740217Y349833D01*
X739800Y350250D01*
G01X748400Y349500D02*
Y352833D01*
G01Y352250D02*
X748067Y352583D01*
X747567Y352750D01*
X746983Y352833D01*
X746400Y352667D01*
X745900Y352333D01*
X745567Y351833D01*
X745400Y351167D01*
X745567Y350500D01*
X745900Y350000D01*
X746400Y349667D01*
X746983Y349500D01*
X747567Y349583D01*
X748067Y349833D01*
X748400Y350167D01*
G01X753833Y352417D02*
X753250Y352750D01*
X752750Y352833D01*
X752083Y352667D01*
X751583Y352333D01*
X751250Y351750D01*
X751167Y351167D01*
X751250Y350583D01*
X751583Y350083D01*
X752083Y349667D01*
X752750Y349500D01*
X753333Y349667D01*
X753833Y350000D01*
G01X756683Y349500D02*
Y354500D01*
G01X759350Y352833D02*
X756683Y350917D01*
G01X757767Y351667D02*
X759517Y349500D01*
G01X765200Y354500D02*
Y349500D01*
G01Y350250D02*
X764867Y349833D01*
X764367Y349583D01*
X763783Y349500D01*
X763117Y349667D01*
X762617Y350083D01*
X762283Y350583D01*
X762200Y351167D01*
X762283Y351750D01*
X762617Y352250D01*
X763117Y352667D01*
X763783Y352833D01*
X764367Y352750D01*
X764783Y352583D01*
X765200Y352250D01*
G01X768133Y349500D02*
Y352833D01*
G01Y352167D02*
X768550Y352500D01*
X768967Y352750D01*
X769550Y352833D01*
X769967Y352750D01*
X770467Y352500D01*
G01X774900Y352833D02*
Y349500D01*
G01Y354167D02*
X774733Y354250D01*
Y354417D01*
X774900Y354500D01*
X775067Y354417D01*
Y354250D01*
X774900Y354167D01*
G01X780500Y349500D02*
Y354500D01*
G01X786100Y349500D02*
Y354500D01*
G01X798800Y349500D02*
Y352833D01*
G01Y352250D02*
X798467Y352583D01*
X797967Y352750D01*
X797383Y352833D01*
X796800Y352667D01*
X796300Y352333D01*
X795967Y351833D01*
X795800Y351167D01*
X795967Y350500D01*
X796300Y350000D01*
X796800Y349667D01*
X797383Y349500D01*
X797967Y349583D01*
X798467Y349833D01*
X798800Y350167D01*
G01X801483Y349500D02*
Y352833D01*
G01Y352000D02*
X801817Y352417D01*
X802317Y352750D01*
X802983Y352833D01*
X803567Y352750D01*
X804067Y352417D01*
X804317Y351833D01*
Y349500D01*
G01X810000Y354500D02*
Y349500D01*
G01Y350250D02*
X809667Y349833D01*
X809167Y349583D01*
X808583Y349500D01*
X807917Y349667D01*
X807417Y350083D01*
X807083Y350583D01*
X807000Y351167D01*
X807083Y351750D01*
X807417Y352250D01*
X807917Y352667D01*
X808583Y352833D01*
X809167Y352750D01*
X809583Y352583D01*
X810000Y352250D01*
G01X818450Y350083D02*
X818867Y349750D01*
X819450Y349500D01*
X819950D01*
X820450Y349667D01*
X820783Y349917D01*
X820950Y350250D01*
X820867Y350750D01*
X820533Y351000D01*
X819033Y351500D01*
X818700Y352083D01*
X818867Y352500D01*
X819200Y352750D01*
X819700Y352833D01*
X820200Y352750D01*
X820700Y352500D01*
G01X826800Y347833D02*
Y352833D01*
G01Y352083D02*
X826383Y352500D01*
X825883Y352750D01*
X825300Y352833D01*
X824800Y352750D01*
X824217Y352333D01*
X823883Y351750D01*
X823800Y351167D01*
X823883Y350583D01*
X824217Y350000D01*
X824800Y349583D01*
X825300Y349500D01*
X825883Y349583D01*
X826383Y349833D01*
X826800Y350250D01*
G01X829483Y352833D02*
Y350500D01*
X829817Y349917D01*
X830317Y349583D01*
X830900Y349500D01*
X831483Y349583D01*
X831983Y349917D01*
X832317Y350500D01*
G01Y349500D02*
Y352833D01*
G01X838000Y349500D02*
Y352833D01*
G01Y352250D02*
X837667Y352583D01*
X837167Y352750D01*
X836583Y352833D01*
X836000Y352667D01*
X835500Y352333D01*
X835167Y351833D01*
X835000Y351167D01*
X835167Y350500D01*
X835500Y350000D01*
X836000Y349667D01*
X836583Y349500D01*
X837167Y349583D01*
X837667Y349833D01*
X838000Y350167D01*
G01X840933Y349500D02*
Y352833D01*
G01Y352167D02*
X841350Y352500D01*
X841767Y352750D01*
X842350Y352833D01*
X842767Y352750D01*
X843267Y352500D01*
G01X846450Y351750D02*
X849117D01*
X848867Y352333D01*
X848450Y352667D01*
X847867Y352833D01*
X847283Y352750D01*
X846783Y352500D01*
X846450Y351917D01*
X846283Y351417D01*
Y350917D01*
X846450Y350417D01*
X846867Y349917D01*
X847367Y349583D01*
X847950Y349500D01*
X848533Y349667D01*
X849117Y350167D01*
G01X857483Y349500D02*
Y354500D01*
G01Y352083D02*
X857900Y352500D01*
X858317Y352750D01*
X858983Y352833D01*
X859483Y352750D01*
X860067Y352417D01*
X860317Y351917D01*
Y349500D01*
G01X864500D02*
X864000Y349583D01*
X863500Y349917D01*
X863167Y350500D01*
X863000Y351167D01*
X863167Y351833D01*
X863500Y352417D01*
X864000Y352750D01*
X864500Y352833D01*
X865000Y352750D01*
X865500Y352417D01*
X865833Y351833D01*
X865917Y351167D01*
X865833Y350500D01*
X865500Y349917D01*
X865000Y349583D01*
X864500Y349500D01*
G01X870100D02*
Y354500D01*
G01X874450Y351750D02*
X877117D01*
X876867Y352333D01*
X876450Y352667D01*
X875867Y352833D01*
X875283Y352750D01*
X874783Y352500D01*
X874450Y351917D01*
X874283Y351417D01*
Y350917D01*
X874450Y350417D01*
X874867Y349917D01*
X875367Y349583D01*
X875950Y349500D01*
X876533Y349667D01*
X877117Y350167D01*
G01X881300Y349333D02*
X881133Y349417D01*
Y349583D01*
X881300Y349667D01*
X881467Y349583D01*
Y349417D01*
X881300Y349333D01*
G01Y351583D02*
X881133Y351667D01*
Y351833D01*
X881300Y351917D01*
X881467Y351833D01*
Y351667D01*
X881300Y351583D01*
G01X713000Y335500D02*
X1343000D01*
G01X721407Y374673D02*
X725073Y378340D01*
G01X723240Y379007D02*
Y374007D01*
G01X725073Y374673D02*
X721407Y378340D01*
G01X720740Y376507D02*
X725740D01*
G01X728423Y373173D02*
X727590Y374007D01*
X727173Y374840D01*
Y378173D01*
X727590Y379007D01*
X728423Y379840D01*
G01X732607Y375590D02*
X733107Y375173D01*
X733690Y374923D01*
X734440Y374840D01*
X735190Y375007D01*
X735773Y375340D01*
X736190Y375923D01*
X736273Y376590D01*
X736107Y377257D01*
X735690Y377673D01*
X735107Y378007D01*
X734523Y378090D01*
X733940Y378007D01*
X733190Y377673D01*
X733440Y379840D01*
X735690D01*
G01X740040Y374673D02*
X739873Y374757D01*
Y374923D01*
X740040Y375007D01*
X740207Y374923D01*
Y374757D01*
X740040Y374673D01*
G01X745640Y374840D02*
Y379840D01*
X744640Y378840D01*
G01Y374840D02*
X746640D01*
G01X751657Y373173D02*
X752490Y374007D01*
X752907Y374840D01*
Y378173D01*
X752490Y379007D01*
X751657Y379840D01*
G01X721107Y408303D02*
X724773Y411970D01*
G01X722940Y412637D02*
Y407637D01*
G01X724773Y408303D02*
X721107Y411970D01*
G01X720440Y410137D02*
X725440D01*
G01X728123Y406803D02*
X727290Y407637D01*
X726873Y408470D01*
Y411803D01*
X727290Y412637D01*
X728123Y413470D01*
G01X732307Y409220D02*
X732807Y408803D01*
X733390Y408553D01*
X734140Y408470D01*
X734890Y408637D01*
X735473Y408970D01*
X735890Y409553D01*
X735973Y410220D01*
X735807Y410887D01*
X735390Y411303D01*
X734807Y411637D01*
X734223Y411720D01*
X733640Y411637D01*
X732890Y411303D01*
X733140Y413470D01*
X735390D01*
G01X739740Y408303D02*
X739573Y408387D01*
Y408553D01*
X739740Y408637D01*
X739907Y408553D01*
Y408387D01*
X739740Y408303D01*
G01X745340Y408470D02*
Y413470D01*
X744340Y412470D01*
G01Y408470D02*
X746340D01*
G01X751357Y406803D02*
X752190Y407637D01*
X752607Y408470D01*
Y411803D01*
X752190Y412637D01*
X751357Y413470D01*
G01X721217Y391740D02*
X723300Y386740D01*
X725383Y391740D01*
G01X728900Y390073D02*
Y386740D01*
G01Y391407D02*
X728733Y391490D01*
Y391657D01*
X728900Y391740D01*
X729067Y391657D01*
Y391490D01*
X728900Y391407D01*
G01X736000Y386740D02*
Y390073D01*
G01Y389490D02*
X735667Y389823D01*
X735167Y389990D01*
X734583Y390073D01*
X734000Y389907D01*
X733500Y389573D01*
X733167Y389073D01*
X733000Y388407D01*
X733167Y387740D01*
X733500Y387240D01*
X734000Y386907D01*
X734583Y386740D01*
X735167Y386823D01*
X735667Y387073D01*
X736000Y387407D01*
G01X744700Y391740D02*
X746700D01*
G01X745700D02*
Y386740D01*
G01X744700D02*
X746700D01*
G01X749883D02*
Y390073D01*
G01Y389240D02*
X750217Y389657D01*
X750717Y389990D01*
X751383Y390073D01*
X751967Y389990D01*
X752467Y389657D01*
X752717Y389073D01*
Y386740D01*
G01X760833D02*
Y391740D01*
X762833D01*
X763500Y391490D01*
X764000Y390907D01*
X764167Y390240D01*
X764000Y389573D01*
X763583Y389073D01*
X762833Y388823D01*
X760833D01*
G01X769600Y386740D02*
Y390073D01*
G01Y389490D02*
X769267Y389823D01*
X768767Y389990D01*
X768183Y390073D01*
X767600Y389907D01*
X767100Y389573D01*
X766767Y389073D01*
X766600Y388407D01*
X766767Y387740D01*
X767100Y387240D01*
X767600Y386907D01*
X768183Y386740D01*
X768767Y386823D01*
X769267Y387073D01*
X769600Y387407D01*
G01X775200Y391740D02*
Y386740D01*
G01Y387490D02*
X774867Y387073D01*
X774367Y386823D01*
X773783Y386740D01*
X773117Y386907D01*
X772617Y387323D01*
X772283Y387823D01*
X772200Y388407D01*
X772283Y388990D01*
X772617Y389490D01*
X773117Y389907D01*
X773783Y390073D01*
X774367Y389990D01*
X774783Y389823D01*
X775200Y389490D01*
G01X778883Y385073D02*
X778050Y385907D01*
X777633Y386740D01*
Y390073D01*
X778050Y390907D01*
X778883Y391740D01*
G01X782817D02*
X784900Y386740D01*
X786983Y391740D01*
G01X789500D02*
X791500D01*
G01X790500D02*
Y386740D01*
G01X789500D02*
X791500D01*
G01X794433D02*
Y391740D01*
X796433D01*
X797100Y391490D01*
X797600Y390907D01*
X797767Y390240D01*
X797600Y389573D01*
X797183Y389073D01*
X796433Y388823D01*
X794433D01*
G01X802117Y385073D02*
X802950Y385907D01*
X803367Y386740D01*
Y390073D01*
X802950Y390907D01*
X802117Y391740D01*
G01X720917Y424500D02*
X723000Y419500D01*
X725083Y424500D01*
G01X728600Y422833D02*
Y419500D01*
G01Y424167D02*
X728433Y424250D01*
Y424417D01*
X728600Y424500D01*
X728767Y424417D01*
Y424250D01*
X728600Y424167D01*
G01X735700Y419500D02*
Y422833D01*
G01Y422250D02*
X735367Y422583D01*
X734867Y422750D01*
X734283Y422833D01*
X733700Y422667D01*
X733200Y422333D01*
X732867Y421833D01*
X732700Y421167D01*
X732867Y420500D01*
X733200Y420000D01*
X733700Y419667D01*
X734283Y419500D01*
X734867Y419583D01*
X735367Y419833D01*
X735700Y420167D01*
G01X745400Y419500D02*
X744733Y419583D01*
X744150Y419917D01*
X743650Y420417D01*
X743317Y421000D01*
X743150Y421667D01*
Y422333D01*
X743317Y423000D01*
X743650Y423583D01*
X744150Y424083D01*
X744733Y424417D01*
X745400Y424500D01*
X746067Y424417D01*
X746650Y424083D01*
X747150Y423583D01*
X747483Y423000D01*
X747650Y422333D01*
Y421667D01*
X747483Y421000D01*
X747150Y420417D01*
X746650Y419917D01*
X746067Y419583D01*
X745400Y419500D01*
G01X749583D02*
Y422833D01*
G01Y422000D02*
X749917Y422417D01*
X750417Y422750D01*
X751083Y422833D01*
X751667Y422750D01*
X752167Y422417D01*
X752417Y421833D01*
Y419500D01*
G01X760533D02*
Y424500D01*
X762533D01*
X763200Y424250D01*
X763700Y423667D01*
X763867Y423000D01*
X763700Y422333D01*
X763283Y421833D01*
X762533Y421583D01*
X760533D01*
G01X769300Y419500D02*
Y422833D01*
G01Y422250D02*
X768967Y422583D01*
X768467Y422750D01*
X767883Y422833D01*
X767300Y422667D01*
X766800Y422333D01*
X766467Y421833D01*
X766300Y421167D01*
X766467Y420500D01*
X766800Y420000D01*
X767300Y419667D01*
X767883Y419500D01*
X768467Y419583D01*
X768967Y419833D01*
X769300Y420167D01*
G01X774900Y424500D02*
Y419500D01*
G01Y420250D02*
X774567Y419833D01*
X774067Y419583D01*
X773483Y419500D01*
X772817Y419667D01*
X772317Y420083D01*
X771983Y420583D01*
X771900Y421167D01*
X771983Y421750D01*
X772317Y422250D01*
X772817Y422667D01*
X773483Y422833D01*
X774067Y422750D01*
X774483Y422583D01*
X774900Y422250D01*
G01X778583Y417833D02*
X777750Y418667D01*
X777333Y419500D01*
Y422833D01*
X777750Y423667D01*
X778583Y424500D01*
G01X782517D02*
X784600Y419500D01*
X786683Y424500D01*
G01X790200Y419500D02*
X789533Y419583D01*
X788950Y419917D01*
X788450Y420417D01*
X788117Y421000D01*
X787950Y421667D01*
Y422333D01*
X788117Y423000D01*
X788450Y423583D01*
X788950Y424083D01*
X789533Y424417D01*
X790200Y424500D01*
X790867Y424417D01*
X791450Y424083D01*
X791950Y423583D01*
X792283Y423000D01*
X792450Y422333D01*
Y421667D01*
X792283Y421000D01*
X791950Y420417D01*
X791450Y419917D01*
X790867Y419583D01*
X790200Y419500D01*
G01X794133D02*
Y424500D01*
X796133D01*
X796800Y424250D01*
X797300Y423667D01*
X797467Y423000D01*
X797300Y422333D01*
X796883Y421833D01*
X796133Y421583D01*
X794133D01*
G01X801817Y417833D02*
X802650Y418667D01*
X803067Y419500D01*
Y422833D01*
X802650Y423667D01*
X801817Y424500D01*
G01X713000Y365500D02*
X1343000D01*
G01X713000Y400500D02*
X1343000D01*
G01X723667Y443167D02*
X724000Y443417D01*
X724250Y443833D01*
X724417Y444417D01*
X724250Y444917D01*
X723917Y445250D01*
X723333Y445500D01*
X721083D01*
Y440500D01*
X723833D01*
X724417Y440833D01*
X724750Y441333D01*
X724917Y441917D01*
X724750Y442500D01*
X724250Y443000D01*
X723667Y443167D01*
X721083D01*
G01X727183Y443833D02*
Y441500D01*
X727517Y440917D01*
X728017Y440583D01*
X728600Y440500D01*
X729183Y440583D01*
X729683Y440917D01*
X730017Y441500D01*
G01Y440500D02*
Y443833D01*
G01X733033Y440500D02*
Y443833D01*
G01Y443167D02*
X733450Y443500D01*
X733867Y443750D01*
X734450Y443833D01*
X734867Y443750D01*
X735367Y443500D01*
G01X739800Y443833D02*
Y440500D01*
G01Y445167D02*
X739633Y445250D01*
Y445417D01*
X739800Y445500D01*
X739967Y445417D01*
Y445250D01*
X739800Y445167D01*
G01X744150Y442750D02*
X746817D01*
X746567Y443333D01*
X746150Y443667D01*
X745567Y443833D01*
X744983Y443750D01*
X744483Y443500D01*
X744150Y442917D01*
X743983Y442417D01*
Y441917D01*
X744150Y441417D01*
X744567Y440917D01*
X745067Y440583D01*
X745650Y440500D01*
X746233Y440667D01*
X746817Y441167D01*
G01X752500Y445500D02*
Y440500D01*
G01Y441250D02*
X752167Y440833D01*
X751667Y440583D01*
X751083Y440500D01*
X750417Y440667D01*
X749917Y441083D01*
X749583Y441583D01*
X749500Y442167D01*
X749583Y442750D01*
X749917Y443250D01*
X750417Y443667D01*
X751083Y443833D01*
X751667Y443750D01*
X752083Y443583D01*
X752500Y443250D01*
G01X760783Y440500D02*
Y445500D01*
G01Y443083D02*
X761200Y443500D01*
X761617Y443750D01*
X762283Y443833D01*
X762783Y443750D01*
X763367Y443417D01*
X763617Y442917D01*
Y440500D01*
G01X767800D02*
X767300Y440583D01*
X766800Y440917D01*
X766467Y441500D01*
X766300Y442167D01*
X766467Y442833D01*
X766800Y443417D01*
X767300Y443750D01*
X767800Y443833D01*
X768300Y443750D01*
X768800Y443417D01*
X769133Y442833D01*
X769217Y442167D01*
X769133Y441500D01*
X768800Y440917D01*
X768300Y440583D01*
X767800Y440500D01*
G01X773400D02*
Y445500D01*
G01X777750Y442750D02*
X780417D01*
X780167Y443333D01*
X779750Y443667D01*
X779167Y443833D01*
X778583Y443750D01*
X778083Y443500D01*
X777750Y442917D01*
X777583Y442417D01*
Y441917D01*
X777750Y441417D01*
X778167Y440917D01*
X778667Y440583D01*
X779250Y440500D01*
X779833Y440667D01*
X780417Y441167D01*
G01X721417Y461500D02*
Y466500D01*
X724583D01*
G01X723417Y464083D02*
X721417D01*
G01X727183Y464833D02*
Y462500D01*
X727517Y461917D01*
X728017Y461583D01*
X728600Y461500D01*
X729183Y461583D01*
X729683Y461917D01*
X730017Y462500D01*
G01Y461500D02*
Y464833D01*
G01X734200Y461500D02*
Y466500D01*
G01X739800Y461500D02*
Y466500D01*
G01X749500Y459833D02*
Y464833D01*
G01Y464083D02*
X749917Y464500D01*
X750333Y464750D01*
X751000Y464833D01*
X751583Y464750D01*
X752167Y464333D01*
X752417Y463750D01*
X752500Y463167D01*
X752417Y462583D01*
X752167Y462000D01*
X751667Y461667D01*
X751000Y461500D01*
X750417Y461583D01*
X749833Y461833D01*
X749500Y462167D01*
G01X756600Y461500D02*
Y466500D01*
G01X760783Y464833D02*
Y462500D01*
X761117Y461917D01*
X761617Y461583D01*
X762200Y461500D01*
X762783Y461583D01*
X763283Y461917D01*
X763617Y462500D01*
G01Y461500D02*
Y464833D01*
G01X766633Y460250D02*
X767217Y459917D01*
X767883Y459833D01*
X768467Y459917D01*
X768967Y460333D01*
X769300Y460917D01*
Y464833D01*
G01Y464167D02*
X768967Y464500D01*
X768467Y464750D01*
X767883Y464833D01*
X767217Y464667D01*
X766800Y464333D01*
X766467Y463750D01*
X766300Y463167D01*
X766383Y462667D01*
X766717Y462083D01*
X767217Y461667D01*
X767883Y461500D01*
X768383Y461583D01*
X768967Y461917D01*
X769300Y462250D01*
G01X772233Y460250D02*
X772817Y459917D01*
X773483Y459833D01*
X774067Y459917D01*
X774567Y460333D01*
X774900Y460917D01*
Y464833D01*
G01Y464167D02*
X774567Y464500D01*
X774067Y464750D01*
X773483Y464833D01*
X772817Y464667D01*
X772400Y464333D01*
X772067Y463750D01*
X771900Y463167D01*
X771983Y462667D01*
X772317Y462083D01*
X772817Y461667D01*
X773483Y461500D01*
X773983Y461583D01*
X774567Y461917D01*
X774900Y462250D01*
G01X779000Y464833D02*
Y461500D01*
G01Y466167D02*
X778833Y466250D01*
Y466417D01*
X779000Y466500D01*
X779167Y466417D01*
Y466250D01*
X779000Y466167D01*
G01X783183Y461500D02*
Y464833D01*
G01Y464000D02*
X783517Y464417D01*
X784017Y464750D01*
X784683Y464833D01*
X785267Y464750D01*
X785767Y464417D01*
X786017Y463833D01*
Y461500D01*
G01X789033Y460250D02*
X789617Y459917D01*
X790283Y459833D01*
X790867Y459917D01*
X791367Y460333D01*
X791700Y460917D01*
Y464833D01*
G01Y464167D02*
X791367Y464500D01*
X790867Y464750D01*
X790283Y464833D01*
X789617Y464667D01*
X789200Y464333D01*
X788867Y463750D01*
X788700Y463167D01*
X788783Y462667D01*
X789117Y462083D01*
X789617Y461667D01*
X790283Y461500D01*
X790783Y461583D01*
X791367Y461917D01*
X791700Y462250D01*
G01X713000Y435500D02*
X1343000D01*
G01X713000Y450500D02*
X1343000D01*
G01X713000Y477500D02*
X1343000D01*
G01X721250Y530000D02*
Y535000D01*
G01X724750D02*
Y530000D01*
G01Y532500D02*
X721250D01*
G01X730100Y530000D02*
Y533333D01*
G01Y532750D02*
X729767Y533083D01*
X729267Y533250D01*
X728683Y533333D01*
X728100Y533167D01*
X727600Y532833D01*
X727267Y532333D01*
X727100Y531667D01*
X727267Y531000D01*
X727600Y530500D01*
X728100Y530167D01*
X728683Y530000D01*
X729267Y530083D01*
X729767Y530333D01*
X730100Y530667D01*
G01X734200Y530000D02*
Y535000D01*
G01X739300Y530000D02*
Y534250D01*
X739467Y534667D01*
X739800Y534917D01*
X740300Y535000D01*
X740800Y534833D01*
X741050Y534417D01*
G01X740050Y533000D02*
X738383D01*
G01X749333Y530000D02*
Y535000D01*
X751333D01*
X752000Y534750D01*
X752500Y534167D01*
X752667Y533500D01*
X752500Y532833D01*
X752083Y532333D01*
X751333Y532083D01*
X749333D01*
G01X756600Y530000D02*
Y535000D01*
G01X760783Y533333D02*
Y531000D01*
X761117Y530417D01*
X761617Y530083D01*
X762200Y530000D01*
X762783Y530083D01*
X763283Y530417D01*
X763617Y531000D01*
G01Y530000D02*
Y533333D01*
G01X766633Y528750D02*
X767217Y528417D01*
X767883Y528333D01*
X768467Y528417D01*
X768967Y528833D01*
X769300Y529417D01*
Y533333D01*
G01Y532667D02*
X768967Y533000D01*
X768467Y533250D01*
X767883Y533333D01*
X767217Y533167D01*
X766800Y532833D01*
X766467Y532250D01*
X766300Y531667D01*
X766383Y531167D01*
X766717Y530583D01*
X767217Y530167D01*
X767883Y530000D01*
X768383Y530083D01*
X768967Y530417D01*
X769300Y530750D01*
G01X772233Y528750D02*
X772817Y528417D01*
X773483Y528333D01*
X774067Y528417D01*
X774567Y528833D01*
X774900Y529417D01*
Y533333D01*
G01Y532667D02*
X774567Y533000D01*
X774067Y533250D01*
X773483Y533333D01*
X772817Y533167D01*
X772400Y532833D01*
X772067Y532250D01*
X771900Y531667D01*
X771983Y531167D01*
X772317Y530583D01*
X772817Y530167D01*
X773483Y530000D01*
X773983Y530083D01*
X774567Y530417D01*
X774900Y530750D01*
G01X779000Y533333D02*
Y530000D01*
G01Y534667D02*
X778833Y534750D01*
Y534917D01*
X779000Y535000D01*
X779167Y534917D01*
Y534750D01*
X779000Y534667D01*
G01X783183Y530000D02*
Y533333D01*
G01Y532500D02*
X783517Y532917D01*
X784017Y533250D01*
X784683Y533333D01*
X785267Y533250D01*
X785767Y532917D01*
X786017Y532333D01*
Y530000D01*
G01X789033Y528750D02*
X789617Y528417D01*
X790283Y528333D01*
X790867Y528417D01*
X791367Y528833D01*
X791700Y529417D01*
Y533333D01*
G01Y532667D02*
X791367Y533000D01*
X790867Y533250D01*
X790283Y533333D01*
X789617Y533167D01*
X789200Y532833D01*
X788867Y532250D01*
X788700Y531667D01*
X788783Y531167D01*
X789117Y530583D01*
X789617Y530167D01*
X790283Y530000D01*
X790783Y530083D01*
X791367Y530417D01*
X791700Y530750D01*
G01X722833Y589000D02*
Y594000D01*
X724833D01*
X725500Y593750D01*
X726000Y593167D01*
X726167Y592500D01*
X726000Y591833D01*
X725583Y591333D01*
X724833Y591083D01*
X722833D01*
G01X730100Y589000D02*
Y594000D01*
G01X734283Y592333D02*
Y590000D01*
X734617Y589417D01*
X735117Y589083D01*
X735700Y589000D01*
X736283Y589083D01*
X736783Y589417D01*
X737117Y590000D01*
G01Y589000D02*
Y592333D01*
G01X740133Y587750D02*
X740717Y587417D01*
X741383Y587333D01*
X741967Y587417D01*
X742467Y587833D01*
X742800Y588417D01*
Y592333D01*
G01Y591667D02*
X742467Y592000D01*
X741967Y592250D01*
X741383Y592333D01*
X740717Y592167D01*
X740300Y591833D01*
X739967Y591250D01*
X739800Y590667D01*
X739883Y590167D01*
X740217Y589583D01*
X740717Y589167D01*
X741383Y589000D01*
X741883Y589083D01*
X742467Y589417D01*
X742800Y589750D01*
G01X745733Y587750D02*
X746317Y587417D01*
X746983Y587333D01*
X747567Y587417D01*
X748067Y587833D01*
X748400Y588417D01*
Y592333D01*
G01Y591667D02*
X748067Y592000D01*
X747567Y592250D01*
X746983Y592333D01*
X746317Y592167D01*
X745900Y591833D01*
X745567Y591250D01*
X745400Y590667D01*
X745483Y590167D01*
X745817Y589583D01*
X746317Y589167D01*
X746983Y589000D01*
X747483Y589083D01*
X748067Y589417D01*
X748400Y589750D01*
G01X752500Y592333D02*
Y589000D01*
G01Y593667D02*
X752333Y593750D01*
Y593917D01*
X752500Y594000D01*
X752667Y593917D01*
Y593750D01*
X752500Y593667D01*
G01X756683Y589000D02*
Y592333D01*
G01Y591500D02*
X757017Y591917D01*
X757517Y592250D01*
X758183Y592333D01*
X758767Y592250D01*
X759267Y591917D01*
X759517Y591333D01*
Y589000D01*
G01X762533Y587750D02*
X763117Y587417D01*
X763783Y587333D01*
X764367Y587417D01*
X764867Y587833D01*
X765200Y588417D01*
Y592333D01*
G01Y591667D02*
X764867Y592000D01*
X764367Y592250D01*
X763783Y592333D01*
X763117Y592167D01*
X762700Y591833D01*
X762367Y591250D01*
X762200Y590667D01*
X762283Y590167D01*
X762617Y589583D01*
X763117Y589167D01*
X763783Y589000D01*
X764283Y589083D01*
X764867Y589417D01*
X765200Y589750D01*
G01X776400Y594000D02*
Y589000D01*
G01Y589750D02*
X776067Y589333D01*
X775567Y589083D01*
X774983Y589000D01*
X774317Y589167D01*
X773817Y589583D01*
X773483Y590083D01*
X773400Y590667D01*
X773483Y591250D01*
X773817Y591750D01*
X774317Y592167D01*
X774983Y592333D01*
X775567Y592250D01*
X775983Y592083D01*
X776400Y591750D01*
G01X779250Y591250D02*
X781917D01*
X781667Y591833D01*
X781250Y592167D01*
X780667Y592333D01*
X780083Y592250D01*
X779583Y592000D01*
X779250Y591417D01*
X779083Y590917D01*
Y590417D01*
X779250Y589917D01*
X779667Y589417D01*
X780167Y589083D01*
X780750Y589000D01*
X781333Y589167D01*
X781917Y589667D01*
G01X785600Y589000D02*
Y593250D01*
X785767Y593667D01*
X786100Y593917D01*
X786600Y594000D01*
X787100Y593833D01*
X787350Y593417D01*
G01X786350Y592000D02*
X784683D01*
G01X791700Y592333D02*
Y589000D01*
G01Y593667D02*
X791533Y593750D01*
Y593917D01*
X791700Y594000D01*
X791867Y593917D01*
Y593750D01*
X791700Y593667D01*
G01X795883Y589000D02*
Y592333D01*
G01Y591500D02*
X796217Y591917D01*
X796717Y592250D01*
X797383Y592333D01*
X797967Y592250D01*
X798467Y591917D01*
X798717Y591333D01*
Y589000D01*
G01X801650Y591250D02*
X804317D01*
X804067Y591833D01*
X803650Y592167D01*
X803067Y592333D01*
X802483Y592250D01*
X801983Y592000D01*
X801650Y591417D01*
X801483Y590917D01*
Y590417D01*
X801650Y589917D01*
X802067Y589417D01*
X802567Y589083D01*
X803150Y589000D01*
X803733Y589167D01*
X804317Y589667D01*
G01X713000Y579500D02*
X1343000D01*
G01X713000Y604500D02*
X1343000D01*
G01X722667Y765000D02*
X723167Y764417D01*
X723833Y764083D01*
X724583Y764000D01*
X725250Y764083D01*
X725917Y764500D01*
X726333Y765000D01*
X726417Y765500D01*
X726250Y766083D01*
X725667Y766500D01*
X725083Y766667D01*
X724333D01*
G01X725083D02*
X725583Y766917D01*
X726000Y767333D01*
X726167Y767833D01*
X726000Y768333D01*
X725583Y768750D01*
X724833Y769000D01*
X724083Y768917D01*
X723333Y768583D01*
G01X730100Y763833D02*
X729933Y763917D01*
Y764083D01*
X730100Y764167D01*
X730267Y764083D01*
Y763917D01*
X730100Y763833D01*
G01X739633Y764000D02*
Y769000D01*
X741633D01*
X742300Y768750D01*
X742800Y768167D01*
X742967Y767500D01*
X742800Y766833D01*
X742383Y766333D01*
X741633Y766083D01*
X739633D01*
G01X746900Y764000D02*
Y769000D01*
G01X751083Y767333D02*
Y765000D01*
X751417Y764417D01*
X751917Y764083D01*
X752500Y764000D01*
X753083Y764083D01*
X753583Y764417D01*
X753917Y765000D01*
G01Y764000D02*
Y767333D01*
G01X756933Y762750D02*
X757517Y762417D01*
X758183Y762333D01*
X758767Y762417D01*
X759267Y762833D01*
X759600Y763417D01*
Y767333D01*
G01Y766667D02*
X759267Y767000D01*
X758767Y767250D01*
X758183Y767333D01*
X757517Y767167D01*
X757100Y766833D01*
X756767Y766250D01*
X756600Y765667D01*
X756683Y765167D01*
X757017Y764583D01*
X757517Y764167D01*
X758183Y764000D01*
X758683Y764083D01*
X759267Y764417D01*
X759600Y764750D01*
G01X767800Y767333D02*
X769300Y764000D01*
X770800Y767333D01*
G01X774900D02*
Y764000D01*
G01Y768667D02*
X774733Y768750D01*
Y768917D01*
X774900Y769000D01*
X775067Y768917D01*
Y768750D01*
X774900Y768667D01*
G01X782000Y764000D02*
Y767333D01*
G01Y766750D02*
X781667Y767083D01*
X781167Y767250D01*
X780583Y767333D01*
X780000Y767167D01*
X779500Y766833D01*
X779167Y766333D01*
X779000Y765667D01*
X779167Y765000D01*
X779500Y764500D01*
X780000Y764167D01*
X780583Y764000D01*
X781167Y764083D01*
X781667Y764333D01*
X782000Y764667D01*
G01X790200Y763833D02*
X793200Y769000D01*
G01X795217D02*
X797300Y764000D01*
X799383Y769000D01*
G01X802900Y764000D02*
X802233Y764083D01*
X801650Y764417D01*
X801150Y764917D01*
X800817Y765500D01*
X800650Y766167D01*
Y766833D01*
X800817Y767500D01*
X801150Y768083D01*
X801650Y768583D01*
X802233Y768917D01*
X802900Y769000D01*
X803567Y768917D01*
X804150Y768583D01*
X804650Y768083D01*
X804983Y767500D01*
X805150Y766833D01*
Y766167D01*
X804983Y765500D01*
X804650Y764917D01*
X804150Y764417D01*
X803567Y764083D01*
X802900Y764000D01*
G01X806833D02*
Y769000D01*
X808833D01*
X809500Y768750D01*
X810000Y768167D01*
X810167Y767500D01*
X810000Y766833D01*
X809583Y766333D01*
X808833Y766083D01*
X806833D01*
G01X812600Y763833D02*
X815600Y769000D01*
G01X817617D02*
X819700Y764000D01*
X821783Y769000D01*
G01X824300D02*
X826300D01*
G01X825300D02*
Y764000D01*
G01X824300D02*
X826300D01*
G01X829233D02*
Y769000D01*
X831233D01*
X831900Y768750D01*
X832400Y768167D01*
X832567Y767500D01*
X832400Y766833D01*
X831983Y766333D01*
X831233Y766083D01*
X829233D01*
G01X836500Y763833D02*
X836333Y763917D01*
Y764083D01*
X836500Y764167D01*
X836667Y764083D01*
Y763917D01*
X836500Y763833D01*
G01Y766083D02*
X836333Y766167D01*
Y766333D01*
X836500Y766417D01*
X836667Y766333D01*
Y766167D01*
X836500Y766083D01*
G01X713000Y752000D02*
X1344500D01*
G01X724813Y813000D02*
Y818000D01*
X726897D01*
X727563Y817750D01*
X727980Y817417D01*
X728147Y816750D01*
X727980Y816083D01*
X727480Y815667D01*
X726897Y815417D01*
X724813D01*
G01X726897D02*
X728147Y813000D01*
G01X732080D02*
X731580Y813083D01*
X731080Y813417D01*
X730747Y814000D01*
X730580Y814667D01*
X730747Y815333D01*
X731080Y815917D01*
X731580Y816250D01*
X732080Y816333D01*
X732580Y816250D01*
X733080Y815917D01*
X733413Y815333D01*
X733497Y814667D01*
X733413Y814000D01*
X733080Y813417D01*
X732580Y813083D01*
X732080Y813000D01*
G01X736263Y816333D02*
Y814000D01*
X736597Y813417D01*
X737097Y813083D01*
X737680Y813000D01*
X738263Y813083D01*
X738763Y813417D01*
X739097Y814000D01*
G01Y813000D02*
Y816333D01*
G01X743280Y818000D02*
Y813000D01*
G01X742113Y816333D02*
X744447D01*
G01X748880D02*
Y813000D01*
G01Y817667D02*
X748713Y817750D01*
Y817917D01*
X748880Y818000D01*
X749047Y817917D01*
Y817750D01*
X748880Y817667D01*
G01X753063Y813000D02*
Y816333D01*
G01Y815500D02*
X753397Y815917D01*
X753897Y816250D01*
X754563Y816333D01*
X755147Y816250D01*
X755647Y815917D01*
X755897Y815333D01*
Y813000D01*
G01X758913Y811750D02*
X759497Y811417D01*
X760163Y811333D01*
X760747Y811417D01*
X761247Y811833D01*
X761580Y812417D01*
Y816333D01*
G01Y815667D02*
X761247Y816000D01*
X760747Y816250D01*
X760163Y816333D01*
X759497Y816167D01*
X759080Y815833D01*
X758747Y815250D01*
X758580Y814667D01*
X758663Y814167D01*
X758997Y813583D01*
X759497Y813167D01*
X760163Y813000D01*
X760663Y813083D01*
X761247Y813417D01*
X761580Y813750D01*
G01X712980Y850500D02*
X1343000D01*
G01X802167Y-15500D02*
Y-10500D01*
X803833D01*
X804500Y-10750D01*
X805000Y-11083D01*
X805417Y-11583D01*
X805750Y-12167D01*
X805833Y-13000D01*
X805750Y-13833D01*
X805417Y-14417D01*
X805000Y-14917D01*
X804500Y-15250D01*
X803833Y-15500D01*
X802167D01*
G01X809600D02*
Y-10500D01*
X808600Y-11500D01*
G01Y-15500D02*
X810600D01*
G01X813617Y-13417D02*
X814200Y-12833D01*
X814700Y-12500D01*
X815367Y-12333D01*
X815950Y-12500D01*
X816367Y-12833D01*
X816700Y-13333D01*
X816783Y-13917D01*
X816700Y-14417D01*
X816367Y-14917D01*
X815867Y-15333D01*
X815283Y-15500D01*
X814617Y-15333D01*
X814033Y-14833D01*
X813700Y-14083D01*
X813617Y-13250D01*
X813783Y-12167D01*
X814033Y-11583D01*
X814450Y-11000D01*
X815033Y-10583D01*
X815617Y-10500D01*
X816200Y-10667D01*
X816617Y-11083D01*
G01X777583Y104700D02*
Y99700D01*
X780917D01*
G01X783600Y103033D02*
X786100Y99700D01*
G01Y103033D02*
X783600Y99700D01*
G01X790450Y99533D02*
X790283Y99617D01*
Y99783D01*
X790450Y99867D01*
X790617Y99783D01*
Y99617D01*
X790450Y99533D01*
G01Y101783D02*
X790283Y101867D01*
Y102033D01*
X790450Y102117D01*
X790617Y102033D01*
Y101867D01*
X790450Y101783D01*
G01X799150Y99700D02*
Y103033D01*
G01Y102117D02*
X799400Y102533D01*
X799817Y102867D01*
X800400Y103033D01*
X800983Y102867D01*
X801400Y102533D01*
X801650Y102117D01*
Y99700D01*
G01Y102117D02*
X801900Y102533D01*
X802317Y102867D01*
X802900Y103033D01*
X803483Y102867D01*
X803900Y102533D01*
X804150Y102033D01*
Y99700D01*
G01X805833Y103033D02*
Y100700D01*
X806167Y100117D01*
X806667Y99783D01*
X807250Y99700D01*
X807833Y99783D01*
X808333Y100117D01*
X808667Y100700D01*
G01Y99700D02*
Y103033D01*
G01X811600Y100283D02*
X812017Y99950D01*
X812600Y99700D01*
X813100D01*
X813600Y99867D01*
X813933Y100117D01*
X814100Y100450D01*
X814017Y100950D01*
X813683Y101200D01*
X812183Y101700D01*
X811850Y102283D01*
X812017Y102700D01*
X812350Y102950D01*
X812850Y103033D01*
X813350Y102950D01*
X813850Y102700D01*
G01X818450Y104700D02*
Y99700D01*
G01X817283Y103033D02*
X819617D01*
G01X828150Y99700D02*
Y104700D01*
G01Y102200D02*
X828567Y102700D01*
X829067Y102950D01*
X829567Y103033D01*
X830317Y102867D01*
X830817Y102533D01*
X831150Y101950D01*
Y101283D01*
X830983Y100617D01*
X830650Y100117D01*
X830067Y99783D01*
X829567Y99700D01*
X829067Y99783D01*
X828567Y100033D01*
X828150Y100450D01*
G01X834000Y101950D02*
X836667D01*
X836417Y102533D01*
X836000Y102867D01*
X835417Y103033D01*
X834833Y102950D01*
X834333Y102700D01*
X834000Y102117D01*
X833833Y101617D01*
Y101117D01*
X834000Y100617D01*
X834417Y100117D01*
X834917Y99783D01*
X835500Y99700D01*
X836083Y99867D01*
X836667Y100367D01*
G01X844950Y99700D02*
Y104700D01*
G01Y102200D02*
X845367Y102700D01*
X845867Y102950D01*
X846367Y103033D01*
X847117Y102867D01*
X847617Y102533D01*
X847950Y101950D01*
Y101283D01*
X847783Y100617D01*
X847450Y100117D01*
X846867Y99783D01*
X846367Y99700D01*
X845867Y99783D01*
X845367Y100033D01*
X844950Y100450D01*
G01X850883Y99700D02*
Y103033D01*
G01Y102367D02*
X851300Y102700D01*
X851717Y102950D01*
X852300Y103033D01*
X852717Y102950D01*
X853217Y102700D01*
G01X857650Y99700D02*
X857150Y99783D01*
X856650Y100117D01*
X856317Y100700D01*
X856150Y101367D01*
X856317Y102033D01*
X856650Y102617D01*
X857150Y102950D01*
X857650Y103033D01*
X858150Y102950D01*
X858650Y102617D01*
X858983Y102033D01*
X859067Y101367D01*
X858983Y100700D01*
X858650Y100117D01*
X858150Y99783D01*
X857650Y99700D01*
G01X861833D02*
Y104700D01*
G01X864500Y103033D02*
X861833Y101117D01*
G01X862917Y101867D02*
X864667Y99700D01*
G01X867600Y101950D02*
X870267D01*
X870017Y102533D01*
X869600Y102867D01*
X869017Y103033D01*
X868433Y102950D01*
X867933Y102700D01*
X867600Y102117D01*
X867433Y101617D01*
Y101117D01*
X867600Y100617D01*
X868017Y100117D01*
X868517Y99783D01*
X869100Y99700D01*
X869683Y99867D01*
X870267Y100367D01*
G01X873033Y99700D02*
Y103033D01*
G01Y102200D02*
X873367Y102617D01*
X873867Y102950D01*
X874533Y103033D01*
X875117Y102950D01*
X875617Y102617D01*
X875867Y102033D01*
Y99700D01*
G01X885650D02*
Y104700D01*
G01X892750Y99700D02*
Y103033D01*
G01Y102450D02*
X892417Y102783D01*
X891917Y102950D01*
X891333Y103033D01*
X890750Y102867D01*
X890250Y102533D01*
X889917Y102033D01*
X889750Y101367D01*
X889917Y100700D01*
X890250Y100200D01*
X890750Y99867D01*
X891333Y99700D01*
X891917Y99783D01*
X892417Y100033D01*
X892750Y100367D01*
G01X895100Y98200D02*
X895600Y98033D01*
X896267Y98200D01*
X896683Y98533D01*
X897017Y98950D01*
X897517Y100283D01*
X898600Y103033D01*
G01X895933D02*
X897517Y100283D01*
G01X901200Y101950D02*
X903867D01*
X903617Y102533D01*
X903200Y102867D01*
X902617Y103033D01*
X902033Y102950D01*
X901533Y102700D01*
X901200Y102117D01*
X901033Y101617D01*
Y101117D01*
X901200Y100617D01*
X901617Y100117D01*
X902117Y99783D01*
X902700Y99700D01*
X903283Y99867D01*
X903867Y100367D01*
G01X906883Y99700D02*
Y103033D01*
G01Y102367D02*
X907300Y102700D01*
X907717Y102950D01*
X908300Y103033D01*
X908717Y102950D01*
X909217Y102700D01*
G01X776983Y116310D02*
Y111310D01*
X780317D01*
G01X782833D02*
Y114643D01*
G01Y113810D02*
X783167Y114227D01*
X783667Y114560D01*
X784333Y114643D01*
X784917Y114560D01*
X785417Y114227D01*
X785667Y113643D01*
Y111310D01*
G01X789850Y111143D02*
X789683Y111227D01*
Y111393D01*
X789850Y111477D01*
X790017Y111393D01*
Y111227D01*
X789850Y111143D01*
G01Y113393D02*
X789683Y113477D01*
Y113643D01*
X789850Y113727D01*
X790017Y113643D01*
Y113477D01*
X789850Y113393D01*
G01X802383Y114227D02*
X801800Y114560D01*
X801300Y114643D01*
X800633Y114477D01*
X800133Y114143D01*
X799800Y113560D01*
X799717Y112977D01*
X799800Y112393D01*
X800133Y111893D01*
X800633Y111477D01*
X801300Y111310D01*
X801883Y111477D01*
X802383Y111810D01*
G01X808150Y111310D02*
Y114643D01*
G01Y114060D02*
X807817Y114393D01*
X807317Y114560D01*
X806733Y114643D01*
X806150Y114477D01*
X805650Y114143D01*
X805317Y113643D01*
X805150Y112977D01*
X805317Y112310D01*
X805650Y111810D01*
X806150Y111477D01*
X806733Y111310D01*
X807317Y111393D01*
X807817Y111643D01*
X808150Y111977D01*
G01X810833Y111310D02*
Y114643D01*
G01Y113810D02*
X811167Y114227D01*
X811667Y114560D01*
X812333Y114643D01*
X812917Y114560D01*
X813417Y114227D01*
X813667Y113643D01*
Y111310D01*
G01X817850Y114643D02*
X818683Y115685D01*
Y116310D01*
X818058D01*
Y115685D01*
X818683D01*
G01X823450Y116310D02*
Y111310D01*
G01X822283Y114643D02*
X824617D01*
G01X833150Y111310D02*
Y116310D01*
G01Y113810D02*
X833567Y114310D01*
X834067Y114560D01*
X834567Y114643D01*
X835317Y114477D01*
X835817Y114143D01*
X836150Y113560D01*
Y112893D01*
X835983Y112227D01*
X835650Y111727D01*
X835067Y111393D01*
X834567Y111310D01*
X834067Y111393D01*
X833567Y111643D01*
X833150Y112060D01*
G01X839000Y113560D02*
X841667D01*
X841417Y114143D01*
X841000Y114477D01*
X840417Y114643D01*
X839833Y114560D01*
X839333Y114310D01*
X839000Y113727D01*
X838833Y113227D01*
Y112727D01*
X839000Y112227D01*
X839417Y111727D01*
X839917Y111393D01*
X840500Y111310D01*
X841083Y111477D01*
X841667Y111977D01*
G01X849950Y111310D02*
Y116310D01*
G01Y113810D02*
X850367Y114310D01*
X850867Y114560D01*
X851367Y114643D01*
X852117Y114477D01*
X852617Y114143D01*
X852950Y113560D01*
Y112893D01*
X852783Y112227D01*
X852450Y111727D01*
X851867Y111393D01*
X851367Y111310D01*
X850867Y111393D01*
X850367Y111643D01*
X849950Y112060D01*
G01X855883Y111310D02*
Y114643D01*
G01Y113977D02*
X856300Y114310D01*
X856717Y114560D01*
X857300Y114643D01*
X857717Y114560D01*
X858217Y114310D01*
G01X862650Y111310D02*
X862150Y111393D01*
X861650Y111727D01*
X861317Y112310D01*
X861150Y112977D01*
X861317Y113643D01*
X861650Y114227D01*
X862150Y114560D01*
X862650Y114643D01*
X863150Y114560D01*
X863650Y114227D01*
X863983Y113643D01*
X864067Y112977D01*
X863983Y112310D01*
X863650Y111727D01*
X863150Y111393D01*
X862650Y111310D01*
G01X866833D02*
Y116310D01*
G01X869500Y114643D02*
X866833Y112727D01*
G01X867917Y113477D02*
X869667Y111310D01*
G01X872600Y113560D02*
X875267D01*
X875017Y114143D01*
X874600Y114477D01*
X874017Y114643D01*
X873433Y114560D01*
X872933Y114310D01*
X872600Y113727D01*
X872433Y113227D01*
Y112727D01*
X872600Y112227D01*
X873017Y111727D01*
X873517Y111393D01*
X874100Y111310D01*
X874683Y111477D01*
X875267Y111977D01*
G01X878033Y111310D02*
Y114643D01*
G01Y113810D02*
X878367Y114227D01*
X878867Y114560D01*
X879533Y114643D01*
X880117Y114560D01*
X880617Y114227D01*
X880867Y113643D01*
Y111310D01*
G01X890650D02*
Y116310D01*
G01X897750Y111310D02*
Y114643D01*
G01Y114060D02*
X897417Y114393D01*
X896917Y114560D01*
X896333Y114643D01*
X895750Y114477D01*
X895250Y114143D01*
X894917Y113643D01*
X894750Y112977D01*
X894917Y112310D01*
X895250Y111810D01*
X895750Y111477D01*
X896333Y111310D01*
X896917Y111393D01*
X897417Y111643D01*
X897750Y111977D01*
G01X900100Y109810D02*
X900600Y109643D01*
X901267Y109810D01*
X901683Y110143D01*
X902017Y110560D01*
X902517Y111893D01*
X903600Y114643D01*
G01X900933D02*
X902517Y111893D01*
G01X906200Y113560D02*
X908867D01*
X908617Y114143D01*
X908200Y114477D01*
X907617Y114643D01*
X907033Y114560D01*
X906533Y114310D01*
X906200Y113727D01*
X906033Y113227D01*
Y112727D01*
X906200Y112227D01*
X906617Y111727D01*
X907117Y111393D01*
X907700Y111310D01*
X908283Y111477D01*
X908867Y111977D01*
G01X911883Y111310D02*
Y114643D01*
G01Y113977D02*
X912300Y114310D01*
X912717Y114560D01*
X913300Y114643D01*
X913717Y114560D01*
X914217Y114310D01*
G01X777167Y123000D02*
Y128000D01*
X778833D01*
X779500Y127750D01*
X780000Y127417D01*
X780417Y126917D01*
X780750Y126333D01*
X780833Y125500D01*
X780750Y124667D01*
X780417Y124083D01*
X780000Y123583D01*
X779500Y123250D01*
X778833Y123000D01*
X777167D01*
G01X783433D02*
Y126333D01*
G01Y125667D02*
X783850Y126000D01*
X784267Y126250D01*
X784850Y126333D01*
X785267Y126250D01*
X785767Y126000D01*
G01X790200Y126333D02*
Y123000D01*
G01Y127667D02*
X790033Y127750D01*
Y127917D01*
X790200Y128000D01*
X790367Y127917D01*
Y127750D01*
X790200Y127667D01*
G01X795800Y123000D02*
Y128000D01*
G01X801400Y123000D02*
Y128000D01*
G01X811017Y123000D02*
Y128000D01*
X814183D01*
G01X813017Y125583D02*
X811017D01*
G01X817033Y123000D02*
Y126333D01*
G01Y125667D02*
X817450Y126000D01*
X817867Y126250D01*
X818450Y126333D01*
X818867Y126250D01*
X819367Y126000D01*
G01X823800Y123000D02*
X823300Y123083D01*
X822800Y123417D01*
X822467Y124000D01*
X822300Y124667D01*
X822467Y125333D01*
X822800Y125917D01*
X823300Y126250D01*
X823800Y126333D01*
X824300Y126250D01*
X824800Y125917D01*
X825133Y125333D01*
X825217Y124667D01*
X825133Y124000D01*
X824800Y123417D01*
X824300Y123083D01*
X823800Y123000D01*
G01X826900D02*
Y126333D01*
G01Y125417D02*
X827150Y125833D01*
X827567Y126167D01*
X828150Y126333D01*
X828733Y126167D01*
X829150Y125833D01*
X829400Y125417D01*
Y123000D01*
G01Y125417D02*
X829650Y125833D01*
X830067Y126167D01*
X830650Y126333D01*
X831233Y126167D01*
X831650Y125833D01*
X831900Y125333D01*
Y123000D01*
G01X838933Y128000D02*
Y123000D01*
X842267D01*
G01X846200D02*
Y128000D01*
X845200Y127000D01*
G01Y123000D02*
X847200D01*
G01X856983Y121333D02*
X856150Y122167D01*
X855733Y123000D01*
Y126333D01*
X856150Y127167D01*
X856983Y128000D01*
G01X863000D02*
Y123000D01*
G01X861083Y128000D02*
X864917D01*
G01X868600Y123000D02*
X867933Y123083D01*
X867350Y123417D01*
X866850Y123917D01*
X866517Y124500D01*
X866350Y125167D01*
Y125833D01*
X866517Y126500D01*
X866850Y127083D01*
X867350Y127583D01*
X867933Y127917D01*
X868600Y128000D01*
X869267Y127917D01*
X869850Y127583D01*
X870350Y127083D01*
X870683Y126500D01*
X870850Y125833D01*
Y125167D01*
X870683Y124500D01*
X870350Y123917D01*
X869850Y123417D01*
X869267Y123083D01*
X868600Y123000D01*
G01X872533D02*
Y128000D01*
X874533D01*
X875200Y127750D01*
X875700Y127167D01*
X875867Y126500D01*
X875700Y125833D01*
X875283Y125333D01*
X874533Y125083D01*
X872533D01*
G01X880217Y121333D02*
X881050Y122167D01*
X881467Y123000D01*
Y126333D01*
X881050Y127167D01*
X880217Y128000D01*
G01X891000D02*
Y123000D01*
G01X889833Y126333D02*
X892167D01*
G01X896600Y123000D02*
X896100Y123083D01*
X895600Y123417D01*
X895267Y124000D01*
X895100Y124667D01*
X895267Y125333D01*
X895600Y125917D01*
X896100Y126250D01*
X896600Y126333D01*
X897100Y126250D01*
X897600Y125917D01*
X897933Y125333D01*
X898017Y124667D01*
X897933Y124000D01*
X897600Y123417D01*
X897100Y123083D01*
X896600Y123000D01*
G01X906133Y128000D02*
Y123000D01*
X909467D01*
G01X912150Y126333D02*
X914650Y123000D01*
G01Y126333D02*
X912150Y123000D01*
G01X821590Y376450D02*
Y379783D01*
G01Y379200D02*
X821257Y379533D01*
X820757Y379700D01*
X820173Y379783D01*
X819590Y379617D01*
X819090Y379283D01*
X818757Y378783D01*
X818590Y378117D01*
X818757Y377450D01*
X819090Y376950D01*
X819590Y376617D01*
X820173Y376450D01*
X820757Y376533D01*
X821257Y376783D01*
X821590Y377117D01*
G01X824273Y376450D02*
Y379783D01*
G01Y378950D02*
X824607Y379367D01*
X825107Y379700D01*
X825773Y379783D01*
X826357Y379700D01*
X826857Y379367D01*
X827107Y378783D01*
Y376450D01*
G01X832790Y381450D02*
Y376450D01*
G01Y377200D02*
X832457Y376783D01*
X831957Y376533D01*
X831373Y376450D01*
X830707Y376617D01*
X830207Y377033D01*
X829873Y377533D01*
X829790Y378117D01*
X829873Y378700D01*
X830207Y379200D01*
X830707Y379617D01*
X831373Y379783D01*
X831957Y379700D01*
X832373Y379533D01*
X832790Y379200D01*
G01X843823Y379367D02*
X843240Y379700D01*
X842740Y379783D01*
X842073Y379617D01*
X841573Y379283D01*
X841240Y378700D01*
X841157Y378117D01*
X841240Y377533D01*
X841573Y377033D01*
X842073Y376617D01*
X842740Y376450D01*
X843323Y376617D01*
X843823Y376950D01*
G01X848090Y376450D02*
X847590Y376533D01*
X847090Y376867D01*
X846757Y377450D01*
X846590Y378117D01*
X846757Y378783D01*
X847090Y379367D01*
X847590Y379700D01*
X848090Y379783D01*
X848590Y379700D01*
X849090Y379367D01*
X849423Y378783D01*
X849507Y378117D01*
X849423Y377450D01*
X849090Y376867D01*
X848590Y376533D01*
X848090Y376450D01*
G01X852190Y379783D02*
X853690Y376450D01*
X855190Y379783D01*
G01X858040Y378700D02*
X860707D01*
X860457Y379283D01*
X860040Y379617D01*
X859457Y379783D01*
X858873Y379700D01*
X858373Y379450D01*
X858040Y378867D01*
X857873Y378367D01*
Y377867D01*
X858040Y377367D01*
X858457Y376867D01*
X858957Y376533D01*
X859540Y376450D01*
X860123Y376617D01*
X860707Y377117D01*
G01X863723Y376450D02*
Y379783D01*
G01Y379117D02*
X864140Y379450D01*
X864557Y379700D01*
X865140Y379783D01*
X865557Y379700D01*
X866057Y379450D01*
G01X869240Y378700D02*
X871907D01*
X871657Y379283D01*
X871240Y379617D01*
X870657Y379783D01*
X870073Y379700D01*
X869573Y379450D01*
X869240Y378867D01*
X869073Y378367D01*
Y377867D01*
X869240Y377367D01*
X869657Y376867D01*
X870157Y376533D01*
X870740Y376450D01*
X871323Y376617D01*
X871907Y377117D01*
G01X877590Y381450D02*
Y376450D01*
G01Y377200D02*
X877257Y376783D01*
X876757Y376533D01*
X876173Y376450D01*
X875507Y376617D01*
X875007Y377033D01*
X874673Y377533D01*
X874590Y378117D01*
X874673Y378700D01*
X875007Y379200D01*
X875507Y379617D01*
X876173Y379783D01*
X876757Y379700D01*
X877173Y379533D01*
X877590Y379200D01*
G01X885207Y379783D02*
X886207Y376450D01*
X887290Y379783D01*
X888373Y376450D01*
X889373Y379783D01*
G01X892890D02*
Y376450D01*
G01Y381117D02*
X892723Y381200D01*
Y381367D01*
X892890Y381450D01*
X893057Y381367D01*
Y381200D01*
X892890Y381117D01*
G01X898490Y381450D02*
Y376450D01*
G01X897323Y379783D02*
X899657D01*
G01X902673Y376450D02*
Y381450D01*
G01Y379033D02*
X903090Y379450D01*
X903507Y379700D01*
X904173Y379783D01*
X904673Y379700D01*
X905257Y379367D01*
X905507Y378867D01*
Y376450D01*
G01X916623Y379367D02*
X916040Y379700D01*
X915540Y379783D01*
X914873Y379617D01*
X914373Y379283D01*
X914040Y378700D01*
X913957Y378117D01*
X914040Y377533D01*
X914373Y377033D01*
X914873Y376617D01*
X915540Y376450D01*
X916123Y376617D01*
X916623Y376950D01*
G01X920890Y376450D02*
X920390Y376533D01*
X919890Y376867D01*
X919557Y377450D01*
X919390Y378117D01*
X919557Y378783D01*
X919890Y379367D01*
X920390Y379700D01*
X920890Y379783D01*
X921390Y379700D01*
X921890Y379367D01*
X922223Y378783D01*
X922307Y378117D01*
X922223Y377450D01*
X921890Y376867D01*
X921390Y376533D01*
X920890Y376450D01*
G01X924990Y374783D02*
Y379783D01*
G01Y379033D02*
X925407Y379450D01*
X925823Y379700D01*
X926490Y379783D01*
X927073Y379700D01*
X927657Y379283D01*
X927907Y378700D01*
X927990Y378117D01*
X927907Y377533D01*
X927657Y376950D01*
X927157Y376617D01*
X926490Y376450D01*
X925907Y376533D01*
X925323Y376783D01*
X924990Y377117D01*
G01X930590Y374783D02*
Y379783D01*
G01Y379033D02*
X931007Y379450D01*
X931423Y379700D01*
X932090Y379783D01*
X932673Y379700D01*
X933257Y379283D01*
X933507Y378700D01*
X933590Y378117D01*
X933507Y377533D01*
X933257Y376950D01*
X932757Y376617D01*
X932090Y376450D01*
X931507Y376533D01*
X930923Y376783D01*
X930590Y377117D01*
G01X936440Y378700D02*
X939107D01*
X938857Y379283D01*
X938440Y379617D01*
X937857Y379783D01*
X937273Y379700D01*
X936773Y379450D01*
X936440Y378867D01*
X936273Y378367D01*
Y377867D01*
X936440Y377367D01*
X936857Y376867D01*
X937357Y376533D01*
X937940Y376450D01*
X938523Y376617D01*
X939107Y377117D01*
G01X942123Y376450D02*
Y379783D01*
G01Y379117D02*
X942540Y379450D01*
X942957Y379700D01*
X943540Y379783D01*
X943957Y379700D01*
X944457Y379450D01*
G01X821500Y419500D02*
Y423750D01*
X821667Y424167D01*
X822000Y424417D01*
X822500Y424500D01*
X823000Y424333D01*
X823250Y423917D01*
G01X822250Y422500D02*
X820583D01*
G01X827600Y419500D02*
X827100Y419583D01*
X826600Y419917D01*
X826267Y420500D01*
X826100Y421167D01*
X826267Y421833D01*
X826600Y422417D01*
X827100Y422750D01*
X827600Y422833D01*
X828100Y422750D01*
X828600Y422417D01*
X828933Y421833D01*
X829017Y421167D01*
X828933Y420500D01*
X828600Y419917D01*
X828100Y419583D01*
X827600Y419500D01*
G01X833200D02*
Y424500D01*
G01X838800Y419500D02*
Y424500D01*
G01X844400Y419500D02*
X843900Y419583D01*
X843400Y419917D01*
X843067Y420500D01*
X842900Y421167D01*
X843067Y421833D01*
X843400Y422417D01*
X843900Y422750D01*
X844400Y422833D01*
X844900Y422750D01*
X845400Y422417D01*
X845733Y421833D01*
X845817Y421167D01*
X845733Y420500D01*
X845400Y419917D01*
X844900Y419583D01*
X844400Y419500D01*
G01X847917Y422833D02*
X848917Y419500D01*
X850000Y422833D01*
X851083Y419500D01*
X852083Y422833D01*
G01X861700Y422000D02*
X863367D01*
Y420500D01*
X862867Y420000D01*
X862283Y419667D01*
X861450Y419500D01*
X860617Y419667D01*
X860033Y420000D01*
X859533Y420500D01*
X859200Y421083D01*
X859033Y421750D01*
Y422333D01*
X859200Y422833D01*
X859533Y423417D01*
X860033Y423917D01*
X860533Y424250D01*
X861200Y424500D01*
X861783D01*
X862450Y424333D01*
X862950Y424000D01*
G01X865550Y421750D02*
X868217D01*
X867967Y422333D01*
X867550Y422667D01*
X866967Y422833D01*
X866383Y422750D01*
X865883Y422500D01*
X865550Y421917D01*
X865383Y421417D01*
Y420917D01*
X865550Y420417D01*
X865967Y419917D01*
X866467Y419583D01*
X867050Y419500D01*
X867633Y419667D01*
X868217Y420167D01*
G01X871233Y419500D02*
Y422833D01*
G01Y422167D02*
X871650Y422500D01*
X872067Y422750D01*
X872650Y422833D01*
X873067Y422750D01*
X873567Y422500D01*
G01X876500Y419500D02*
Y424500D01*
G01Y422000D02*
X876917Y422500D01*
X877417Y422750D01*
X877917Y422833D01*
X878667Y422667D01*
X879167Y422333D01*
X879500Y421750D01*
Y421083D01*
X879333Y420417D01*
X879000Y419917D01*
X878417Y419583D01*
X877917Y419500D01*
X877417Y419583D01*
X876917Y419833D01*
X876500Y420250D01*
G01X882350Y421750D02*
X885017D01*
X884767Y422333D01*
X884350Y422667D01*
X883767Y422833D01*
X883183Y422750D01*
X882683Y422500D01*
X882350Y421917D01*
X882183Y421417D01*
Y420917D01*
X882350Y420417D01*
X882767Y419917D01*
X883267Y419583D01*
X883850Y419500D01*
X884433Y419667D01*
X885017Y420167D01*
G01X888033Y419500D02*
Y422833D01*
G01Y422167D02*
X888450Y422500D01*
X888867Y422750D01*
X889450Y422833D01*
X889867Y422750D01*
X890367Y422500D01*
G01X901900Y419500D02*
Y422833D01*
G01Y422250D02*
X901567Y422583D01*
X901067Y422750D01*
X900483Y422833D01*
X899900Y422667D01*
X899400Y422333D01*
X899067Y421833D01*
X898900Y421167D01*
X899067Y420500D01*
X899400Y420000D01*
X899900Y419667D01*
X900483Y419500D01*
X901067Y419583D01*
X901567Y419833D01*
X901900Y420167D01*
G01X904583Y419500D02*
Y422833D01*
G01Y422000D02*
X904917Y422417D01*
X905417Y422750D01*
X906083Y422833D01*
X906667Y422750D01*
X907167Y422417D01*
X907417Y421833D01*
Y419500D01*
G01X913100Y424500D02*
Y419500D01*
G01Y420250D02*
X912767Y419833D01*
X912267Y419583D01*
X911683Y419500D01*
X911017Y419667D01*
X910517Y420083D01*
X910183Y420583D01*
X910100Y421167D01*
X910183Y421750D01*
X910517Y422250D01*
X911017Y422667D01*
X911683Y422833D01*
X912267Y422750D01*
X912683Y422583D01*
X913100Y422250D01*
G01X921300Y417833D02*
Y422833D01*
G01Y422083D02*
X921717Y422500D01*
X922133Y422750D01*
X922800Y422833D01*
X923383Y422750D01*
X923967Y422333D01*
X924217Y421750D01*
X924300Y421167D01*
X924217Y420583D01*
X923967Y420000D01*
X923467Y419667D01*
X922800Y419500D01*
X922217Y419583D01*
X921633Y419833D01*
X921300Y420167D01*
G01X928400Y419500D02*
Y424500D01*
G01X932583Y422833D02*
Y420500D01*
X932917Y419917D01*
X933417Y419583D01*
X934000Y419500D01*
X934583Y419583D01*
X935083Y419917D01*
X935417Y420500D01*
G01Y419500D02*
Y422833D01*
G01X938433Y418250D02*
X939017Y417917D01*
X939683Y417833D01*
X940267Y417917D01*
X940767Y418333D01*
X941100Y418917D01*
Y422833D01*
G01Y422167D02*
X940767Y422500D01*
X940267Y422750D01*
X939683Y422833D01*
X939017Y422667D01*
X938600Y422333D01*
X938267Y421750D01*
X938100Y421167D01*
X938183Y420667D01*
X938517Y420083D01*
X939017Y419667D01*
X939683Y419500D01*
X940183Y419583D01*
X940767Y419917D01*
X941100Y420250D01*
G01X948717Y422833D02*
X949717Y419500D01*
X950800Y422833D01*
X951883Y419500D01*
X952883Y422833D01*
G01X956400D02*
Y419500D01*
G01Y424167D02*
X956233Y424250D01*
Y424417D01*
X956400Y424500D01*
X956567Y424417D01*
Y424250D01*
X956400Y424167D01*
G01X962000Y424500D02*
Y419500D01*
G01X960833Y422833D02*
X963167D01*
G01X966183Y419500D02*
Y424500D01*
G01Y422083D02*
X966600Y422500D01*
X967017Y422750D01*
X967683Y422833D01*
X968183Y422750D01*
X968767Y422417D01*
X969017Y421917D01*
Y419500D01*
G01X977633D02*
Y422833D01*
G01Y422167D02*
X978050Y422500D01*
X978467Y422750D01*
X979050Y422833D01*
X979467Y422750D01*
X979967Y422500D01*
G01X983150Y421750D02*
X985817D01*
X985567Y422333D01*
X985150Y422667D01*
X984567Y422833D01*
X983983Y422750D01*
X983483Y422500D01*
X983150Y421917D01*
X982983Y421417D01*
Y420917D01*
X983150Y420417D01*
X983567Y419917D01*
X984067Y419583D01*
X984650Y419500D01*
X985233Y419667D01*
X985817Y420167D01*
G01X988750Y420083D02*
X989167Y419750D01*
X989750Y419500D01*
X990250D01*
X990750Y419667D01*
X991083Y419917D01*
X991250Y420250D01*
X991167Y420750D01*
X990833Y421000D01*
X989333Y421500D01*
X989000Y422083D01*
X989167Y422500D01*
X989500Y422750D01*
X990000Y422833D01*
X990500Y422750D01*
X991000Y422500D01*
G01X995600Y422833D02*
Y419500D01*
G01Y424167D02*
X995433Y424250D01*
Y424417D01*
X995600Y424500D01*
X995767Y424417D01*
Y424250D01*
X995600Y424167D01*
G01X999783Y419500D02*
Y422833D01*
G01Y422000D02*
X1000117Y422417D01*
X1000617Y422750D01*
X1001283Y422833D01*
X1001867Y422750D01*
X1002367Y422417D01*
X1002617Y421833D01*
Y419500D01*
G01X819590Y389810D02*
Y394060D01*
X819757Y394477D01*
X820090Y394727D01*
X820590Y394810D01*
X821090Y394643D01*
X821340Y394227D01*
G01X820340Y392810D02*
X818673D01*
G01X825690Y389810D02*
X825190Y389893D01*
X824690Y390227D01*
X824357Y390810D01*
X824190Y391477D01*
X824357Y392143D01*
X824690Y392727D01*
X825190Y393060D01*
X825690Y393143D01*
X826190Y393060D01*
X826690Y392727D01*
X827023Y392143D01*
X827107Y391477D01*
X827023Y390810D01*
X826690Y390227D01*
X826190Y389893D01*
X825690Y389810D01*
G01X831290D02*
Y394810D01*
G01X836890Y389810D02*
Y394810D01*
G01X842490Y389810D02*
X841990Y389893D01*
X841490Y390227D01*
X841157Y390810D01*
X840990Y391477D01*
X841157Y392143D01*
X841490Y392727D01*
X841990Y393060D01*
X842490Y393143D01*
X842990Y393060D01*
X843490Y392727D01*
X843823Y392143D01*
X843907Y391477D01*
X843823Y390810D01*
X843490Y390227D01*
X842990Y389893D01*
X842490Y389810D01*
G01X846007Y393143D02*
X847007Y389810D01*
X848090Y393143D01*
X849173Y389810D01*
X850173Y393143D01*
G01X859790Y392310D02*
X861457D01*
Y390810D01*
X860957Y390310D01*
X860373Y389977D01*
X859540Y389810D01*
X858707Y389977D01*
X858123Y390310D01*
X857623Y390810D01*
X857290Y391393D01*
X857123Y392060D01*
Y392643D01*
X857290Y393143D01*
X857623Y393727D01*
X858123Y394227D01*
X858623Y394560D01*
X859290Y394810D01*
X859873D01*
X860540Y394643D01*
X861040Y394310D01*
G01X863640Y392060D02*
X866307D01*
X866057Y392643D01*
X865640Y392977D01*
X865057Y393143D01*
X864473Y393060D01*
X863973Y392810D01*
X863640Y392227D01*
X863473Y391727D01*
Y391227D01*
X863640Y390727D01*
X864057Y390227D01*
X864557Y389893D01*
X865140Y389810D01*
X865723Y389977D01*
X866307Y390477D01*
G01X869323Y389810D02*
Y393143D01*
G01Y392477D02*
X869740Y392810D01*
X870157Y393060D01*
X870740Y393143D01*
X871157Y393060D01*
X871657Y392810D01*
G01X874590Y389810D02*
Y394810D01*
G01Y392310D02*
X875007Y392810D01*
X875507Y393060D01*
X876007Y393143D01*
X876757Y392977D01*
X877257Y392643D01*
X877590Y392060D01*
Y391393D01*
X877423Y390727D01*
X877090Y390227D01*
X876507Y389893D01*
X876007Y389810D01*
X875507Y389893D01*
X875007Y390143D01*
X874590Y390560D01*
G01X880440Y392060D02*
X883107D01*
X882857Y392643D01*
X882440Y392977D01*
X881857Y393143D01*
X881273Y393060D01*
X880773Y392810D01*
X880440Y392227D01*
X880273Y391727D01*
Y391227D01*
X880440Y390727D01*
X880857Y390227D01*
X881357Y389893D01*
X881940Y389810D01*
X882523Y389977D01*
X883107Y390477D01*
G01X886123Y389810D02*
Y393143D01*
G01Y392477D02*
X886540Y392810D01*
X886957Y393060D01*
X887540Y393143D01*
X887957Y393060D01*
X888457Y392810D01*
G01X899990Y389810D02*
Y393143D01*
G01Y392560D02*
X899657Y392893D01*
X899157Y393060D01*
X898573Y393143D01*
X897990Y392977D01*
X897490Y392643D01*
X897157Y392143D01*
X896990Y391477D01*
X897157Y390810D01*
X897490Y390310D01*
X897990Y389977D01*
X898573Y389810D01*
X899157Y389893D01*
X899657Y390143D01*
X899990Y390477D01*
G01X902673Y389810D02*
Y393143D01*
G01Y392310D02*
X903007Y392727D01*
X903507Y393060D01*
X904173Y393143D01*
X904757Y393060D01*
X905257Y392727D01*
X905507Y392143D01*
Y389810D01*
G01X911190Y394810D02*
Y389810D01*
G01Y390560D02*
X910857Y390143D01*
X910357Y389893D01*
X909773Y389810D01*
X909107Y389977D01*
X908607Y390393D01*
X908273Y390893D01*
X908190Y391477D01*
X908273Y392060D01*
X908607Y392560D01*
X909107Y392977D01*
X909773Y393143D01*
X910357Y393060D01*
X910773Y392893D01*
X911190Y392560D01*
G01X919390Y388143D02*
Y393143D01*
G01Y392393D02*
X919807Y392810D01*
X920223Y393060D01*
X920890Y393143D01*
X921473Y393060D01*
X922057Y392643D01*
X922307Y392060D01*
X922390Y391477D01*
X922307Y390893D01*
X922057Y390310D01*
X921557Y389977D01*
X920890Y389810D01*
X920307Y389893D01*
X919723Y390143D01*
X919390Y390477D01*
G01X926490Y389810D02*
Y394810D01*
G01X930673Y393143D02*
Y390810D01*
X931007Y390227D01*
X931507Y389893D01*
X932090Y389810D01*
X932673Y389893D01*
X933173Y390227D01*
X933507Y390810D01*
G01Y389810D02*
Y393143D01*
G01X936523Y388560D02*
X937107Y388227D01*
X937773Y388143D01*
X938357Y388227D01*
X938857Y388643D01*
X939190Y389227D01*
Y393143D01*
G01Y392477D02*
X938857Y392810D01*
X938357Y393060D01*
X937773Y393143D01*
X937107Y392977D01*
X936690Y392643D01*
X936357Y392060D01*
X936190Y391477D01*
X936273Y390977D01*
X936607Y390393D01*
X937107Y389977D01*
X937773Y389810D01*
X938273Y389893D01*
X938857Y390227D01*
X939190Y390560D01*
G01X946807Y393143D02*
X947807Y389810D01*
X948890Y393143D01*
X949973Y389810D01*
X950973Y393143D01*
G01X954490D02*
Y389810D01*
G01Y394477D02*
X954323Y394560D01*
Y394727D01*
X954490Y394810D01*
X954657Y394727D01*
Y394560D01*
X954490Y394477D01*
G01X960090Y394810D02*
Y389810D01*
G01X958923Y393143D02*
X961257D01*
G01X964273Y389810D02*
Y394810D01*
G01Y392393D02*
X964690Y392810D01*
X965107Y393060D01*
X965773Y393143D01*
X966273Y393060D01*
X966857Y392727D01*
X967107Y392227D01*
Y389810D01*
G01X975723D02*
Y393143D01*
G01Y392477D02*
X976140Y392810D01*
X976557Y393060D01*
X977140Y393143D01*
X977557Y393060D01*
X978057Y392810D01*
G01X981240Y392060D02*
X983907D01*
X983657Y392643D01*
X983240Y392977D01*
X982657Y393143D01*
X982073Y393060D01*
X981573Y392810D01*
X981240Y392227D01*
X981073Y391727D01*
Y391227D01*
X981240Y390727D01*
X981657Y390227D01*
X982157Y389893D01*
X982740Y389810D01*
X983323Y389977D01*
X983907Y390477D01*
G01X986840Y390393D02*
X987257Y390060D01*
X987840Y389810D01*
X988340D01*
X988840Y389977D01*
X989173Y390227D01*
X989340Y390560D01*
X989257Y391060D01*
X988923Y391310D01*
X987423Y391810D01*
X987090Y392393D01*
X987257Y392810D01*
X987590Y393060D01*
X988090Y393143D01*
X988590Y393060D01*
X989090Y392810D01*
G01X993690Y393143D02*
Y389810D01*
G01Y394477D02*
X993523Y394560D01*
Y394727D01*
X993690Y394810D01*
X993857Y394727D01*
Y394560D01*
X993690Y394477D01*
G01X997873Y389810D02*
Y393143D01*
G01Y392310D02*
X998207Y392727D01*
X998707Y393060D01*
X999373Y393143D01*
X999957Y393060D01*
X1000457Y392727D01*
X1000707Y392143D01*
Y389810D01*
G01X812000Y604500D02*
Y366000D01*
G01X823500Y455500D02*
Y458833D01*
G01Y458250D02*
X823167Y458583D01*
X822667Y458750D01*
X822083Y458833D01*
X821500Y458667D01*
X821000Y458333D01*
X820667Y457833D01*
X820500Y457167D01*
X820667Y456500D01*
X821000Y456000D01*
X821500Y455667D01*
X822083Y455500D01*
X822667Y455583D01*
X823167Y455833D01*
X823500Y456167D01*
G01X826183Y455500D02*
Y458833D01*
G01Y458000D02*
X826517Y458417D01*
X827017Y458750D01*
X827683Y458833D01*
X828267Y458750D01*
X828767Y458417D01*
X829017Y457833D01*
Y455500D01*
G01X834700Y460500D02*
Y455500D01*
G01Y456250D02*
X834367Y455833D01*
X833867Y455583D01*
X833283Y455500D01*
X832617Y455667D01*
X832117Y456083D01*
X831783Y456583D01*
X831700Y457167D01*
X831783Y457750D01*
X832117Y458250D01*
X832617Y458667D01*
X833283Y458833D01*
X833867Y458750D01*
X834283Y458583D01*
X834700Y458250D01*
G01X842900Y455500D02*
Y460500D01*
G01Y458000D02*
X843317Y458500D01*
X843817Y458750D01*
X844317Y458833D01*
X845067Y458667D01*
X845567Y458333D01*
X845900Y457750D01*
Y457083D01*
X845733Y456417D01*
X845400Y455917D01*
X844817Y455583D01*
X844317Y455500D01*
X843817Y455583D01*
X843317Y455833D01*
X842900Y456250D01*
G01X850000Y455500D02*
X849500Y455583D01*
X849000Y455917D01*
X848667Y456500D01*
X848500Y457167D01*
X848667Y457833D01*
X849000Y458417D01*
X849500Y458750D01*
X850000Y458833D01*
X850500Y458750D01*
X851000Y458417D01*
X851333Y457833D01*
X851417Y457167D01*
X851333Y456500D01*
X851000Y455917D01*
X850500Y455583D01*
X850000Y455500D01*
G01X855600Y460500D02*
Y455500D01*
G01X854433Y458833D02*
X856767D01*
G01X861200Y460500D02*
Y455500D01*
G01X860033Y458833D02*
X862367D01*
G01X866800Y455500D02*
X866300Y455583D01*
X865800Y455917D01*
X865467Y456500D01*
X865300Y457167D01*
X865467Y457833D01*
X865800Y458417D01*
X866300Y458750D01*
X866800Y458833D01*
X867300Y458750D01*
X867800Y458417D01*
X868133Y457833D01*
X868217Y457167D01*
X868133Y456500D01*
X867800Y455917D01*
X867300Y455583D01*
X866800Y455500D01*
G01X869900D02*
Y458833D01*
G01Y457917D02*
X870150Y458333D01*
X870567Y458667D01*
X871150Y458833D01*
X871733Y458667D01*
X872150Y458333D01*
X872400Y457917D01*
Y455500D01*
G01Y457917D02*
X872650Y458333D01*
X873067Y458667D01*
X873650Y458833D01*
X874233Y458667D01*
X874650Y458333D01*
X874900Y457833D01*
Y455500D01*
G01X882350Y456083D02*
X882767Y455750D01*
X883350Y455500D01*
X883850D01*
X884350Y455667D01*
X884683Y455917D01*
X884850Y456250D01*
X884767Y456750D01*
X884433Y457000D01*
X882933Y457500D01*
X882600Y458083D01*
X882767Y458500D01*
X883100Y458750D01*
X883600Y458833D01*
X884100Y458750D01*
X884600Y458500D01*
G01X889200Y458833D02*
Y455500D01*
G01Y460167D02*
X889033Y460250D01*
Y460417D01*
X889200Y460500D01*
X889367Y460417D01*
Y460250D01*
X889200Y460167D01*
G01X896300Y460500D02*
Y455500D01*
G01Y456250D02*
X895967Y455833D01*
X895467Y455583D01*
X894883Y455500D01*
X894217Y455667D01*
X893717Y456083D01*
X893383Y456583D01*
X893300Y457167D01*
X893383Y457750D01*
X893717Y458250D01*
X894217Y458667D01*
X894883Y458833D01*
X895467Y458750D01*
X895883Y458583D01*
X896300Y458250D01*
G01X899150Y457750D02*
X901817D01*
X901567Y458333D01*
X901150Y458667D01*
X900567Y458833D01*
X899983Y458750D01*
X899483Y458500D01*
X899150Y457917D01*
X898983Y457417D01*
Y456917D01*
X899150Y456417D01*
X899567Y455917D01*
X900067Y455583D01*
X900650Y455500D01*
X901233Y455667D01*
X901817Y456167D01*
G01X819917Y470833D02*
X820917Y467500D01*
X822000Y470833D01*
X823083Y467500D01*
X824083Y470833D01*
G01X827600D02*
Y467500D01*
G01Y472167D02*
X827433Y472250D01*
Y472417D01*
X827600Y472500D01*
X827767Y472417D01*
Y472250D01*
X827600Y472167D01*
G01X833200Y472500D02*
Y467500D01*
G01X832033Y470833D02*
X834367D01*
G01X837383Y467500D02*
Y472500D01*
G01Y470083D02*
X837800Y470500D01*
X838217Y470750D01*
X838883Y470833D01*
X839383Y470750D01*
X839967Y470417D01*
X840217Y469917D01*
Y467500D01*
G01X844400D02*
X843900Y467583D01*
X843400Y467917D01*
X843067Y468500D01*
X842900Y469167D01*
X843067Y469833D01*
X843400Y470417D01*
X843900Y470750D01*
X844400Y470833D01*
X844900Y470750D01*
X845400Y470417D01*
X845733Y469833D01*
X845817Y469167D01*
X845733Y468500D01*
X845400Y467917D01*
X844900Y467583D01*
X844400Y467500D01*
G01X848583Y470833D02*
Y468500D01*
X848917Y467917D01*
X849417Y467583D01*
X850000Y467500D01*
X850583Y467583D01*
X851083Y467917D01*
X851417Y468500D01*
G01Y467500D02*
Y470833D01*
G01X855600Y472500D02*
Y467500D01*
G01X854433Y470833D02*
X856767D01*
G01X865550Y468083D02*
X865967Y467750D01*
X866550Y467500D01*
X867050D01*
X867550Y467667D01*
X867883Y467917D01*
X868050Y468250D01*
X867967Y468750D01*
X867633Y469000D01*
X866133Y469500D01*
X865800Y470083D01*
X865967Y470500D01*
X866300Y470750D01*
X866800Y470833D01*
X867300Y470750D01*
X867800Y470500D01*
G01X872400Y467500D02*
X871900Y467583D01*
X871400Y467917D01*
X871067Y468500D01*
X870900Y469167D01*
X871067Y469833D01*
X871400Y470417D01*
X871900Y470750D01*
X872400Y470833D01*
X872900Y470750D01*
X873400Y470417D01*
X873733Y469833D01*
X873817Y469167D01*
X873733Y468500D01*
X873400Y467917D01*
X872900Y467583D01*
X872400Y467500D01*
G01X878000D02*
Y472500D01*
G01X885100D02*
Y467500D01*
G01Y468250D02*
X884767Y467833D01*
X884267Y467583D01*
X883683Y467500D01*
X883017Y467667D01*
X882517Y468083D01*
X882183Y468583D01*
X882100Y469167D01*
X882183Y469750D01*
X882517Y470250D01*
X883017Y470667D01*
X883683Y470833D01*
X884267Y470750D01*
X884683Y470583D01*
X885100Y470250D01*
G01X887950Y469750D02*
X890617D01*
X890367Y470333D01*
X889950Y470667D01*
X889367Y470833D01*
X888783Y470750D01*
X888283Y470500D01*
X887950Y469917D01*
X887783Y469417D01*
Y468917D01*
X887950Y468417D01*
X888367Y467917D01*
X888867Y467583D01*
X889450Y467500D01*
X890033Y467667D01*
X890617Y468167D01*
G01X893633Y467500D02*
Y470833D01*
G01Y470167D02*
X894050Y470500D01*
X894467Y470750D01*
X895050Y470833D01*
X895467Y470750D01*
X895967Y470500D01*
G01X903500Y467500D02*
Y470833D01*
G01Y469917D02*
X903750Y470333D01*
X904167Y470667D01*
X904750Y470833D01*
X905333Y470667D01*
X905750Y470333D01*
X906000Y469917D01*
Y467500D01*
G01Y469917D02*
X906250Y470333D01*
X906667Y470667D01*
X907250Y470833D01*
X907833Y470667D01*
X908250Y470333D01*
X908500Y469833D01*
Y467500D01*
G01X913100D02*
Y470833D01*
G01Y470250D02*
X912767Y470583D01*
X912267Y470750D01*
X911683Y470833D01*
X911100Y470667D01*
X910600Y470333D01*
X910267Y469833D01*
X910100Y469167D01*
X910267Y468500D01*
X910600Y468000D01*
X911100Y467667D01*
X911683Y467500D01*
X912267Y467583D01*
X912767Y467833D01*
X913100Y468167D01*
G01X915950Y468083D02*
X916367Y467750D01*
X916950Y467500D01*
X917450D01*
X917950Y467667D01*
X918283Y467917D01*
X918450Y468250D01*
X918367Y468750D01*
X918033Y469000D01*
X916533Y469500D01*
X916200Y470083D01*
X916367Y470500D01*
X916700Y470750D01*
X917200Y470833D01*
X917700Y470750D01*
X918200Y470500D01*
G01X921383Y467500D02*
Y472500D01*
G01X924050Y470833D02*
X921383Y468917D01*
G01X922467Y469667D02*
X924217Y467500D01*
G01X932500Y465833D02*
Y470833D01*
G01Y470083D02*
X932917Y470500D01*
X933333Y470750D01*
X934000Y470833D01*
X934583Y470750D01*
X935167Y470333D01*
X935417Y469750D01*
X935500Y469167D01*
X935417Y468583D01*
X935167Y468000D01*
X934667Y467667D01*
X934000Y467500D01*
X933417Y467583D01*
X932833Y467833D01*
X932500Y468167D01*
G01X941100Y467500D02*
Y470833D01*
G01Y470250D02*
X940767Y470583D01*
X940267Y470750D01*
X939683Y470833D01*
X939100Y470667D01*
X938600Y470333D01*
X938267Y469833D01*
X938100Y469167D01*
X938267Y468500D01*
X938600Y468000D01*
X939100Y467667D01*
X939683Y467500D01*
X940267Y467583D01*
X940767Y467833D01*
X941100Y468167D01*
G01X946700Y472500D02*
Y467500D01*
G01Y468250D02*
X946367Y467833D01*
X945867Y467583D01*
X945283Y467500D01*
X944617Y467667D01*
X944117Y468083D01*
X943783Y468583D01*
X943700Y469167D01*
X943783Y469750D01*
X944117Y470250D01*
X944617Y470667D01*
X945283Y470833D01*
X945867Y470750D01*
X946283Y470583D01*
X946700Y470250D01*
G01X956400Y467500D02*
X955900Y467583D01*
X955400Y467917D01*
X955067Y468500D01*
X954900Y469167D01*
X955067Y469833D01*
X955400Y470417D01*
X955900Y470750D01*
X956400Y470833D01*
X956900Y470750D01*
X957400Y470417D01*
X957733Y469833D01*
X957817Y469167D01*
X957733Y468500D01*
X957400Y467917D01*
X956900Y467583D01*
X956400Y467500D01*
G01X960583D02*
Y470833D01*
G01Y470000D02*
X960917Y470417D01*
X961417Y470750D01*
X962083Y470833D01*
X962667Y470750D01*
X963167Y470417D01*
X963417Y469833D01*
Y467500D01*
G01X973200Y472500D02*
Y467500D01*
G01X972033Y470833D02*
X974367D01*
G01X978800Y467500D02*
X978300Y467583D01*
X977800Y467917D01*
X977467Y468500D01*
X977300Y469167D01*
X977467Y469833D01*
X977800Y470417D01*
X978300Y470750D01*
X978800Y470833D01*
X979300Y470750D01*
X979800Y470417D01*
X980133Y469833D01*
X980217Y469167D01*
X980133Y468500D01*
X979800Y467917D01*
X979300Y467583D01*
X978800Y467500D01*
G01X982900Y465833D02*
Y470833D01*
G01Y470083D02*
X983317Y470500D01*
X983733Y470750D01*
X984400Y470833D01*
X984983Y470750D01*
X985567Y470333D01*
X985817Y469750D01*
X985900Y469167D01*
X985817Y468583D01*
X985567Y468000D01*
X985067Y467667D01*
X984400Y467500D01*
X983817Y467583D01*
X983233Y467833D01*
X982900Y468167D01*
G01X821500Y440500D02*
Y444750D01*
X821667Y445167D01*
X822000Y445417D01*
X822500Y445500D01*
X823000Y445333D01*
X823250Y444917D01*
G01X822250Y443500D02*
X820583D01*
G01X827600Y440500D02*
X827100Y440583D01*
X826600Y440917D01*
X826267Y441500D01*
X826100Y442167D01*
X826267Y442833D01*
X826600Y443417D01*
X827100Y443750D01*
X827600Y443833D01*
X828100Y443750D01*
X828600Y443417D01*
X828933Y442833D01*
X829017Y442167D01*
X828933Y441500D01*
X828600Y440917D01*
X828100Y440583D01*
X827600Y440500D01*
G01X833200D02*
Y445500D01*
G01X838800Y440500D02*
Y445500D01*
G01X844400Y440500D02*
X843900Y440583D01*
X843400Y440917D01*
X843067Y441500D01*
X842900Y442167D01*
X843067Y442833D01*
X843400Y443417D01*
X843900Y443750D01*
X844400Y443833D01*
X844900Y443750D01*
X845400Y443417D01*
X845733Y442833D01*
X845817Y442167D01*
X845733Y441500D01*
X845400Y440917D01*
X844900Y440583D01*
X844400Y440500D01*
G01X847917Y443833D02*
X848917Y440500D01*
X850000Y443833D01*
X851083Y440500D01*
X852083Y443833D01*
G01X861700Y443000D02*
X863367D01*
Y441500D01*
X862867Y441000D01*
X862283Y440667D01*
X861450Y440500D01*
X860617Y440667D01*
X860033Y441000D01*
X859533Y441500D01*
X859200Y442083D01*
X859033Y442750D01*
Y443333D01*
X859200Y443833D01*
X859533Y444417D01*
X860033Y444917D01*
X860533Y445250D01*
X861200Y445500D01*
X861783D01*
X862450Y445333D01*
X862950Y445000D01*
G01X865550Y442750D02*
X868217D01*
X867967Y443333D01*
X867550Y443667D01*
X866967Y443833D01*
X866383Y443750D01*
X865883Y443500D01*
X865550Y442917D01*
X865383Y442417D01*
Y441917D01*
X865550Y441417D01*
X865967Y440917D01*
X866467Y440583D01*
X867050Y440500D01*
X867633Y440667D01*
X868217Y441167D01*
G01X871233Y440500D02*
Y443833D01*
G01Y443167D02*
X871650Y443500D01*
X872067Y443750D01*
X872650Y443833D01*
X873067Y443750D01*
X873567Y443500D01*
G01X876500Y440500D02*
Y445500D01*
G01Y443000D02*
X876917Y443500D01*
X877417Y443750D01*
X877917Y443833D01*
X878667Y443667D01*
X879167Y443333D01*
X879500Y442750D01*
Y442083D01*
X879333Y441417D01*
X879000Y440917D01*
X878417Y440583D01*
X877917Y440500D01*
X877417Y440583D01*
X876917Y440833D01*
X876500Y441250D01*
G01X882350Y442750D02*
X885017D01*
X884767Y443333D01*
X884350Y443667D01*
X883767Y443833D01*
X883183Y443750D01*
X882683Y443500D01*
X882350Y442917D01*
X882183Y442417D01*
Y441917D01*
X882350Y441417D01*
X882767Y440917D01*
X883267Y440583D01*
X883850Y440500D01*
X884433Y440667D01*
X885017Y441167D01*
G01X888033Y440500D02*
Y443833D01*
G01Y443167D02*
X888450Y443500D01*
X888867Y443750D01*
X889450Y443833D01*
X889867Y443750D01*
X890367Y443500D01*
G01X822000Y569000D02*
Y574000D01*
X821000Y573000D01*
G01Y569000D02*
X823000D01*
G01X827600Y568833D02*
X827433Y568917D01*
Y569083D01*
X827600Y569167D01*
X827767Y569083D01*
Y568917D01*
X827600Y568833D01*
G01X833200Y569000D02*
X832533Y569083D01*
X831950Y569417D01*
X831450Y569917D01*
X831117Y570500D01*
X830950Y571167D01*
Y571833D01*
X831117Y572500D01*
X831450Y573083D01*
X831950Y573583D01*
X832533Y573917D01*
X833200Y574000D01*
X833867Y573917D01*
X834450Y573583D01*
X834950Y573083D01*
X835283Y572500D01*
X835450Y571833D01*
Y571167D01*
X835283Y570500D01*
X834950Y569917D01*
X834450Y569417D01*
X833867Y569083D01*
X833200Y569000D01*
G01X837383D02*
Y572333D01*
G01Y571500D02*
X837717Y571917D01*
X838217Y572250D01*
X838883Y572333D01*
X839467Y572250D01*
X839967Y571917D01*
X840217Y571333D01*
Y569000D01*
G01X843150Y571250D02*
X845817D01*
X845567Y571833D01*
X845150Y572167D01*
X844567Y572333D01*
X843983Y572250D01*
X843483Y572000D01*
X843150Y571417D01*
X842983Y570917D01*
Y570417D01*
X843150Y569917D01*
X843567Y569417D01*
X844067Y569083D01*
X844650Y569000D01*
X845233Y569167D01*
X845817Y569667D01*
G01X854350Y569583D02*
X854767Y569250D01*
X855350Y569000D01*
X855850D01*
X856350Y569167D01*
X856683Y569417D01*
X856850Y569750D01*
X856767Y570250D01*
X856433Y570500D01*
X854933Y571000D01*
X854600Y571583D01*
X854767Y572000D01*
X855100Y572250D01*
X855600Y572333D01*
X856100Y572250D01*
X856600Y572000D01*
G01X861200Y572333D02*
Y569000D01*
G01Y573667D02*
X861033Y573750D01*
Y573917D01*
X861200Y574000D01*
X861367Y573917D01*
Y573750D01*
X861200Y573667D01*
G01X868300Y574000D02*
Y569000D01*
G01Y569750D02*
X867967Y569333D01*
X867467Y569083D01*
X866883Y569000D01*
X866217Y569167D01*
X865717Y569583D01*
X865383Y570083D01*
X865300Y570667D01*
X865383Y571250D01*
X865717Y571750D01*
X866217Y572167D01*
X866883Y572333D01*
X867467Y572250D01*
X867883Y572083D01*
X868300Y571750D01*
G01X871150Y571250D02*
X873817D01*
X873567Y571833D01*
X873150Y572167D01*
X872567Y572333D01*
X871983Y572250D01*
X871483Y572000D01*
X871150Y571417D01*
X870983Y570917D01*
Y570417D01*
X871150Y569917D01*
X871567Y569417D01*
X872067Y569083D01*
X872650Y569000D01*
X873233Y569167D01*
X873817Y569667D01*
G01X881517Y572333D02*
X882517Y569000D01*
X883600Y572333D01*
X884683Y569000D01*
X885683Y572333D01*
G01X889200D02*
Y569000D01*
G01Y573667D02*
X889033Y573750D01*
Y573917D01*
X889200Y574000D01*
X889367Y573917D01*
Y573750D01*
X889200Y573667D01*
G01X894800Y574000D02*
Y569000D01*
G01X893633Y572333D02*
X895967D01*
G01X898983Y569000D02*
Y574000D01*
G01Y571583D02*
X899400Y572000D01*
X899817Y572250D01*
X900483Y572333D01*
X900983Y572250D01*
X901567Y571917D01*
X901817Y571417D01*
Y569000D01*
G01X910350Y569583D02*
X910767Y569250D01*
X911350Y569000D01*
X911850D01*
X912350Y569167D01*
X912683Y569417D01*
X912850Y569750D01*
X912767Y570250D01*
X912433Y570500D01*
X910933Y571000D01*
X910600Y571583D01*
X910767Y572000D01*
X911100Y572250D01*
X911600Y572333D01*
X912100Y572250D01*
X912600Y572000D01*
G01X917200Y569000D02*
X916700Y569083D01*
X916200Y569417D01*
X915867Y570000D01*
X915700Y570667D01*
X915867Y571333D01*
X916200Y571917D01*
X916700Y572250D01*
X917200Y572333D01*
X917700Y572250D01*
X918200Y571917D01*
X918533Y571333D01*
X918617Y570667D01*
X918533Y570000D01*
X918200Y569417D01*
X917700Y569083D01*
X917200Y569000D01*
G01X922800D02*
Y574000D01*
G01X929900D02*
Y569000D01*
G01Y569750D02*
X929567Y569333D01*
X929067Y569083D01*
X928483Y569000D01*
X927817Y569167D01*
X927317Y569583D01*
X926983Y570083D01*
X926900Y570667D01*
X926983Y571250D01*
X927317Y571750D01*
X927817Y572167D01*
X928483Y572333D01*
X929067Y572250D01*
X929483Y572083D01*
X929900Y571750D01*
G01X932750Y571250D02*
X935417D01*
X935167Y571833D01*
X934750Y572167D01*
X934167Y572333D01*
X933583Y572250D01*
X933083Y572000D01*
X932750Y571417D01*
X932583Y570917D01*
Y570417D01*
X932750Y569917D01*
X933167Y569417D01*
X933667Y569083D01*
X934250Y569000D01*
X934833Y569167D01*
X935417Y569667D01*
G01X938433Y569000D02*
Y572333D01*
G01Y571667D02*
X938850Y572000D01*
X939267Y572250D01*
X939850Y572333D01*
X940267Y572250D01*
X940767Y572000D01*
G01X948300Y569000D02*
Y572333D01*
G01Y571417D02*
X948550Y571833D01*
X948967Y572167D01*
X949550Y572333D01*
X950133Y572167D01*
X950550Y571833D01*
X950800Y571417D01*
Y569000D01*
G01Y571417D02*
X951050Y571833D01*
X951467Y572167D01*
X952050Y572333D01*
X952633Y572167D01*
X953050Y571833D01*
X953300Y571333D01*
Y569000D01*
G01X957900D02*
Y572333D01*
G01Y571750D02*
X957567Y572083D01*
X957067Y572250D01*
X956483Y572333D01*
X955900Y572167D01*
X955400Y571833D01*
X955067Y571333D01*
X954900Y570667D01*
X955067Y570000D01*
X955400Y569500D01*
X955900Y569167D01*
X956483Y569000D01*
X957067Y569083D01*
X957567Y569333D01*
X957900Y569667D01*
G01X960750Y569583D02*
X961167Y569250D01*
X961750Y569000D01*
X962250D01*
X962750Y569167D01*
X963083Y569417D01*
X963250Y569750D01*
X963167Y570250D01*
X962833Y570500D01*
X961333Y571000D01*
X961000Y571583D01*
X961167Y572000D01*
X961500Y572250D01*
X962000Y572333D01*
X962500Y572250D01*
X963000Y572000D01*
G01X966183Y569000D02*
Y574000D01*
G01X968850Y572333D02*
X966183Y570417D01*
G01X967267Y571167D02*
X969017Y569000D01*
G01X977300Y567333D02*
Y572333D01*
G01Y571583D02*
X977717Y572000D01*
X978133Y572250D01*
X978800Y572333D01*
X979383Y572250D01*
X979967Y571833D01*
X980217Y571250D01*
X980300Y570667D01*
X980217Y570083D01*
X979967Y569500D01*
X979467Y569167D01*
X978800Y569000D01*
X978217Y569083D01*
X977633Y569333D01*
X977300Y569667D01*
G01X985900Y569000D02*
Y572333D01*
G01Y571750D02*
X985567Y572083D01*
X985067Y572250D01*
X984483Y572333D01*
X983900Y572167D01*
X983400Y571833D01*
X983067Y571333D01*
X982900Y570667D01*
X983067Y570000D01*
X983400Y569500D01*
X983900Y569167D01*
X984483Y569000D01*
X985067Y569083D01*
X985567Y569333D01*
X985900Y569667D01*
G01X991500Y574000D02*
Y569000D01*
G01Y569750D02*
X991167Y569333D01*
X990667Y569083D01*
X990083Y569000D01*
X989417Y569167D01*
X988917Y569583D01*
X988583Y570083D01*
X988500Y570667D01*
X988583Y571250D01*
X988917Y571750D01*
X989417Y572167D01*
X990083Y572333D01*
X990667Y572250D01*
X991083Y572083D01*
X991500Y571750D01*
G01X794500Y674500D02*
Y669500D01*
G01X793333Y672833D02*
X795667D01*
G01X798683Y669500D02*
Y674500D01*
G01Y672083D02*
X799100Y672500D01*
X799517Y672750D01*
X800183Y672833D01*
X800683Y672750D01*
X801267Y672417D01*
X801517Y671917D01*
Y669500D01*
G01X805700Y672833D02*
Y669500D01*
G01Y674167D02*
X805533Y674250D01*
Y674417D01*
X805700Y674500D01*
X805867Y674417D01*
Y674250D01*
X805700Y674167D01*
G01X812633Y672417D02*
X812050Y672750D01*
X811550Y672833D01*
X810883Y672667D01*
X810383Y672333D01*
X810050Y671750D01*
X809967Y671167D01*
X810050Y670583D01*
X810383Y670083D01*
X810883Y669667D01*
X811550Y669500D01*
X812133Y669667D01*
X812633Y670000D01*
G01X815483Y669500D02*
Y674500D01*
G01X818150Y672833D02*
X815483Y670917D01*
G01X816567Y671667D02*
X818317Y669500D01*
G01X821083D02*
Y672833D01*
G01Y672000D02*
X821417Y672417D01*
X821917Y672750D01*
X822583Y672833D01*
X823167Y672750D01*
X823667Y672417D01*
X823917Y671833D01*
Y669500D01*
G01X826850Y671750D02*
X829517D01*
X829267Y672333D01*
X828850Y672667D01*
X828267Y672833D01*
X827683Y672750D01*
X827183Y672500D01*
X826850Y671917D01*
X826683Y671417D01*
Y670917D01*
X826850Y670417D01*
X827267Y669917D01*
X827767Y669583D01*
X828350Y669500D01*
X828933Y669667D01*
X829517Y670167D01*
G01X832450Y670083D02*
X832867Y669750D01*
X833450Y669500D01*
X833950D01*
X834450Y669667D01*
X834783Y669917D01*
X834950Y670250D01*
X834867Y670750D01*
X834533Y671000D01*
X833033Y671500D01*
X832700Y672083D01*
X832867Y672500D01*
X833200Y672750D01*
X833700Y672833D01*
X834200Y672750D01*
X834700Y672500D01*
G01X838050Y670083D02*
X838467Y669750D01*
X839050Y669500D01*
X839550D01*
X840050Y669667D01*
X840383Y669917D01*
X840550Y670250D01*
X840467Y670750D01*
X840133Y671000D01*
X838633Y671500D01*
X838300Y672083D01*
X838467Y672500D01*
X838800Y672750D01*
X839300Y672833D01*
X839800Y672750D01*
X840300Y672500D01*
G01X809000Y686500D02*
Y691500D01*
G01Y689000D02*
X809417Y689500D01*
X809917Y689750D01*
X810417Y689833D01*
X811167Y689667D01*
X811667Y689333D01*
X812000Y688750D01*
Y688083D01*
X811833Y687417D01*
X811500Y686917D01*
X810917Y686583D01*
X810417Y686500D01*
X809917Y686583D01*
X809417Y686833D01*
X809000Y687250D01*
G01X816100Y686500D02*
X815600Y686583D01*
X815100Y686917D01*
X814767Y687500D01*
X814600Y688167D01*
X814767Y688833D01*
X815100Y689417D01*
X815600Y689750D01*
X816100Y689833D01*
X816600Y689750D01*
X817100Y689417D01*
X817433Y688833D01*
X817517Y688167D01*
X817433Y687500D01*
X817100Y686917D01*
X816600Y686583D01*
X816100Y686500D01*
G01X823200D02*
Y689833D01*
G01Y689250D02*
X822867Y689583D01*
X822367Y689750D01*
X821783Y689833D01*
X821200Y689667D01*
X820700Y689333D01*
X820367Y688833D01*
X820200Y688167D01*
X820367Y687500D01*
X820700Y687000D01*
X821200Y686667D01*
X821783Y686500D01*
X822367Y686583D01*
X822867Y686833D01*
X823200Y687167D01*
G01X826133Y686500D02*
Y689833D01*
G01Y689167D02*
X826550Y689500D01*
X826967Y689750D01*
X827550Y689833D01*
X827967Y689750D01*
X828467Y689500D01*
G01X834400Y691500D02*
Y686500D01*
G01Y687250D02*
X834067Y686833D01*
X833567Y686583D01*
X832983Y686500D01*
X832317Y686667D01*
X831817Y687083D01*
X831483Y687583D01*
X831400Y688167D01*
X831483Y688750D01*
X831817Y689250D01*
X832317Y689667D01*
X832983Y689833D01*
X833567Y689750D01*
X833983Y689583D01*
X834400Y689250D01*
G01X798500Y795500D02*
Y790500D01*
G01X796583Y795500D02*
X800417D01*
G01X802017Y793833D02*
X803017Y790500D01*
X804100Y793833D01*
X805183Y790500D01*
X806183Y793833D01*
G01X809700D02*
Y790500D01*
G01Y795167D02*
X809533Y795250D01*
Y795417D01*
X809700Y795500D01*
X809867Y795417D01*
Y795250D01*
X809700Y795167D01*
G01X814050Y791083D02*
X814467Y790750D01*
X815050Y790500D01*
X815550D01*
X816050Y790667D01*
X816383Y790917D01*
X816550Y791250D01*
X816467Y791750D01*
X816133Y792000D01*
X814633Y792500D01*
X814300Y793083D01*
X814467Y793500D01*
X814800Y793750D01*
X815300Y793833D01*
X815800Y793750D01*
X816300Y793500D01*
G01X820900Y795500D02*
Y790500D01*
G01X819733Y793833D02*
X822067D01*
G01X833600Y790500D02*
Y793833D01*
G01Y793250D02*
X833267Y793583D01*
X832767Y793750D01*
X832183Y793833D01*
X831600Y793667D01*
X831100Y793333D01*
X830767Y792833D01*
X830600Y792167D01*
X830767Y791500D01*
X831100Y791000D01*
X831600Y790667D01*
X832183Y790500D01*
X832767Y790583D01*
X833267Y790833D01*
X833600Y791167D01*
G01X836283Y790500D02*
Y793833D01*
G01Y793000D02*
X836617Y793417D01*
X837117Y793750D01*
X837783Y793833D01*
X838367Y793750D01*
X838867Y793417D01*
X839117Y792833D01*
Y790500D01*
G01X844800Y795500D02*
Y790500D01*
G01Y791250D02*
X844467Y790833D01*
X843967Y790583D01*
X843383Y790500D01*
X842717Y790667D01*
X842217Y791083D01*
X841883Y791583D01*
X841800Y792167D01*
X841883Y792750D01*
X842217Y793250D01*
X842717Y793667D01*
X843383Y793833D01*
X843967Y793750D01*
X844383Y793583D01*
X844800Y793250D01*
G01X853000Y790500D02*
Y795500D01*
G01Y793000D02*
X853417Y793500D01*
X853917Y793750D01*
X854417Y793833D01*
X855167Y793667D01*
X855667Y793333D01*
X856000Y792750D01*
Y792083D01*
X855833Y791417D01*
X855500Y790917D01*
X854917Y790583D01*
X854417Y790500D01*
X853917Y790583D01*
X853417Y790833D01*
X853000Y791250D01*
G01X860100Y790500D02*
X859600Y790583D01*
X859100Y790917D01*
X858767Y791500D01*
X858600Y792167D01*
X858767Y792833D01*
X859100Y793417D01*
X859600Y793750D01*
X860100Y793833D01*
X860600Y793750D01*
X861100Y793417D01*
X861433Y792833D01*
X861517Y792167D01*
X861433Y791500D01*
X861100Y790917D01*
X860600Y790583D01*
X860100Y790500D01*
G01X863617Y793833D02*
X864617Y790500D01*
X865700Y793833D01*
X866783Y790500D01*
X867783Y793833D01*
G01X788000Y850610D02*
Y782110D01*
G01X796833Y826500D02*
Y831500D01*
X798917D01*
X799583Y831250D01*
X800000Y830917D01*
X800167Y830250D01*
X800000Y829583D01*
X799500Y829167D01*
X798917Y828917D01*
X796833D01*
G01X798917D02*
X800167Y826500D01*
G01X804100D02*
X803600Y826583D01*
X803100Y826917D01*
X802767Y827500D01*
X802600Y828167D01*
X802767Y828833D01*
X803100Y829417D01*
X803600Y829750D01*
X804100Y829833D01*
X804600Y829750D01*
X805100Y829417D01*
X805433Y828833D01*
X805517Y828167D01*
X805433Y827500D01*
X805100Y826917D01*
X804600Y826583D01*
X804100Y826500D01*
G01X808283Y829833D02*
Y827500D01*
X808617Y826917D01*
X809117Y826583D01*
X809700Y826500D01*
X810283Y826583D01*
X810783Y826917D01*
X811117Y827500D01*
G01Y826500D02*
Y829833D01*
G01X815300Y831500D02*
Y826500D01*
G01X814133Y829833D02*
X816467D01*
G01X820900D02*
Y826500D01*
G01Y831167D02*
X820733Y831250D01*
Y831417D01*
X820900Y831500D01*
X821067Y831417D01*
Y831250D01*
X820900Y831167D01*
G01X825083Y826500D02*
Y829833D01*
G01Y829000D02*
X825417Y829417D01*
X825917Y829750D01*
X826583Y829833D01*
X827167Y829750D01*
X827667Y829417D01*
X827917Y828833D01*
Y826500D01*
G01X830933Y825250D02*
X831517Y824917D01*
X832183Y824833D01*
X832767Y824917D01*
X833267Y825333D01*
X833600Y825917D01*
Y829833D01*
G01Y829167D02*
X833267Y829500D01*
X832767Y829750D01*
X832183Y829833D01*
X831517Y829667D01*
X831100Y829333D01*
X830767Y828750D01*
X830600Y828167D01*
X830683Y827667D01*
X831017Y827083D01*
X831517Y826667D01*
X832183Y826500D01*
X832683Y826583D01*
X833267Y826917D01*
X833600Y827250D01*
G01X843300Y831500D02*
Y826500D01*
G01X842133Y829833D02*
X844467D01*
G01X848900Y826500D02*
X848400Y826583D01*
X847900Y826917D01*
X847567Y827500D01*
X847400Y828167D01*
X847567Y828833D01*
X847900Y829417D01*
X848400Y829750D01*
X848900Y829833D01*
X849400Y829750D01*
X849900Y829417D01*
X850233Y828833D01*
X850317Y828167D01*
X850233Y827500D01*
X849900Y826917D01*
X849400Y826583D01*
X848900Y826500D01*
G01X854500D02*
Y831500D01*
G01X858850Y828750D02*
X861517D01*
X861267Y829333D01*
X860850Y829667D01*
X860267Y829833D01*
X859683Y829750D01*
X859183Y829500D01*
X858850Y828917D01*
X858683Y828417D01*
Y827917D01*
X858850Y827417D01*
X859267Y826917D01*
X859767Y826583D01*
X860350Y826500D01*
X860933Y826667D01*
X861517Y827167D01*
G01X864533Y826500D02*
Y829833D01*
G01Y829167D02*
X864950Y829500D01*
X865367Y829750D01*
X865950Y829833D01*
X866367Y829750D01*
X866867Y829500D01*
G01X872800Y826500D02*
Y829833D01*
G01Y829250D02*
X872467Y829583D01*
X871967Y829750D01*
X871383Y829833D01*
X870800Y829667D01*
X870300Y829333D01*
X869967Y828833D01*
X869800Y828167D01*
X869967Y827500D01*
X870300Y827000D01*
X870800Y826667D01*
X871383Y826500D01*
X871967Y826583D01*
X872467Y826833D01*
X872800Y827167D01*
G01X875483Y826500D02*
Y829833D01*
G01Y829000D02*
X875817Y829417D01*
X876317Y829750D01*
X876983Y829833D01*
X877567Y829750D01*
X878067Y829417D01*
X878317Y828833D01*
Y826500D01*
G01X883833Y829417D02*
X883250Y829750D01*
X882750Y829833D01*
X882083Y829667D01*
X881583Y829333D01*
X881250Y828750D01*
X881167Y828167D01*
X881250Y827583D01*
X881583Y827083D01*
X882083Y826667D01*
X882750Y826500D01*
X883333Y826667D01*
X883833Y827000D01*
G01X886850Y828750D02*
X889517D01*
X889267Y829333D01*
X888850Y829667D01*
X888267Y829833D01*
X887683Y829750D01*
X887183Y829500D01*
X886850Y828917D01*
X886683Y828417D01*
Y827917D01*
X886850Y827417D01*
X887267Y826917D01*
X887767Y826583D01*
X888350Y826500D01*
X888933Y826667D01*
X889517Y827167D01*
G01X788000Y805500D02*
X1343000D01*
G01X868250Y152000D02*
Y157000D01*
G01X871750D02*
Y152000D01*
G01Y154500D02*
X868250D01*
G01X875600Y152000D02*
X874933Y152083D01*
X874350Y152417D01*
X873850Y152917D01*
X873517Y153500D01*
X873350Y154167D01*
Y154833D01*
X873517Y155500D01*
X873850Y156083D01*
X874350Y156583D01*
X874933Y156917D01*
X875600Y157000D01*
X876267Y156917D01*
X876850Y156583D01*
X877350Y156083D01*
X877683Y155500D01*
X877850Y154833D01*
Y154167D01*
X877683Y153500D01*
X877350Y152917D01*
X876850Y152417D01*
X876267Y152083D01*
X875600Y152000D01*
G01X879533Y157000D02*
Y152000D01*
X882867D01*
G01X888467D02*
X885133D01*
Y157000D01*
X888467D01*
G01X887133Y154583D02*
X885133D01*
G01X912300Y152000D02*
Y155333D01*
G01Y154417D02*
X912550Y154833D01*
X912967Y155167D01*
X913550Y155333D01*
X914133Y155167D01*
X914550Y154833D01*
X914800Y154417D01*
Y152000D01*
G01Y154417D02*
X915050Y154833D01*
X915467Y155167D01*
X916050Y155333D01*
X916633Y155167D01*
X917050Y154833D01*
X917300Y154333D01*
Y152000D01*
G01X920400Y155333D02*
Y152000D01*
G01Y156667D02*
X920233Y156750D01*
Y156917D01*
X920400Y157000D01*
X920567Y156917D01*
Y156750D01*
X920400Y156667D01*
G01X926000Y152000D02*
Y157000D01*
G01X930350Y152583D02*
X930767Y152250D01*
X931350Y152000D01*
X931850D01*
X932350Y152167D01*
X932683Y152417D01*
X932850Y152750D01*
X932767Y153250D01*
X932433Y153500D01*
X930933Y154000D01*
X930600Y154583D01*
X930767Y155000D01*
X931100Y155250D01*
X931600Y155333D01*
X932100Y155250D01*
X932600Y155000D01*
G01X936783Y150333D02*
X935950Y151167D01*
X935533Y152000D01*
Y155333D01*
X935950Y156167D01*
X936783Y157000D01*
G01X941133Y152000D02*
Y157000D01*
X943133D01*
X943800Y156750D01*
X944300Y156167D01*
X944467Y155500D01*
X944300Y154833D01*
X943883Y154333D01*
X943133Y154083D01*
X941133D01*
G01X948400Y157000D02*
Y152000D01*
G01X946483Y157000D02*
X950317D01*
G01X952250Y152000D02*
Y157000D01*
G01X955750D02*
Y152000D01*
G01Y154500D02*
X952250D01*
G01X960017Y150333D02*
X960850Y151167D01*
X961267Y152000D01*
Y155333D01*
X960850Y156167D01*
X960017Y157000D01*
G01X827667Y150500D02*
Y155500D01*
X829333D01*
X830000Y155250D01*
X830500Y154917D01*
X830917Y154417D01*
X831250Y153833D01*
X831333Y153000D01*
X831250Y152167D01*
X830917Y151583D01*
X830500Y151083D01*
X830000Y150750D01*
X829333Y150500D01*
X827667D01*
G01X835100D02*
Y155500D01*
X834100Y154500D01*
G01Y150500D02*
X836100D01*
G01X889267Y349073D02*
X892933Y352740D01*
G01X891100Y353407D02*
Y348407D01*
G01X892933Y349073D02*
X889267Y352740D01*
G01X888600Y350907D02*
X893600D01*
G01X896283Y347573D02*
X895450Y348407D01*
X895033Y349240D01*
Y352573D01*
X895450Y353407D01*
X896283Y354240D01*
G01X900467Y349990D02*
X900967Y349573D01*
X901550Y349323D01*
X902300Y349240D01*
X903050Y349407D01*
X903633Y349740D01*
X904050Y350323D01*
X904133Y350990D01*
X903967Y351657D01*
X903550Y352073D01*
X902967Y352407D01*
X902383Y352490D01*
X901800Y352407D01*
X901050Y352073D01*
X901300Y354240D01*
X903550D01*
G01X907900Y349073D02*
X907733Y349157D01*
Y349323D01*
X907900Y349407D01*
X908067Y349323D01*
Y349157D01*
X907900Y349073D01*
G01X913500Y349240D02*
Y354240D01*
X912500Y353240D01*
G01Y349240D02*
X914500D01*
G01X919517Y347573D02*
X920350Y348407D01*
X920767Y349240D01*
Y352573D01*
X920350Y353407D01*
X919517Y354240D01*
G01X868167Y308167D02*
X868500Y308417D01*
X868750Y308833D01*
X868917Y309417D01*
X868750Y309917D01*
X868417Y310250D01*
X867833Y310500D01*
X865583D01*
Y305500D01*
X868333D01*
X868917Y305833D01*
X869250Y306333D01*
X869417Y306917D01*
X869250Y307500D01*
X868750Y308000D01*
X868167Y308167D01*
X865583D01*
G01X871017Y305500D02*
X873100Y310500D01*
X875183Y305500D01*
G01X874433Y307250D02*
X871767D01*
G01X880533Y310083D02*
X880033Y310333D01*
X879450Y310500D01*
X878783D01*
X878033Y310250D01*
X877450Y309833D01*
X877033Y309333D01*
X876700Y308500D01*
X876617Y307750D01*
X876783Y307000D01*
X877033Y306500D01*
X877533Y306000D01*
X878117Y305667D01*
X878700Y305500D01*
X879283D01*
X879867Y305667D01*
X880367Y305917D01*
X880783Y306250D01*
G01X882467Y305500D02*
Y310500D01*
G01X885633D02*
X882467Y307417D01*
G01X886133Y305500D02*
X883883Y308833D01*
G01X893667Y305500D02*
Y310500D01*
X895333D01*
X896000Y310250D01*
X896500Y309917D01*
X896917Y309417D01*
X897250Y308833D01*
X897333Y308000D01*
X897250Y307167D01*
X896917Y306583D01*
X896500Y306083D01*
X896000Y305750D01*
X895333Y305500D01*
X893667D01*
G01X899433D02*
Y310500D01*
X901517D01*
X902183Y310250D01*
X902600Y309917D01*
X902767Y309250D01*
X902600Y308583D01*
X902100Y308167D01*
X901517Y307917D01*
X899433D01*
G01X901517D02*
X902767Y305500D01*
G01X905700Y310500D02*
X907700D01*
G01X906700D02*
Y305500D01*
G01X905700D02*
X907700D01*
G01X910633Y310500D02*
Y305500D01*
X913967D01*
G01X916233Y310500D02*
Y305500D01*
X919567D01*
G01X943400D02*
Y308833D01*
G01Y307917D02*
X943650Y308333D01*
X944067Y308667D01*
X944650Y308833D01*
X945233Y308667D01*
X945650Y308333D01*
X945900Y307917D01*
Y305500D01*
G01Y307917D02*
X946150Y308333D01*
X946567Y308667D01*
X947150Y308833D01*
X947733Y308667D01*
X948150Y308333D01*
X948400Y307833D01*
Y305500D01*
G01X951500Y308833D02*
Y305500D01*
G01Y310167D02*
X951333Y310250D01*
Y310417D01*
X951500Y310500D01*
X951667Y310417D01*
Y310250D01*
X951500Y310167D01*
G01X957100Y305500D02*
Y310500D01*
G01X961450Y306083D02*
X961867Y305750D01*
X962450Y305500D01*
X962950D01*
X963450Y305667D01*
X963783Y305917D01*
X963950Y306250D01*
X963867Y306750D01*
X963533Y307000D01*
X962033Y307500D01*
X961700Y308083D01*
X961867Y308500D01*
X962200Y308750D01*
X962700Y308833D01*
X963200Y308750D01*
X963700Y308500D01*
G01X967883Y303833D02*
X967050Y304667D01*
X966633Y305500D01*
Y308833D01*
X967050Y309667D01*
X967883Y310500D01*
G01X971983Y305500D02*
Y310500D01*
X975817Y305500D01*
Y310500D01*
G01X977833Y305500D02*
Y310500D01*
X979833D01*
X980500Y310250D01*
X981000Y309667D01*
X981167Y309000D01*
X981000Y308333D01*
X980583Y307833D01*
X979833Y307583D01*
X977833D01*
G01X985100Y310500D02*
Y305500D01*
G01X983183Y310500D02*
X987017D01*
G01X988950Y305500D02*
Y310500D01*
G01X992450D02*
Y305500D01*
G01Y308000D02*
X988950D01*
G01X996717Y303833D02*
X997550Y304667D01*
X997967Y305500D01*
Y308833D01*
X997550Y309667D01*
X996717Y310500D01*
G01X825667Y314500D02*
Y319500D01*
X827333D01*
X828000Y319250D01*
X828500Y318917D01*
X828917Y318417D01*
X829250Y317833D01*
X829333Y317000D01*
X829250Y316167D01*
X828917Y315583D01*
X828500Y315083D01*
X828000Y314750D01*
X827333Y314500D01*
X825667D01*
G01X831517Y318667D02*
X832017Y319167D01*
X832600Y319417D01*
X833267Y319500D01*
X834100Y319333D01*
X834683Y318917D01*
X834850Y318417D01*
X834767Y317917D01*
X834433Y317500D01*
X832767Y316667D01*
X832017Y316083D01*
X831517Y315250D01*
X831350Y314500D01*
X834850D01*
G01X829750Y542583D02*
X830167Y542250D01*
X830750Y542000D01*
X831250D01*
X831750Y542167D01*
X832083Y542417D01*
X832250Y542750D01*
X832167Y543250D01*
X831833Y543500D01*
X830333Y544000D01*
X830000Y544583D01*
X830167Y545000D01*
X830500Y545250D01*
X831000Y545333D01*
X831500Y545250D01*
X832000Y545000D01*
G01X836600Y542000D02*
X836100Y542083D01*
X835600Y542417D01*
X835267Y543000D01*
X835100Y543667D01*
X835267Y544333D01*
X835600Y544917D01*
X836100Y545250D01*
X836600Y545333D01*
X837100Y545250D01*
X837600Y544917D01*
X837933Y544333D01*
X838017Y543667D01*
X837933Y543000D01*
X837600Y542417D01*
X837100Y542083D01*
X836600Y542000D01*
G01X842200D02*
Y547000D01*
G01X849300D02*
Y542000D01*
G01Y542750D02*
X848967Y542333D01*
X848467Y542083D01*
X847883Y542000D01*
X847217Y542167D01*
X846717Y542583D01*
X846383Y543083D01*
X846300Y543667D01*
X846383Y544250D01*
X846717Y544750D01*
X847217Y545167D01*
X847883Y545333D01*
X848467Y545250D01*
X848883Y545083D01*
X849300Y544750D01*
G01X852150Y544250D02*
X854817D01*
X854567Y544833D01*
X854150Y545167D01*
X853567Y545333D01*
X852983Y545250D01*
X852483Y545000D01*
X852150Y544417D01*
X851983Y543917D01*
Y543417D01*
X852150Y542917D01*
X852567Y542417D01*
X853067Y542083D01*
X853650Y542000D01*
X854233Y542167D01*
X854817Y542667D01*
G01X857833Y542000D02*
Y545333D01*
G01Y544667D02*
X858250Y545000D01*
X858667Y545250D01*
X859250Y545333D01*
X859667Y545250D01*
X860167Y545000D01*
G01X867700Y542000D02*
Y545333D01*
G01Y544417D02*
X867950Y544833D01*
X868367Y545167D01*
X868950Y545333D01*
X869533Y545167D01*
X869950Y544833D01*
X870200Y544417D01*
Y542000D01*
G01Y544417D02*
X870450Y544833D01*
X870867Y545167D01*
X871450Y545333D01*
X872033Y545167D01*
X872450Y544833D01*
X872700Y544333D01*
Y542000D01*
G01X877300D02*
Y545333D01*
G01Y544750D02*
X876967Y545083D01*
X876467Y545250D01*
X875883Y545333D01*
X875300Y545167D01*
X874800Y544833D01*
X874467Y544333D01*
X874300Y543667D01*
X874467Y543000D01*
X874800Y542500D01*
X875300Y542167D01*
X875883Y542000D01*
X876467Y542083D01*
X876967Y542333D01*
X877300Y542667D01*
G01X880150Y542583D02*
X880567Y542250D01*
X881150Y542000D01*
X881650D01*
X882150Y542167D01*
X882483Y542417D01*
X882650Y542750D01*
X882567Y543250D01*
X882233Y543500D01*
X880733Y544000D01*
X880400Y544583D01*
X880567Y545000D01*
X880900Y545250D01*
X881400Y545333D01*
X881900Y545250D01*
X882400Y545000D01*
G01X885583Y542000D02*
Y547000D01*
G01X888250Y545333D02*
X885583Y543417D01*
G01X886667Y544167D02*
X888417Y542000D01*
G01X896700Y540333D02*
Y545333D01*
G01Y544583D02*
X897117Y545000D01*
X897533Y545250D01*
X898200Y545333D01*
X898783Y545250D01*
X899367Y544833D01*
X899617Y544250D01*
X899700Y543667D01*
X899617Y543083D01*
X899367Y542500D01*
X898867Y542167D01*
X898200Y542000D01*
X897617Y542083D01*
X897033Y542333D01*
X896700Y542667D01*
G01X905300Y542000D02*
Y545333D01*
G01Y544750D02*
X904967Y545083D01*
X904467Y545250D01*
X903883Y545333D01*
X903300Y545167D01*
X902800Y544833D01*
X902467Y544333D01*
X902300Y543667D01*
X902467Y543000D01*
X902800Y542500D01*
X903300Y542167D01*
X903883Y542000D01*
X904467Y542083D01*
X904967Y542333D01*
X905300Y542667D01*
G01X910900Y547000D02*
Y542000D01*
G01Y542750D02*
X910567Y542333D01*
X910067Y542083D01*
X909483Y542000D01*
X908817Y542167D01*
X908317Y542583D01*
X907983Y543083D01*
X907900Y543667D01*
X907983Y544250D01*
X908317Y544750D01*
X908817Y545167D01*
X909483Y545333D01*
X910067Y545250D01*
X910483Y545083D01*
X910900Y544750D01*
G01X829917Y563333D02*
X830917Y560000D01*
X832000Y563333D01*
X833083Y560000D01*
X834083Y563333D01*
G01X836183Y560000D02*
Y565000D01*
G01Y562583D02*
X836600Y563000D01*
X837017Y563250D01*
X837683Y563333D01*
X838183Y563250D01*
X838767Y562917D01*
X839017Y562417D01*
Y560000D01*
G01X843200Y563333D02*
Y560000D01*
G01Y564667D02*
X843033Y564750D01*
Y564917D01*
X843200Y565000D01*
X843367Y564917D01*
Y564750D01*
X843200Y564667D01*
G01X850133Y562917D02*
X849550Y563250D01*
X849050Y563333D01*
X848383Y563167D01*
X847883Y562833D01*
X847550Y562250D01*
X847467Y561667D01*
X847550Y561083D01*
X847883Y560583D01*
X848383Y560167D01*
X849050Y560000D01*
X849633Y560167D01*
X850133Y560500D01*
G01X852983Y560000D02*
Y565000D01*
G01Y562583D02*
X853400Y563000D01*
X853817Y563250D01*
X854483Y563333D01*
X854983Y563250D01*
X855567Y562917D01*
X855817Y562417D01*
Y560000D01*
G01X864350Y560583D02*
X864767Y560250D01*
X865350Y560000D01*
X865850D01*
X866350Y560167D01*
X866683Y560417D01*
X866850Y560750D01*
X866767Y561250D01*
X866433Y561500D01*
X864933Y562000D01*
X864600Y562583D01*
X864767Y563000D01*
X865100Y563250D01*
X865600Y563333D01*
X866100Y563250D01*
X866600Y563000D01*
G01X871200Y563333D02*
Y560000D01*
G01Y564667D02*
X871033Y564750D01*
Y564917D01*
X871200Y565000D01*
X871367Y564917D01*
Y564750D01*
X871200Y564667D01*
G01X875550Y563333D02*
X878050D01*
X875550Y560000D01*
X878050D01*
G01X881150Y562250D02*
X883817D01*
X883567Y562833D01*
X883150Y563167D01*
X882567Y563333D01*
X881983Y563250D01*
X881483Y563000D01*
X881150Y562417D01*
X880983Y561917D01*
Y561417D01*
X881150Y560917D01*
X881567Y560417D01*
X882067Y560083D01*
X882650Y560000D01*
X883233Y560167D01*
X883817Y560667D01*
G01X893600Y563333D02*
Y560000D01*
G01Y564667D02*
X893433Y564750D01*
Y564917D01*
X893600Y565000D01*
X893767Y564917D01*
Y564750D01*
X893600Y564667D01*
G01X897950Y560583D02*
X898367Y560250D01*
X898950Y560000D01*
X899450D01*
X899950Y560167D01*
X900283Y560417D01*
X900450Y560750D01*
X900367Y561250D01*
X900033Y561500D01*
X898533Y562000D01*
X898200Y562583D01*
X898367Y563000D01*
X898700Y563250D01*
X899200Y563333D01*
X899700Y563250D01*
X900200Y563000D01*
G01X908900Y560000D02*
Y565000D01*
G01Y562500D02*
X909317Y563000D01*
X909817Y563250D01*
X910317Y563333D01*
X911067Y563167D01*
X911567Y562833D01*
X911900Y562250D01*
Y561583D01*
X911733Y560917D01*
X911400Y560417D01*
X910817Y560083D01*
X910317Y560000D01*
X909817Y560083D01*
X909317Y560333D01*
X908900Y560750D01*
G01X916000Y563333D02*
Y560000D01*
G01Y564667D02*
X915833Y564750D01*
Y564917D01*
X916000Y565000D01*
X916167Y564917D01*
Y564750D01*
X916000Y564667D01*
G01X920433Y558750D02*
X921017Y558417D01*
X921683Y558333D01*
X922267Y558417D01*
X922767Y558833D01*
X923100Y559417D01*
Y563333D01*
G01Y562667D02*
X922767Y563000D01*
X922267Y563250D01*
X921683Y563333D01*
X921017Y563167D01*
X920600Y562833D01*
X920267Y562250D01*
X920100Y561667D01*
X920183Y561167D01*
X920517Y560583D01*
X921017Y560167D01*
X921683Y560000D01*
X922183Y560083D01*
X922767Y560417D01*
X923100Y560750D01*
G01X926033Y558750D02*
X926617Y558417D01*
X927283Y558333D01*
X927867Y558417D01*
X928367Y558833D01*
X928700Y559417D01*
Y563333D01*
G01Y562667D02*
X928367Y563000D01*
X927867Y563250D01*
X927283Y563333D01*
X926617Y563167D01*
X926200Y562833D01*
X925867Y562250D01*
X925700Y561667D01*
X925783Y561167D01*
X926117Y560583D01*
X926617Y560167D01*
X927283Y560000D01*
X927783Y560083D01*
X928367Y560417D01*
X928700Y560750D01*
G01X931550Y562250D02*
X934217D01*
X933967Y562833D01*
X933550Y563167D01*
X932967Y563333D01*
X932383Y563250D01*
X931883Y563000D01*
X931550Y562417D01*
X931383Y561917D01*
Y561417D01*
X931550Y560917D01*
X931967Y560417D01*
X932467Y560083D01*
X933050Y560000D01*
X933633Y560167D01*
X934217Y560667D01*
G01X937233Y560000D02*
Y563333D01*
G01Y562667D02*
X937650Y563000D01*
X938067Y563250D01*
X938650Y563333D01*
X939067Y563250D01*
X939567Y563000D01*
G01X949600Y565000D02*
Y560000D01*
G01X948433Y563333D02*
X950767D01*
G01X953783Y560000D02*
Y565000D01*
G01Y562583D02*
X954200Y563000D01*
X954617Y563250D01*
X955283Y563333D01*
X955783Y563250D01*
X956367Y562917D01*
X956617Y562417D01*
Y560000D01*
G01X962300D02*
Y563333D01*
G01Y562750D02*
X961967Y563083D01*
X961467Y563250D01*
X960883Y563333D01*
X960300Y563167D01*
X959800Y562833D01*
X959467Y562333D01*
X959300Y561667D01*
X959467Y561000D01*
X959800Y560500D01*
X960300Y560167D01*
X960883Y560000D01*
X961467Y560083D01*
X961967Y560333D01*
X962300Y560667D01*
G01X964983Y560000D02*
Y563333D01*
G01Y562500D02*
X965317Y562917D01*
X965817Y563250D01*
X966483Y563333D01*
X967067Y563250D01*
X967567Y562917D01*
X967817Y562333D01*
Y560000D01*
G01X979100D02*
Y563333D01*
G01Y562750D02*
X978767Y563083D01*
X978267Y563250D01*
X977683Y563333D01*
X977100Y563167D01*
X976600Y562833D01*
X976267Y562333D01*
X976100Y561667D01*
X976267Y561000D01*
X976600Y560500D01*
X977100Y560167D01*
X977683Y560000D01*
X978267Y560083D01*
X978767Y560333D01*
X979100Y560667D01*
G01X981783Y560000D02*
Y563333D01*
G01Y562500D02*
X982117Y562917D01*
X982617Y563250D01*
X983283Y563333D01*
X983867Y563250D01*
X984367Y562917D01*
X984617Y562333D01*
Y560000D01*
G01X987383D02*
Y563333D01*
G01Y562500D02*
X987717Y562917D01*
X988217Y563250D01*
X988883Y563333D01*
X989467Y563250D01*
X989967Y562917D01*
X990217Y562333D01*
Y560000D01*
G01X992983Y563333D02*
Y561000D01*
X993317Y560417D01*
X993817Y560083D01*
X994400Y560000D01*
X994983Y560083D01*
X995483Y560417D01*
X995817Y561000D01*
G01Y560000D02*
Y563333D01*
G01X1001500Y560000D02*
Y563333D01*
G01Y562750D02*
X1001167Y563083D01*
X1000667Y563250D01*
X1000083Y563333D01*
X999500Y563167D01*
X999000Y562833D01*
X998667Y562333D01*
X998500Y561667D01*
X998667Y561000D01*
X999000Y560500D01*
X999500Y560167D01*
X1000083Y560000D01*
X1000667Y560083D01*
X1001167Y560333D01*
X1001500Y560667D01*
G01X1005600Y560000D02*
Y565000D01*
G01X831333Y551000D02*
Y554333D01*
G01Y553667D02*
X831750Y554000D01*
X832167Y554250D01*
X832750Y554333D01*
X833167Y554250D01*
X833667Y554000D01*
G01X838100Y554333D02*
Y551000D01*
G01Y555667D02*
X837933Y555750D01*
Y555917D01*
X838100Y556000D01*
X838267Y555917D01*
Y555750D01*
X838100Y555667D01*
G01X842283Y551000D02*
Y554333D01*
G01Y553500D02*
X842617Y553917D01*
X843117Y554250D01*
X843783Y554333D01*
X844367Y554250D01*
X844867Y553917D01*
X845117Y553333D01*
Y551000D01*
G01X848133Y549750D02*
X848717Y549417D01*
X849383Y549333D01*
X849967Y549417D01*
X850467Y549833D01*
X850800Y550417D01*
Y554333D01*
G01Y553667D02*
X850467Y554000D01*
X849967Y554250D01*
X849383Y554333D01*
X848717Y554167D01*
X848300Y553833D01*
X847967Y553250D01*
X847800Y552667D01*
X847883Y552167D01*
X848217Y551583D01*
X848717Y551167D01*
X849383Y551000D01*
X849883Y551083D01*
X850467Y551417D01*
X850800Y551750D01*
G01X859250Y551583D02*
X859667Y551250D01*
X860250Y551000D01*
X860750D01*
X861250Y551167D01*
X861583Y551417D01*
X861750Y551750D01*
X861667Y552250D01*
X861333Y552500D01*
X859833Y553000D01*
X859500Y553583D01*
X859667Y554000D01*
X860000Y554250D01*
X860500Y554333D01*
X861000Y554250D01*
X861500Y554000D01*
G01X866100Y554333D02*
Y551000D01*
G01Y555667D02*
X865933Y555750D01*
Y555917D01*
X866100Y556000D01*
X866267Y555917D01*
Y555750D01*
X866100Y555667D01*
G01X870450Y554333D02*
X872950D01*
X870450Y551000D01*
X872950D01*
G01X876050Y553250D02*
X878717D01*
X878467Y553833D01*
X878050Y554167D01*
X877467Y554333D01*
X876883Y554250D01*
X876383Y554000D01*
X876050Y553417D01*
X875883Y552917D01*
Y552417D01*
X876050Y551917D01*
X876467Y551417D01*
X876967Y551083D01*
X877550Y551000D01*
X878133Y551167D01*
X878717Y551667D01*
G01X888333Y550083D02*
X888667Y551167D01*
G01X878000Y591500D02*
X879667D01*
Y590000D01*
X879167Y589500D01*
X878583Y589167D01*
X877750Y589000D01*
X876917Y589167D01*
X876333Y589500D01*
X875833Y590000D01*
X875500Y590583D01*
X875333Y591250D01*
Y591833D01*
X875500Y592333D01*
X875833Y592917D01*
X876333Y593417D01*
X876833Y593750D01*
X877500Y594000D01*
X878083D01*
X878750Y593833D01*
X879250Y593500D01*
G01X881850Y591250D02*
X884517D01*
X884267Y591833D01*
X883850Y592167D01*
X883267Y592333D01*
X882683Y592250D01*
X882183Y592000D01*
X881850Y591417D01*
X881683Y590917D01*
Y590417D01*
X881850Y589917D01*
X882267Y589417D01*
X882767Y589083D01*
X883350Y589000D01*
X883933Y589167D01*
X884517Y589667D01*
G01X887533Y589000D02*
Y592333D01*
G01Y591667D02*
X887950Y592000D01*
X888367Y592250D01*
X888950Y592333D01*
X889367Y592250D01*
X889867Y592000D01*
G01X892800Y589000D02*
Y594000D01*
G01Y591500D02*
X893217Y592000D01*
X893717Y592250D01*
X894217Y592333D01*
X894967Y592167D01*
X895467Y591833D01*
X895800Y591250D01*
Y590583D01*
X895633Y589917D01*
X895300Y589417D01*
X894717Y589083D01*
X894217Y589000D01*
X893717Y589083D01*
X893217Y589333D01*
X892800Y589750D01*
G01X898650Y591250D02*
X901317D01*
X901067Y591833D01*
X900650Y592167D01*
X900067Y592333D01*
X899483Y592250D01*
X898983Y592000D01*
X898650Y591417D01*
X898483Y590917D01*
Y590417D01*
X898650Y589917D01*
X899067Y589417D01*
X899567Y589083D01*
X900150Y589000D01*
X900733Y589167D01*
X901317Y589667D01*
G01X904333Y589000D02*
Y592333D01*
G01Y591667D02*
X904750Y592000D01*
X905167Y592250D01*
X905750Y592333D01*
X906167Y592250D01*
X906667Y592000D01*
G01X918200Y594000D02*
Y589000D01*
G01Y589750D02*
X917867Y589333D01*
X917367Y589083D01*
X916783Y589000D01*
X916117Y589167D01*
X915617Y589583D01*
X915283Y590083D01*
X915200Y590667D01*
X915283Y591250D01*
X915617Y591750D01*
X916117Y592167D01*
X916783Y592333D01*
X917367Y592250D01*
X917783Y592083D01*
X918200Y591750D01*
G01X921050Y591250D02*
X923717D01*
X923467Y591833D01*
X923050Y592167D01*
X922467Y592333D01*
X921883Y592250D01*
X921383Y592000D01*
X921050Y591417D01*
X920883Y590917D01*
Y590417D01*
X921050Y589917D01*
X921467Y589417D01*
X921967Y589083D01*
X922550Y589000D01*
X923133Y589167D01*
X923717Y589667D01*
G01X926650Y589583D02*
X927067Y589250D01*
X927650Y589000D01*
X928150D01*
X928650Y589167D01*
X928983Y589417D01*
X929150Y589750D01*
X929067Y590250D01*
X928733Y590500D01*
X927233Y591000D01*
X926900Y591583D01*
X927067Y592000D01*
X927400Y592250D01*
X927900Y592333D01*
X928400Y592250D01*
X928900Y592000D01*
G01X933500Y592333D02*
Y589000D01*
G01Y593667D02*
X933333Y593750D01*
Y593917D01*
X933500Y594000D01*
X933667Y593917D01*
Y593750D01*
X933500Y593667D01*
G01X937933Y587750D02*
X938517Y587417D01*
X939183Y587333D01*
X939767Y587417D01*
X940267Y587833D01*
X940600Y588417D01*
Y592333D01*
G01Y591667D02*
X940267Y592000D01*
X939767Y592250D01*
X939183Y592333D01*
X938517Y592167D01*
X938100Y591833D01*
X937767Y591250D01*
X937600Y590667D01*
X937683Y590167D01*
X938017Y589583D01*
X938517Y589167D01*
X939183Y589000D01*
X939683Y589083D01*
X940267Y589417D01*
X940600Y589750D01*
G01X943283Y589000D02*
Y592333D01*
G01Y591500D02*
X943617Y591917D01*
X944117Y592250D01*
X944783Y592333D01*
X945367Y592250D01*
X945867Y591917D01*
X946117Y591333D01*
Y589000D01*
G01X843083Y734500D02*
Y739500D01*
G01Y737083D02*
X843500Y737500D01*
X843917Y737750D01*
X844583Y737833D01*
X845083Y737750D01*
X845667Y737417D01*
X845917Y736917D01*
Y734500D01*
G01X851600D02*
Y737833D01*
G01Y737250D02*
X851267Y737583D01*
X850767Y737750D01*
X850183Y737833D01*
X849600Y737667D01*
X849100Y737333D01*
X848767Y736833D01*
X848600Y736167D01*
X848767Y735500D01*
X849100Y735000D01*
X849600Y734667D01*
X850183Y734500D01*
X850767Y734583D01*
X851267Y734833D01*
X851600Y735167D01*
G01X855700Y734500D02*
Y739500D01*
G01X860800Y734500D02*
Y738750D01*
X860967Y739167D01*
X861300Y739417D01*
X861800Y739500D01*
X862300Y739333D01*
X862550Y738917D01*
G01X861550Y737500D02*
X859883D01*
G01X871000Y732833D02*
Y737833D01*
G01Y737083D02*
X871417Y737500D01*
X871833Y737750D01*
X872500Y737833D01*
X873083Y737750D01*
X873667Y737333D01*
X873917Y736750D01*
X874000Y736167D01*
X873917Y735583D01*
X873667Y735000D01*
X873167Y734667D01*
X872500Y734500D01*
X871917Y734583D01*
X871333Y734833D01*
X871000Y735167D01*
G01X878100Y734500D02*
Y739500D01*
G01X882283Y737833D02*
Y735500D01*
X882617Y734917D01*
X883117Y734583D01*
X883700Y734500D01*
X884283Y734583D01*
X884783Y734917D01*
X885117Y735500D01*
G01Y734500D02*
Y737833D01*
G01X888133Y733250D02*
X888717Y732917D01*
X889383Y732833D01*
X889967Y732917D01*
X890467Y733333D01*
X890800Y733917D01*
Y737833D01*
G01Y737167D02*
X890467Y737500D01*
X889967Y737750D01*
X889383Y737833D01*
X888717Y737667D01*
X888300Y737333D01*
X887967Y736750D01*
X887800Y736167D01*
X887883Y735667D01*
X888217Y735083D01*
X888717Y734667D01*
X889383Y734500D01*
X889883Y734583D01*
X890467Y734917D01*
X890800Y735250D01*
G01X893733Y733250D02*
X894317Y732917D01*
X894983Y732833D01*
X895567Y732917D01*
X896067Y733333D01*
X896400Y733917D01*
Y737833D01*
G01Y737167D02*
X896067Y737500D01*
X895567Y737750D01*
X894983Y737833D01*
X894317Y737667D01*
X893900Y737333D01*
X893567Y736750D01*
X893400Y736167D01*
X893483Y735667D01*
X893817Y735083D01*
X894317Y734667D01*
X894983Y734500D01*
X895483Y734583D01*
X896067Y734917D01*
X896400Y735250D01*
G01X900500Y737833D02*
Y734500D01*
G01Y739167D02*
X900333Y739250D01*
Y739417D01*
X900500Y739500D01*
X900667Y739417D01*
Y739250D01*
X900500Y739167D01*
G01X904683Y734500D02*
Y737833D01*
G01Y737000D02*
X905017Y737417D01*
X905517Y737750D01*
X906183Y737833D01*
X906767Y737750D01*
X907267Y737417D01*
X907517Y736833D01*
Y734500D01*
G01X910533Y733250D02*
X911117Y732917D01*
X911783Y732833D01*
X912367Y732917D01*
X912867Y733333D01*
X913200Y733917D01*
Y737833D01*
G01Y737167D02*
X912867Y737500D01*
X912367Y737750D01*
X911783Y737833D01*
X911117Y737667D01*
X910700Y737333D01*
X910367Y736750D01*
X910200Y736167D01*
X910283Y735667D01*
X910617Y735083D01*
X911117Y734667D01*
X911783Y734500D01*
X912283Y734583D01*
X912867Y734917D01*
X913200Y735250D01*
G01X928583Y23083D02*
X929167Y22667D01*
X929833Y22500D01*
X930500Y22667D01*
X931083Y23167D01*
X931500Y23917D01*
X931667Y24667D01*
Y25583D01*
X931500Y26333D01*
X931083Y27000D01*
X930583Y27333D01*
X930000Y27500D01*
X929333Y27333D01*
X928833Y27000D01*
X928500Y26500D01*
X928333Y25833D01*
X928500Y25250D01*
X928917Y24667D01*
X929417Y24333D01*
X930000Y24250D01*
X930667Y24417D01*
X931167Y24833D01*
X931667Y25583D01*
G01X934017Y24583D02*
X934600Y25167D01*
X935100Y25500D01*
X935767Y25667D01*
X936350Y25500D01*
X936767Y25167D01*
X937100Y24667D01*
X937183Y24083D01*
X937100Y23583D01*
X936767Y23083D01*
X936267Y22667D01*
X935683Y22500D01*
X935017Y22667D01*
X934433Y23167D01*
X934100Y23917D01*
X934017Y24750D01*
X934183Y25833D01*
X934433Y26417D01*
X934850Y27000D01*
X935433Y27417D01*
X936017Y27500D01*
X936600Y27333D01*
X937017Y26917D01*
G01X909000Y67500D02*
Y72500D01*
X905917Y68917D01*
X910083D01*
G01X911767Y68250D02*
X912267Y67833D01*
X912850Y67583D01*
X913600Y67500D01*
X914350Y67667D01*
X914933Y68000D01*
X915350Y68583D01*
X915433Y69250D01*
X915267Y69917D01*
X914850Y70333D01*
X914267Y70667D01*
X913683Y70750D01*
X913100Y70667D01*
X912350Y70333D01*
X912600Y72500D01*
X914850D01*
G01X909250Y184083D02*
X909667Y183750D01*
X910250Y183500D01*
X910750D01*
X911250Y183667D01*
X911583Y183917D01*
X911750Y184250D01*
X911667Y184750D01*
X911333Y185000D01*
X909833Y185500D01*
X909500Y186083D01*
X909667Y186500D01*
X910000Y186750D01*
X910500Y186833D01*
X911000Y186750D01*
X911500Y186500D01*
G01X916100Y188500D02*
Y183500D01*
G01X914933Y186833D02*
X917267D01*
G01X920283D02*
Y184500D01*
X920617Y183917D01*
X921117Y183583D01*
X921700Y183500D01*
X922283Y183583D01*
X922783Y183917D01*
X923117Y184500D01*
G01Y183500D02*
Y186833D01*
G01X925800Y183500D02*
Y188500D01*
G01Y186000D02*
X926217Y186500D01*
X926717Y186750D01*
X927217Y186833D01*
X927967Y186667D01*
X928467Y186333D01*
X928800Y185750D01*
Y185083D01*
X928633Y184417D01*
X928300Y183917D01*
X927717Y183583D01*
X927217Y183500D01*
X926717Y183583D01*
X926217Y183833D01*
X925800Y184250D01*
G01X938500Y183500D02*
Y188500D01*
G01X942850Y185750D02*
X945517D01*
X945267Y186333D01*
X944850Y186667D01*
X944267Y186833D01*
X943683Y186750D01*
X943183Y186500D01*
X942850Y185917D01*
X942683Y185417D01*
Y184917D01*
X942850Y184417D01*
X943267Y183917D01*
X943767Y183583D01*
X944350Y183500D01*
X944933Y183667D01*
X945517Y184167D01*
G01X948283Y183500D02*
Y186833D01*
G01Y186000D02*
X948617Y186417D01*
X949117Y186750D01*
X949783Y186833D01*
X950367Y186750D01*
X950867Y186417D01*
X951117Y185833D01*
Y183500D01*
G01X954133Y182250D02*
X954717Y181917D01*
X955383Y181833D01*
X955967Y181917D01*
X956467Y182333D01*
X956800Y182917D01*
Y186833D01*
G01Y186167D02*
X956467Y186500D01*
X955967Y186750D01*
X955383Y186833D01*
X954717Y186667D01*
X954300Y186333D01*
X953967Y185750D01*
X953800Y185167D01*
X953883Y184667D01*
X954217Y184083D01*
X954717Y183667D01*
X955383Y183500D01*
X955883Y183583D01*
X956467Y183917D01*
X956800Y184250D01*
G01X960900Y188500D02*
Y183500D01*
G01X959733Y186833D02*
X962067D01*
G01X965083Y183500D02*
Y188500D01*
G01Y186083D02*
X965500Y186500D01*
X965917Y186750D01*
X966583Y186833D01*
X967083Y186750D01*
X967667Y186417D01*
X967917Y185917D01*
Y183500D01*
G01X971017Y184417D02*
X973183D01*
G01Y185917D02*
X971017D01*
G01X976117Y185583D02*
X976700Y186167D01*
X977200Y186500D01*
X977867Y186667D01*
X978450Y186500D01*
X978867Y186167D01*
X979200Y185667D01*
X979283Y185083D01*
X979200Y184583D01*
X978867Y184083D01*
X978367Y183667D01*
X977783Y183500D01*
X977117Y183667D01*
X976533Y184167D01*
X976200Y184917D01*
X976117Y185750D01*
X976283Y186833D01*
X976533Y187417D01*
X976950Y188000D01*
X977533Y188417D01*
X978117Y188500D01*
X978700Y188333D01*
X979117Y187917D01*
G01X982383Y185167D02*
X984383D01*
G01X983300Y186250D02*
Y184083D01*
G01X987400Y183333D02*
X990400Y188500D01*
G01X993417Y185167D02*
X995583D01*
G01X998267Y184250D02*
X998767Y183833D01*
X999350Y183583D01*
X1000100Y183500D01*
X1000850Y183667D01*
X1001433Y184000D01*
X1001850Y184583D01*
X1001933Y185250D01*
X1001767Y185917D01*
X1001350Y186333D01*
X1000767Y186667D01*
X1000183Y186750D01*
X999600Y186667D01*
X998850Y186333D01*
X999100Y188500D01*
X1001350D01*
G01X1003200Y183500D02*
Y186833D01*
G01Y185917D02*
X1003450Y186333D01*
X1003867Y186667D01*
X1004450Y186833D01*
X1005033Y186667D01*
X1005450Y186333D01*
X1005700Y185917D01*
Y183500D01*
G01Y185917D02*
X1005950Y186333D01*
X1006367Y186667D01*
X1006950Y186833D01*
X1007533Y186667D01*
X1007950Y186333D01*
X1008200Y185833D01*
Y183500D01*
G01X1011300Y186833D02*
Y183500D01*
G01Y188167D02*
X1011133Y188250D01*
Y188417D01*
X1011300Y188500D01*
X1011467Y188417D01*
Y188250D01*
X1011300Y188167D01*
G01X1016900Y183500D02*
Y188500D01*
G01X900833Y214500D02*
Y209500D01*
X904167D01*
G01X906683D02*
Y212833D01*
G01Y212000D02*
X907017Y212417D01*
X907517Y212750D01*
X908183Y212833D01*
X908767Y212750D01*
X909267Y212417D01*
X909517Y211833D01*
Y209500D01*
G01X902833Y255500D02*
Y250500D01*
X906167D01*
G01X908850Y253833D02*
X911350Y250500D01*
G01Y253833D02*
X908850Y250500D01*
G01X894000Y556000D02*
Y551000D01*
G01X892833Y554333D02*
X895167D01*
G01X898183Y551000D02*
Y556000D01*
G01Y553583D02*
X898600Y554000D01*
X899017Y554250D01*
X899683Y554333D01*
X900183Y554250D01*
X900767Y553917D01*
X901017Y553417D01*
Y551000D01*
G01X903950Y553250D02*
X906617D01*
X906367Y553833D01*
X905950Y554167D01*
X905367Y554333D01*
X904783Y554250D01*
X904283Y554000D01*
X903950Y553417D01*
X903783Y552917D01*
Y552417D01*
X903950Y551917D01*
X904367Y551417D01*
X904867Y551083D01*
X905450Y551000D01*
X906033Y551167D01*
X906617Y551667D01*
G01X916400Y551000D02*
X915900Y551083D01*
X915400Y551417D01*
X915067Y552000D01*
X914900Y552667D01*
X915067Y553333D01*
X915400Y553917D01*
X915900Y554250D01*
X916400Y554333D01*
X916900Y554250D01*
X917400Y553917D01*
X917733Y553333D01*
X917817Y552667D01*
X917733Y552000D01*
X917400Y551417D01*
X916900Y551083D01*
X916400Y551000D01*
G01X922000Y556000D02*
Y551000D01*
G01X920833Y554333D02*
X923167D01*
G01X926183Y551000D02*
Y556000D01*
G01Y553583D02*
X926600Y554000D01*
X927017Y554250D01*
X927683Y554333D01*
X928183Y554250D01*
X928767Y553917D01*
X929017Y553417D01*
Y551000D01*
G01X931950Y553250D02*
X934617D01*
X934367Y553833D01*
X933950Y554167D01*
X933367Y554333D01*
X932783Y554250D01*
X932283Y554000D01*
X931950Y553417D01*
X931783Y552917D01*
Y552417D01*
X931950Y551917D01*
X932367Y551417D01*
X932867Y551083D01*
X933450Y551000D01*
X934033Y551167D01*
X934617Y551667D01*
G01X937633Y551000D02*
Y554333D01*
G01Y553667D02*
X938050Y554000D01*
X938467Y554250D01*
X939050Y554333D01*
X939467Y554250D01*
X939967Y554000D01*
G01X948750Y551583D02*
X949167Y551250D01*
X949750Y551000D01*
X950250D01*
X950750Y551167D01*
X951083Y551417D01*
X951250Y551750D01*
X951167Y552250D01*
X950833Y552500D01*
X949333Y553000D01*
X949000Y553583D01*
X949167Y554000D01*
X949500Y554250D01*
X950000Y554333D01*
X950500Y554250D01*
X951000Y554000D01*
G01X955600Y554333D02*
Y551000D01*
G01Y555667D02*
X955433Y555750D01*
Y555917D01*
X955600Y556000D01*
X955767Y555917D01*
Y555750D01*
X955600Y555667D01*
G01X962700Y556000D02*
Y551000D01*
G01Y551750D02*
X962367Y551333D01*
X961867Y551083D01*
X961283Y551000D01*
X960617Y551167D01*
X960117Y551583D01*
X959783Y552083D01*
X959700Y552667D01*
X959783Y553250D01*
X960117Y553750D01*
X960617Y554167D01*
X961283Y554333D01*
X961867Y554250D01*
X962283Y554083D01*
X962700Y553750D01*
G01X965550Y553250D02*
X968217D01*
X967967Y553833D01*
X967550Y554167D01*
X966967Y554333D01*
X966383Y554250D01*
X965883Y554000D01*
X965550Y553417D01*
X965383Y552917D01*
Y552417D01*
X965550Y551917D01*
X965967Y551417D01*
X966467Y551083D01*
X967050Y551000D01*
X967633Y551167D01*
X968217Y551667D01*
G01X975917Y554333D02*
X976917Y551000D01*
X978000Y554333D01*
X979083Y551000D01*
X980083Y554333D01*
G01X983600D02*
Y551000D01*
G01Y555667D02*
X983433Y555750D01*
Y555917D01*
X983600Y556000D01*
X983767Y555917D01*
Y555750D01*
X983600Y555667D01*
G01X989200Y556000D02*
Y551000D01*
G01X988033Y554333D02*
X990367D01*
G01X993383Y551000D02*
Y556000D01*
G01Y553583D02*
X993800Y554000D01*
X994217Y554250D01*
X994883Y554333D01*
X995383Y554250D01*
X995967Y553917D01*
X996217Y553417D01*
Y551000D01*
G01X1000400D02*
X999900Y551083D01*
X999400Y551417D01*
X999067Y552000D01*
X998900Y552667D01*
X999067Y553333D01*
X999400Y553917D01*
X999900Y554250D01*
X1000400Y554333D01*
X1000900Y554250D01*
X1001400Y553917D01*
X1001733Y553333D01*
X1001817Y552667D01*
X1001733Y552000D01*
X1001400Y551417D01*
X1000900Y551083D01*
X1000400Y551000D01*
G01X1004583Y554333D02*
Y552000D01*
X1004917Y551417D01*
X1005417Y551083D01*
X1006000Y551000D01*
X1006583Y551083D01*
X1007083Y551417D01*
X1007417Y552000D01*
G01Y551000D02*
Y554333D01*
G01X1011600Y556000D02*
Y551000D01*
G01X1010433Y554333D02*
X1012767D01*
G01X929000Y734500D02*
Y738750D01*
X929167Y739167D01*
X929500Y739417D01*
X930000Y739500D01*
X930500Y739333D01*
X930750Y738917D01*
G01X929750Y737500D02*
X928083D01*
G01X933683Y737833D02*
Y735500D01*
X934017Y734917D01*
X934517Y734583D01*
X935100Y734500D01*
X935683Y734583D01*
X936183Y734917D01*
X936517Y735500D01*
G01Y734500D02*
Y737833D01*
G01X940700Y734500D02*
Y739500D01*
G01X946300Y734500D02*
Y739500D01*
G01X956000Y732833D02*
Y737833D01*
G01Y737083D02*
X956417Y737500D01*
X956833Y737750D01*
X957500Y737833D01*
X958083Y737750D01*
X958667Y737333D01*
X958917Y736750D01*
X959000Y736167D01*
X958917Y735583D01*
X958667Y735000D01*
X958167Y734667D01*
X957500Y734500D01*
X956917Y734583D01*
X956333Y734833D01*
X956000Y735167D01*
G01X963100Y734500D02*
Y739500D01*
G01X967283Y737833D02*
Y735500D01*
X967617Y734917D01*
X968117Y734583D01*
X968700Y734500D01*
X969283Y734583D01*
X969783Y734917D01*
X970117Y735500D01*
G01Y734500D02*
Y737833D01*
G01X973133Y733250D02*
X973717Y732917D01*
X974383Y732833D01*
X974967Y732917D01*
X975467Y733333D01*
X975800Y733917D01*
Y737833D01*
G01Y737167D02*
X975467Y737500D01*
X974967Y737750D01*
X974383Y737833D01*
X973717Y737667D01*
X973300Y737333D01*
X972967Y736750D01*
X972800Y736167D01*
X972883Y735667D01*
X973217Y735083D01*
X973717Y734667D01*
X974383Y734500D01*
X974883Y734583D01*
X975467Y734917D01*
X975800Y735250D01*
G01X978733Y733250D02*
X979317Y732917D01*
X979983Y732833D01*
X980567Y732917D01*
X981067Y733333D01*
X981400Y733917D01*
Y737833D01*
G01Y737167D02*
X981067Y737500D01*
X980567Y737750D01*
X979983Y737833D01*
X979317Y737667D01*
X978900Y737333D01*
X978567Y736750D01*
X978400Y736167D01*
X978483Y735667D01*
X978817Y735083D01*
X979317Y734667D01*
X979983Y734500D01*
X980483Y734583D01*
X981067Y734917D01*
X981400Y735250D01*
G01X985500Y737833D02*
Y734500D01*
G01Y739167D02*
X985333Y739250D01*
Y739417D01*
X985500Y739500D01*
X985667Y739417D01*
Y739250D01*
X985500Y739167D01*
G01X989683Y734500D02*
Y737833D01*
G01Y737000D02*
X990017Y737417D01*
X990517Y737750D01*
X991183Y737833D01*
X991767Y737750D01*
X992267Y737417D01*
X992517Y736833D01*
Y734500D01*
G01X995533Y733250D02*
X996117Y732917D01*
X996783Y732833D01*
X997367Y732917D01*
X997867Y733333D01*
X998200Y733917D01*
Y737833D01*
G01Y737167D02*
X997867Y737500D01*
X997367Y737750D01*
X996783Y737833D01*
X996117Y737667D01*
X995700Y737333D01*
X995367Y736750D01*
X995200Y736167D01*
X995283Y735667D01*
X995617Y735083D01*
X996117Y734667D01*
X996783Y734500D01*
X997283Y734583D01*
X997867Y734917D01*
X998200Y735250D01*
G01X995667Y5500D02*
Y10500D01*
X997333D01*
X998000Y10250D01*
X998500Y9917D01*
X998917Y9417D01*
X999250Y8833D01*
X999333Y8000D01*
X999250Y7167D01*
X998917Y6583D01*
X998500Y6083D01*
X998000Y5750D01*
X997333Y5500D01*
X995667D01*
G01X1003100D02*
Y10500D01*
X1002100Y9500D01*
G01Y5500D02*
X1004100D01*
G01X1007117Y7583D02*
X1007700Y8167D01*
X1008200Y8500D01*
X1008867Y8667D01*
X1009450Y8500D01*
X1009867Y8167D01*
X1010200Y7667D01*
X1010283Y7083D01*
X1010200Y6583D01*
X1009867Y6083D01*
X1009367Y5667D01*
X1008783Y5500D01*
X1008117Y5667D01*
X1007533Y6167D01*
X1007200Y6917D01*
X1007117Y7750D01*
X1007283Y8833D01*
X1007533Y9417D01*
X1007950Y10000D01*
X1008533Y10417D01*
X1009117Y10500D01*
X1009700Y10333D01*
X1010117Y9917D01*
G01X1014300Y5333D02*
X1014133Y5417D01*
Y5583D01*
X1014300Y5667D01*
X1014467Y5583D01*
Y5417D01*
X1014300Y5333D01*
G01Y7583D02*
X1014133Y7667D01*
Y7833D01*
X1014300Y7917D01*
X1014467Y7833D01*
Y7667D01*
X1014300Y7583D01*
G01X1018067Y5500D02*
Y10500D01*
X1019733D01*
X1020400Y10250D01*
X1020900Y9917D01*
X1021317Y9417D01*
X1021650Y8833D01*
X1021733Y8000D01*
X1021650Y7167D01*
X1021317Y6583D01*
X1020900Y6083D01*
X1020400Y5750D01*
X1019733Y5500D01*
X1018067D01*
G01X1025500Y8833D02*
Y5500D01*
G01Y10167D02*
X1025333Y10250D01*
Y10417D01*
X1025500Y10500D01*
X1025667Y10417D01*
Y10250D01*
X1025500Y10167D01*
G01X1032600Y5500D02*
Y8833D01*
G01Y8250D02*
X1032267Y8583D01*
X1031767Y8750D01*
X1031183Y8833D01*
X1030600Y8667D01*
X1030100Y8333D01*
X1029767Y7833D01*
X1029600Y7167D01*
X1029767Y6500D01*
X1030100Y6000D01*
X1030600Y5667D01*
X1031183Y5500D01*
X1031767Y5583D01*
X1032267Y5833D01*
X1032600Y6167D01*
G01X1034200Y5500D02*
Y8833D01*
G01Y7917D02*
X1034450Y8333D01*
X1034867Y8667D01*
X1035450Y8833D01*
X1036033Y8667D01*
X1036450Y8333D01*
X1036700Y7917D01*
Y5500D01*
G01Y7917D02*
X1036950Y8333D01*
X1037367Y8667D01*
X1037950Y8833D01*
X1038533Y8667D01*
X1038950Y8333D01*
X1039200Y7833D01*
Y5500D01*
G01X1041050Y7750D02*
X1043717D01*
X1043467Y8333D01*
X1043050Y8667D01*
X1042467Y8833D01*
X1041883Y8750D01*
X1041383Y8500D01*
X1041050Y7917D01*
X1040883Y7417D01*
Y6917D01*
X1041050Y6417D01*
X1041467Y5917D01*
X1041967Y5583D01*
X1042550Y5500D01*
X1043133Y5667D01*
X1043717Y6167D01*
G01X1047900Y10500D02*
Y5500D01*
G01X1046733Y8833D02*
X1049067D01*
G01X1052250Y7750D02*
X1054917D01*
X1054667Y8333D01*
X1054250Y8667D01*
X1053667Y8833D01*
X1053083Y8750D01*
X1052583Y8500D01*
X1052250Y7917D01*
X1052083Y7417D01*
Y6917D01*
X1052250Y6417D01*
X1052667Y5917D01*
X1053167Y5583D01*
X1053750Y5500D01*
X1054333Y5667D01*
X1054917Y6167D01*
G01X1057933Y5500D02*
Y8833D01*
G01Y8167D02*
X1058350Y8500D01*
X1058767Y8750D01*
X1059350Y8833D01*
X1059767Y8750D01*
X1060267Y8500D01*
G01X1070300Y5500D02*
Y10500D01*
X1069300Y9500D01*
G01Y5500D02*
X1071300D01*
G01X1074317Y7583D02*
X1074900Y8167D01*
X1075400Y8500D01*
X1076067Y8667D01*
X1076650Y8500D01*
X1077067Y8167D01*
X1077400Y7667D01*
X1077483Y7083D01*
X1077400Y6583D01*
X1077067Y6083D01*
X1076567Y5667D01*
X1075983Y5500D01*
X1075317Y5667D01*
X1074733Y6167D01*
X1074400Y6917D01*
X1074317Y7750D01*
X1074483Y8833D01*
X1074733Y9417D01*
X1075150Y10000D01*
X1075733Y10417D01*
X1076317Y10500D01*
X1076900Y10333D01*
X1077317Y9917D01*
G01X1079000Y5500D02*
Y8833D01*
G01Y7917D02*
X1079250Y8333D01*
X1079667Y8667D01*
X1080250Y8833D01*
X1080833Y8667D01*
X1081250Y8333D01*
X1081500Y7917D01*
Y5500D01*
G01Y7917D02*
X1081750Y8333D01*
X1082167Y8667D01*
X1082750Y8833D01*
X1083333Y8667D01*
X1083750Y8333D01*
X1084000Y7833D01*
Y5500D01*
G01X1087100Y8833D02*
Y5500D01*
G01Y10167D02*
X1086933Y10250D01*
Y10417D01*
X1087100Y10500D01*
X1087267Y10417D01*
Y10250D01*
X1087100Y10167D01*
G01X1092700Y5500D02*
Y10500D01*
G01X980667Y16500D02*
X977333D01*
Y21500D01*
X980667D01*
G01X979333Y19083D02*
X977333D01*
G01X983350Y19833D02*
X985850Y16500D01*
G01Y19833D02*
X983350Y16500D01*
G01X990200Y16333D02*
X990033Y16417D01*
Y16583D01*
X990200Y16667D01*
X990367Y16583D01*
Y16417D01*
X990200Y16333D01*
G01X994050Y16500D02*
Y21500D01*
G01X997550D02*
Y16500D01*
G01Y19000D02*
X994050D01*
G01X999733Y16500D02*
Y21500D01*
X1001817D01*
X1002483Y21250D01*
X1002900Y20917D01*
X1003067Y20250D01*
X1002900Y19583D01*
X1002400Y19167D01*
X1001817Y18917D01*
X999733D01*
G01X1001817D02*
X1003067Y16500D01*
G01X1008667D02*
X1005333D01*
Y21500D01*
X1008667D01*
G01X1007333Y19083D02*
X1005333D01*
G01X1013600Y16500D02*
Y21500D01*
X1010517Y17917D01*
X1014683D01*
G01X1016367Y17250D02*
X1016867Y16833D01*
X1017450Y16583D01*
X1018200Y16500D01*
X1018950Y16667D01*
X1019533Y17000D01*
X1019950Y17583D01*
X1020033Y18250D01*
X1019867Y18917D01*
X1019450Y19333D01*
X1018867Y19667D01*
X1018283Y19750D01*
X1017700Y19667D01*
X1016950Y19333D01*
X1017200Y21500D01*
X1019450D01*
G01X1022050Y16500D02*
X1025550Y21500D01*
G01X1022050D02*
X1025550Y16500D01*
G01X1027983Y17083D02*
X1028567Y16667D01*
X1029233Y16500D01*
X1029900Y16667D01*
X1030483Y17167D01*
X1030900Y17917D01*
X1031067Y18667D01*
Y19583D01*
X1030900Y20333D01*
X1030483Y21000D01*
X1029983Y21333D01*
X1029400Y21500D01*
X1028733Y21333D01*
X1028233Y21000D01*
X1027900Y20500D01*
X1027733Y19833D01*
X1027900Y19250D01*
X1028317Y18667D01*
X1028817Y18333D01*
X1029400Y18250D01*
X1030067Y18417D01*
X1030567Y18833D01*
X1031067Y19583D01*
G01X1033417Y18583D02*
X1034000Y19167D01*
X1034500Y19500D01*
X1035167Y19667D01*
X1035750Y19500D01*
X1036167Y19167D01*
X1036500Y18667D01*
X1036583Y18083D01*
X1036500Y17583D01*
X1036167Y17083D01*
X1035667Y16667D01*
X1035083Y16500D01*
X1034417Y16667D01*
X1033833Y17167D01*
X1033500Y17917D01*
X1033417Y18750D01*
X1033583Y19833D01*
X1033833Y20417D01*
X1034250Y21000D01*
X1034833Y21417D01*
X1035417Y21500D01*
X1036000Y21333D01*
X1036417Y20917D01*
G01X1040183Y14833D02*
X1039350Y15667D01*
X1038933Y16500D01*
Y19833D01*
X1039350Y20667D01*
X1040183Y21500D01*
G01X1044367Y16500D02*
Y21500D01*
X1046033D01*
X1046700Y21250D01*
X1047200Y20917D01*
X1047617Y20417D01*
X1047950Y19833D01*
X1048033Y19000D01*
X1047950Y18167D01*
X1047617Y17583D01*
X1047200Y17083D01*
X1046700Y16750D01*
X1046033Y16500D01*
X1044367D01*
G01X1051800D02*
Y21500D01*
X1050800Y20500D01*
G01Y16500D02*
X1052800D01*
G01X1055817Y18583D02*
X1056400Y19167D01*
X1056900Y19500D01*
X1057567Y19667D01*
X1058150Y19500D01*
X1058567Y19167D01*
X1058900Y18667D01*
X1058983Y18083D01*
X1058900Y17583D01*
X1058567Y17083D01*
X1058067Y16667D01*
X1057483Y16500D01*
X1056817Y16667D01*
X1056233Y17167D01*
X1055900Y17917D01*
X1055817Y18750D01*
X1055983Y19833D01*
X1056233Y20417D01*
X1056650Y21000D01*
X1057233Y21417D01*
X1057817Y21500D01*
X1058400Y21333D01*
X1058817Y20917D01*
G01X1061250Y16500D02*
X1064750Y21500D01*
G01X1061250D02*
X1064750Y16500D01*
G01X1069600D02*
Y21500D01*
X1066517Y17917D01*
X1070683D01*
G01X1074617Y14833D02*
X1075450Y15667D01*
X1075867Y16500D01*
Y19833D01*
X1075450Y20667D01*
X1074617Y21500D01*
G01X977333Y65500D02*
Y70500D01*
X979417D01*
X980083Y70250D01*
X980500Y69917D01*
X980667Y69250D01*
X980500Y68583D01*
X980000Y68167D01*
X979417Y67917D01*
X977333D01*
G01X979417D02*
X980667Y65500D01*
G01X986267D02*
X982933D01*
Y70500D01*
X986267D01*
G01X984933Y68083D02*
X982933D01*
G01X992033Y70083D02*
X991533Y70333D01*
X990950Y70500D01*
X990283D01*
X989533Y70250D01*
X988950Y69833D01*
X988533Y69333D01*
X988200Y68500D01*
X988117Y67750D01*
X988283Y67000D01*
X988533Y66500D01*
X989033Y66000D01*
X989617Y65667D01*
X990200Y65500D01*
X990783D01*
X991367Y65667D01*
X991867Y65917D01*
X992283Y66250D01*
G01X995800Y70500D02*
Y65500D01*
G01X993883Y70500D02*
X997717D01*
G01X999317Y65500D02*
X1001400Y70500D01*
X1003483Y65500D01*
G01X1002733Y67250D02*
X1000067D01*
G01X1005083Y65500D02*
Y70500D01*
X1008917Y65500D01*
Y70500D01*
G01X1013100Y68000D02*
X1014767D01*
Y66500D01*
X1014267Y66000D01*
X1013683Y65667D01*
X1012850Y65500D01*
X1012017Y65667D01*
X1011433Y66000D01*
X1010933Y66500D01*
X1010600Y67083D01*
X1010433Y67750D01*
Y68333D01*
X1010600Y68833D01*
X1010933Y69417D01*
X1011433Y69917D01*
X1011933Y70250D01*
X1012600Y70500D01*
X1013183D01*
X1013850Y70333D01*
X1014350Y70000D01*
G01X1016533Y70500D02*
Y65500D01*
X1019867D01*
G01X1025467D02*
X1022133D01*
Y70500D01*
X1025467D01*
G01X1024133Y68083D02*
X1022133D01*
G01X1033167Y65500D02*
Y70500D01*
X1034833D01*
X1035500Y70250D01*
X1036000Y69917D01*
X1036417Y69417D01*
X1036750Y68833D01*
X1036833Y68000D01*
X1036750Y67167D01*
X1036417Y66583D01*
X1036000Y66083D01*
X1035500Y65750D01*
X1034833Y65500D01*
X1033167D01*
G01X1038933D02*
Y70500D01*
X1041017D01*
X1041683Y70250D01*
X1042100Y69917D01*
X1042267Y69250D01*
X1042100Y68583D01*
X1041600Y68167D01*
X1041017Y67917D01*
X1038933D01*
G01X1041017D02*
X1042267Y65500D01*
G01X1045200Y70500D02*
X1047200D01*
G01X1046200D02*
Y65500D01*
G01X1045200D02*
X1047200D01*
G01X1050133Y70500D02*
Y65500D01*
X1053467D01*
G01X1055733Y70500D02*
Y65500D01*
X1059067D01*
G01X1066850D02*
Y70500D01*
G01X1070350D02*
Y65500D01*
G01Y68000D02*
X1066850D01*
G01X1074200Y65500D02*
X1073533Y65583D01*
X1072950Y65917D01*
X1072450Y66417D01*
X1072117Y67000D01*
X1071950Y67667D01*
Y68333D01*
X1072117Y69000D01*
X1072450Y69583D01*
X1072950Y70083D01*
X1073533Y70417D01*
X1074200Y70500D01*
X1074867Y70417D01*
X1075450Y70083D01*
X1075950Y69583D01*
X1076283Y69000D01*
X1076450Y68333D01*
Y67667D01*
X1076283Y67000D01*
X1075950Y66417D01*
X1075450Y65917D01*
X1074867Y65583D01*
X1074200Y65500D01*
G01X1078133Y70500D02*
Y65500D01*
X1081467D01*
G01X1087067D02*
X1083733D01*
Y70500D01*
X1087067D01*
G01X1085733Y68083D02*
X1083733D01*
G01X1094767Y65500D02*
Y70500D01*
X1096433D01*
X1097100Y70250D01*
X1097600Y69917D01*
X1098017Y69417D01*
X1098350Y68833D01*
X1098433Y68000D01*
X1098350Y67167D01*
X1098017Y66583D01*
X1097600Y66083D01*
X1097100Y65750D01*
X1096433Y65500D01*
X1094767D01*
G01X1103867D02*
X1100533D01*
Y70500D01*
X1103867D01*
G01X1102533Y68083D02*
X1100533D01*
G01X1106217Y65500D02*
Y70500D01*
X1109383D01*
G01X1108217Y68083D02*
X1106217D01*
G01X1112400Y70500D02*
X1114400D01*
G01X1113400D02*
Y65500D01*
G01X1112400D02*
X1114400D01*
G01X1117083D02*
Y70500D01*
X1120917Y65500D01*
Y70500D01*
G01X1126267Y65500D02*
X1122933D01*
Y70500D01*
X1126267D01*
G01X1124933Y68083D02*
X1122933D01*
G01X956000Y795980D02*
Y790980D01*
G01X954083Y795980D02*
X957917D01*
G01X959517Y794313D02*
X960517Y790980D01*
X961600Y794313D01*
X962683Y790980D01*
X963683Y794313D01*
G01X967200D02*
Y790980D01*
G01Y795647D02*
X967033Y795730D01*
Y795897D01*
X967200Y795980D01*
X967367Y795897D01*
Y795730D01*
X967200Y795647D01*
G01X971550Y791563D02*
X971967Y791230D01*
X972550Y790980D01*
X973050D01*
X973550Y791147D01*
X973883Y791397D01*
X974050Y791730D01*
X973967Y792230D01*
X973633Y792480D01*
X972133Y792980D01*
X971800Y793563D01*
X971967Y793980D01*
X972300Y794230D01*
X972800Y794313D01*
X973300Y794230D01*
X973800Y793980D01*
G01X978400Y795980D02*
Y790980D01*
G01X977233Y794313D02*
X979567D01*
G01X991100Y790980D02*
Y794313D01*
G01Y793730D02*
X990767Y794063D01*
X990267Y794230D01*
X989683Y794313D01*
X989100Y794147D01*
X988600Y793813D01*
X988267Y793313D01*
X988100Y792647D01*
X988267Y791980D01*
X988600Y791480D01*
X989100Y791147D01*
X989683Y790980D01*
X990267Y791063D01*
X990767Y791313D01*
X991100Y791647D01*
G01X993783Y790980D02*
Y794313D01*
G01Y793480D02*
X994117Y793897D01*
X994617Y794230D01*
X995283Y794313D01*
X995867Y794230D01*
X996367Y793897D01*
X996617Y793313D01*
Y790980D01*
G01X1002300Y795980D02*
Y790980D01*
G01Y791730D02*
X1001967Y791313D01*
X1001467Y791063D01*
X1000883Y790980D01*
X1000217Y791147D01*
X999717Y791563D01*
X999383Y792063D01*
X999300Y792647D01*
X999383Y793230D01*
X999717Y793730D01*
X1000217Y794147D01*
X1000883Y794313D01*
X1001467Y794230D01*
X1001883Y794063D01*
X1002300Y793730D01*
G01X1010500Y790980D02*
Y795980D01*
G01Y793480D02*
X1010917Y793980D01*
X1011417Y794230D01*
X1011917Y794313D01*
X1012667Y794147D01*
X1013167Y793813D01*
X1013500Y793230D01*
Y792563D01*
X1013333Y791897D01*
X1013000Y791397D01*
X1012417Y791063D01*
X1011917Y790980D01*
X1011417Y791063D01*
X1010917Y791313D01*
X1010500Y791730D01*
G01X1017600Y790980D02*
X1017100Y791063D01*
X1016600Y791397D01*
X1016267Y791980D01*
X1016100Y792647D01*
X1016267Y793313D01*
X1016600Y793897D01*
X1017100Y794230D01*
X1017600Y794313D01*
X1018100Y794230D01*
X1018600Y793897D01*
X1018933Y793313D01*
X1019017Y792647D01*
X1018933Y791980D01*
X1018600Y791397D01*
X1018100Y791063D01*
X1017600Y790980D01*
G01X1021117Y794313D02*
X1022117Y790980D01*
X1023200Y794313D01*
X1024283Y790980D01*
X1025283Y794313D01*
G01X948000Y850610D02*
Y782110D01*
G01X957500Y811500D02*
X959167D01*
Y810000D01*
X958667Y809500D01*
X958083Y809167D01*
X957250Y809000D01*
X956417Y809167D01*
X955833Y809500D01*
X955333Y810000D01*
X955000Y810583D01*
X954833Y811250D01*
Y811833D01*
X955000Y812333D01*
X955333Y812917D01*
X955833Y813417D01*
X956333Y813750D01*
X957000Y814000D01*
X957583D01*
X958250Y813833D01*
X958750Y813500D01*
G01X961100Y808833D02*
X964100Y814000D01*
G01X966617Y809000D02*
Y814000D01*
X969783D01*
G01X968617Y811583D02*
X966617D01*
G01X977650Y809667D02*
X978317Y809250D01*
X979067Y809000D01*
X979733D01*
X980400Y809250D01*
X980900Y809667D01*
X981150Y810250D01*
X980983Y810833D01*
X980567Y811333D01*
X979817Y811667D01*
X978817Y811833D01*
X978233Y812167D01*
X977983Y812750D01*
X978150Y813333D01*
X978567Y813750D01*
X979150Y814000D01*
X979733D01*
X980317Y813833D01*
X980817Y813417D01*
G01X985000Y809000D02*
Y814000D01*
G01X990600Y809000D02*
X990100Y809083D01*
X989600Y809417D01*
X989267Y810000D01*
X989100Y810667D01*
X989267Y811333D01*
X989600Y811917D01*
X990100Y812250D01*
X990600Y812333D01*
X991100Y812250D01*
X991600Y811917D01*
X991933Y811333D01*
X992017Y810667D01*
X991933Y810000D01*
X991600Y809417D01*
X991100Y809083D01*
X990600Y809000D01*
G01X996200Y814000D02*
Y809000D01*
G01X995033Y812333D02*
X997367D01*
G01X955750Y826250D02*
X958417D01*
X958167Y826833D01*
X957750Y827167D01*
X957167Y827333D01*
X956583Y827250D01*
X956083Y827000D01*
X955750Y826417D01*
X955583Y825917D01*
Y825417D01*
X955750Y824917D01*
X956167Y824417D01*
X956667Y824083D01*
X957250Y824000D01*
X957833Y824167D01*
X958417Y824667D01*
G01X964100Y829000D02*
Y824000D01*
G01Y824750D02*
X963767Y824333D01*
X963267Y824083D01*
X962683Y824000D01*
X962017Y824167D01*
X961517Y824583D01*
X961183Y825083D01*
X961100Y825667D01*
X961183Y826250D01*
X961517Y826750D01*
X962017Y827167D01*
X962683Y827333D01*
X963267Y827250D01*
X963683Y827083D01*
X964100Y826750D01*
G01X967033Y822750D02*
X967617Y822417D01*
X968283Y822333D01*
X968867Y822417D01*
X969367Y822833D01*
X969700Y823417D01*
Y827333D01*
G01Y826667D02*
X969367Y827000D01*
X968867Y827250D01*
X968283Y827333D01*
X967617Y827167D01*
X967200Y826833D01*
X966867Y826250D01*
X966700Y825667D01*
X966783Y825167D01*
X967117Y824583D01*
X967617Y824167D01*
X968283Y824000D01*
X968783Y824083D01*
X969367Y824417D01*
X969700Y824750D01*
G01X972550Y826250D02*
X975217D01*
X974967Y826833D01*
X974550Y827167D01*
X973967Y827333D01*
X973383Y827250D01*
X972883Y827000D01*
X972550Y826417D01*
X972383Y825917D01*
Y825417D01*
X972550Y824917D01*
X972967Y824417D01*
X973467Y824083D01*
X974050Y824000D01*
X974633Y824167D01*
X975217Y824667D01*
G01X985000Y829000D02*
Y824000D01*
G01X983833Y827333D02*
X986167D01*
G01X990600Y824000D02*
X990100Y824083D01*
X989600Y824417D01*
X989267Y825000D01*
X989100Y825667D01*
X989267Y826333D01*
X989600Y826917D01*
X990100Y827250D01*
X990600Y827333D01*
X991100Y827250D01*
X991600Y826917D01*
X991933Y826333D01*
X992017Y825667D01*
X991933Y825000D01*
X991600Y824417D01*
X991100Y824083D01*
X990600Y824000D01*
G01X1000383D02*
Y829000D01*
G01Y826583D02*
X1000800Y827000D01*
X1001217Y827250D01*
X1001883Y827333D01*
X1002383Y827250D01*
X1002967Y826917D01*
X1003217Y826417D01*
Y824000D01*
G01X1007400D02*
X1006900Y824083D01*
X1006400Y824417D01*
X1006067Y825000D01*
X1005900Y825667D01*
X1006067Y826333D01*
X1006400Y826917D01*
X1006900Y827250D01*
X1007400Y827333D01*
X1007900Y827250D01*
X1008400Y826917D01*
X1008733Y826333D01*
X1008817Y825667D01*
X1008733Y825000D01*
X1008400Y824417D01*
X1007900Y824083D01*
X1007400Y824000D01*
G01X1013000D02*
Y829000D01*
G01X1017350Y826250D02*
X1020017D01*
X1019767Y826833D01*
X1019350Y827167D01*
X1018767Y827333D01*
X1018183Y827250D01*
X1017683Y827000D01*
X1017350Y826417D01*
X1017183Y825917D01*
Y825417D01*
X1017350Y824917D01*
X1017767Y824417D01*
X1018267Y824083D01*
X1018850Y824000D01*
X1019433Y824167D01*
X1020017Y824667D01*
G01X955750Y842750D02*
X958417D01*
X958167Y843333D01*
X957750Y843667D01*
X957167Y843833D01*
X956583Y843750D01*
X956083Y843500D01*
X955750Y842917D01*
X955583Y842417D01*
Y841917D01*
X955750Y841417D01*
X956167Y840917D01*
X956667Y840583D01*
X957250Y840500D01*
X957833Y840667D01*
X958417Y841167D01*
G01X964100Y845500D02*
Y840500D01*
G01Y841250D02*
X963767Y840833D01*
X963267Y840583D01*
X962683Y840500D01*
X962017Y840667D01*
X961517Y841083D01*
X961183Y841583D01*
X961100Y842167D01*
X961183Y842750D01*
X961517Y843250D01*
X962017Y843667D01*
X962683Y843833D01*
X963267Y843750D01*
X963683Y843583D01*
X964100Y843250D01*
G01X967033Y839250D02*
X967617Y838917D01*
X968283Y838833D01*
X968867Y838917D01*
X969367Y839333D01*
X969700Y839917D01*
Y843833D01*
G01Y843167D02*
X969367Y843500D01*
X968867Y843750D01*
X968283Y843833D01*
X967617Y843667D01*
X967200Y843333D01*
X966867Y842750D01*
X966700Y842167D01*
X966783Y841667D01*
X967117Y841083D01*
X967617Y840667D01*
X968283Y840500D01*
X968783Y840583D01*
X969367Y840917D01*
X969700Y841250D01*
G01X972550Y842750D02*
X975217D01*
X974967Y843333D01*
X974550Y843667D01*
X973967Y843833D01*
X973383Y843750D01*
X972883Y843500D01*
X972550Y842917D01*
X972383Y842417D01*
Y841917D01*
X972550Y841417D01*
X972967Y840917D01*
X973467Y840583D01*
X974050Y840500D01*
X974633Y840667D01*
X975217Y841167D01*
G01X985000Y845500D02*
Y840500D01*
G01X983833Y843833D02*
X986167D01*
G01X990600Y840500D02*
X990100Y840583D01*
X989600Y840917D01*
X989267Y841500D01*
X989100Y842167D01*
X989267Y842833D01*
X989600Y843417D01*
X990100Y843750D01*
X990600Y843833D01*
X991100Y843750D01*
X991600Y843417D01*
X991933Y842833D01*
X992017Y842167D01*
X991933Y841500D01*
X991600Y840917D01*
X991100Y840583D01*
X990600Y840500D01*
G01X1000550Y842750D02*
X1003217D01*
X1002967Y843333D01*
X1002550Y843667D01*
X1001967Y843833D01*
X1001383Y843750D01*
X1000883Y843500D01*
X1000550Y842917D01*
X1000383Y842417D01*
Y841917D01*
X1000550Y841417D01*
X1000967Y840917D01*
X1001467Y840583D01*
X1002050Y840500D01*
X1002633Y840667D01*
X1003217Y841167D01*
G01X1008900Y845500D02*
Y840500D01*
G01Y841250D02*
X1008567Y840833D01*
X1008067Y840583D01*
X1007483Y840500D01*
X1006817Y840667D01*
X1006317Y841083D01*
X1005983Y841583D01*
X1005900Y842167D01*
X1005983Y842750D01*
X1006317Y843250D01*
X1006817Y843667D01*
X1007483Y843833D01*
X1008067Y843750D01*
X1008483Y843583D01*
X1008900Y843250D01*
G01X1011833Y839250D02*
X1012417Y838917D01*
X1013083Y838833D01*
X1013667Y838917D01*
X1014167Y839333D01*
X1014500Y839917D01*
Y843833D01*
G01Y843167D02*
X1014167Y843500D01*
X1013667Y843750D01*
X1013083Y843833D01*
X1012417Y843667D01*
X1012000Y843333D01*
X1011667Y842750D01*
X1011500Y842167D01*
X1011583Y841667D01*
X1011917Y841083D01*
X1012417Y840667D01*
X1013083Y840500D01*
X1013583Y840583D01*
X1014167Y840917D01*
X1014500Y841250D01*
G01X1017350Y842750D02*
X1020017D01*
X1019767Y843333D01*
X1019350Y843667D01*
X1018767Y843833D01*
X1018183Y843750D01*
X1017683Y843500D01*
X1017350Y842917D01*
X1017183Y842417D01*
Y841917D01*
X1017350Y841417D01*
X1017767Y840917D01*
X1018267Y840583D01*
X1018850Y840500D01*
X1019433Y840667D01*
X1020017Y841167D01*
G01X948500Y819500D02*
X1343000D01*
G01X948500Y834500D02*
X1343000D01*
G01X1026000Y336000D02*
Y86000D01*
G01X1033500Y370500D02*
Y375500D01*
G01Y373000D02*
X1033917Y373500D01*
X1034417Y373750D01*
X1034917Y373833D01*
X1035667Y373667D01*
X1036167Y373333D01*
X1036500Y372750D01*
Y372083D01*
X1036333Y371417D01*
X1036000Y370917D01*
X1035417Y370583D01*
X1034917Y370500D01*
X1034417Y370583D01*
X1033917Y370833D01*
X1033500Y371250D01*
G01X1039183Y373833D02*
Y371500D01*
X1039517Y370917D01*
X1040017Y370583D01*
X1040600Y370500D01*
X1041183Y370583D01*
X1041683Y370917D01*
X1042017Y371500D01*
G01Y370500D02*
Y373833D01*
G01X1044700Y370500D02*
Y375500D01*
G01Y373000D02*
X1045117Y373500D01*
X1045617Y373750D01*
X1046117Y373833D01*
X1046867Y373667D01*
X1047367Y373333D01*
X1047700Y372750D01*
Y372083D01*
X1047533Y371417D01*
X1047200Y370917D01*
X1046617Y370583D01*
X1046117Y370500D01*
X1045617Y370583D01*
X1045117Y370833D01*
X1044700Y371250D01*
G01X1050300Y370500D02*
Y375500D01*
G01Y373000D02*
X1050717Y373500D01*
X1051217Y373750D01*
X1051717Y373833D01*
X1052467Y373667D01*
X1052967Y373333D01*
X1053300Y372750D01*
Y372083D01*
X1053133Y371417D01*
X1052800Y370917D01*
X1052217Y370583D01*
X1051717Y370500D01*
X1051217Y370583D01*
X1050717Y370833D01*
X1050300Y371250D01*
G01X1057400Y370500D02*
Y375500D01*
G01X1061750Y372750D02*
X1064417D01*
X1064167Y373333D01*
X1063750Y373667D01*
X1063167Y373833D01*
X1062583Y373750D01*
X1062083Y373500D01*
X1061750Y372917D01*
X1061583Y372417D01*
Y371917D01*
X1061750Y371417D01*
X1062167Y370917D01*
X1062667Y370583D01*
X1063250Y370500D01*
X1063833Y370667D01*
X1064417Y371167D01*
G01X1074200Y373833D02*
Y370500D01*
G01Y375167D02*
X1074033Y375250D01*
Y375417D01*
X1074200Y375500D01*
X1074367Y375417D01*
Y375250D01*
X1074200Y375167D01*
G01X1078383Y370500D02*
Y373833D01*
G01Y373000D02*
X1078717Y373417D01*
X1079217Y373750D01*
X1079883Y373833D01*
X1080467Y373750D01*
X1080967Y373417D01*
X1081217Y372833D01*
Y370500D01*
G01X1084150Y371083D02*
X1084567Y370750D01*
X1085150Y370500D01*
X1085650D01*
X1086150Y370667D01*
X1086483Y370917D01*
X1086650Y371250D01*
X1086567Y371750D01*
X1086233Y372000D01*
X1084733Y372500D01*
X1084400Y373083D01*
X1084567Y373500D01*
X1084900Y373750D01*
X1085400Y373833D01*
X1085900Y373750D01*
X1086400Y373500D01*
G01X1091000Y373833D02*
Y370500D01*
G01Y375167D02*
X1090833Y375250D01*
Y375417D01*
X1091000Y375500D01*
X1091167Y375417D01*
Y375250D01*
X1091000Y375167D01*
G01X1098100Y375500D02*
Y370500D01*
G01Y371250D02*
X1097767Y370833D01*
X1097267Y370583D01*
X1096683Y370500D01*
X1096017Y370667D01*
X1095517Y371083D01*
X1095183Y371583D01*
X1095100Y372167D01*
X1095183Y372750D01*
X1095517Y373250D01*
X1096017Y373667D01*
X1096683Y373833D01*
X1097267Y373750D01*
X1097683Y373583D01*
X1098100Y373250D01*
G01X1100950Y372750D02*
X1103617D01*
X1103367Y373333D01*
X1102950Y373667D01*
X1102367Y373833D01*
X1101783Y373750D01*
X1101283Y373500D01*
X1100950Y372917D01*
X1100783Y372417D01*
Y371917D01*
X1100950Y371417D01*
X1101367Y370917D01*
X1101867Y370583D01*
X1102450Y370500D01*
X1103033Y370667D01*
X1103617Y371167D01*
G01X1113400Y375500D02*
Y370500D01*
G01X1112233Y373833D02*
X1114567D01*
G01X1117583Y370500D02*
Y375500D01*
G01Y373083D02*
X1118000Y373500D01*
X1118417Y373750D01*
X1119083Y373833D01*
X1119583Y373750D01*
X1120167Y373417D01*
X1120417Y372917D01*
Y370500D01*
G01X1123350Y372750D02*
X1126017D01*
X1125767Y373333D01*
X1125350Y373667D01*
X1124767Y373833D01*
X1124183Y373750D01*
X1123683Y373500D01*
X1123350Y372917D01*
X1123183Y372417D01*
Y371917D01*
X1123350Y371417D01*
X1123767Y370917D01*
X1124267Y370583D01*
X1124850Y370500D01*
X1125433Y370667D01*
X1126017Y371167D01*
G01X1134633Y370500D02*
Y373833D01*
G01Y373167D02*
X1135050Y373500D01*
X1135467Y373750D01*
X1136050Y373833D01*
X1136467Y373750D01*
X1136967Y373500D01*
G01X1140150Y372750D02*
X1142817D01*
X1142567Y373333D01*
X1142150Y373667D01*
X1141567Y373833D01*
X1140983Y373750D01*
X1140483Y373500D01*
X1140150Y372917D01*
X1139983Y372417D01*
Y371917D01*
X1140150Y371417D01*
X1140567Y370917D01*
X1141067Y370583D01*
X1141650Y370500D01*
X1142233Y370667D01*
X1142817Y371167D01*
G01X1145750Y371083D02*
X1146167Y370750D01*
X1146750Y370500D01*
X1147250D01*
X1147750Y370667D01*
X1148083Y370917D01*
X1148250Y371250D01*
X1148167Y371750D01*
X1147833Y372000D01*
X1146333Y372500D01*
X1146000Y373083D01*
X1146167Y373500D01*
X1146500Y373750D01*
X1147000Y373833D01*
X1147500Y373750D01*
X1148000Y373500D01*
G01X1152600Y373833D02*
Y370500D01*
G01Y375167D02*
X1152433Y375250D01*
Y375417D01*
X1152600Y375500D01*
X1152767Y375417D01*
Y375250D01*
X1152600Y375167D01*
G01X1156783Y370500D02*
Y373833D01*
G01Y373000D02*
X1157117Y373417D01*
X1157617Y373750D01*
X1158283Y373833D01*
X1158867Y373750D01*
X1159367Y373417D01*
X1159617Y372833D01*
Y370500D01*
G01X1163800Y370333D02*
X1163633Y370417D01*
Y370583D01*
X1163800Y370667D01*
X1163967Y370583D01*
Y370417D01*
X1163800Y370333D01*
G01X1021417Y383667D02*
X1021917Y384167D01*
X1022500Y384417D01*
X1023167Y384500D01*
X1024000Y384333D01*
X1024583Y383917D01*
X1024750Y383417D01*
X1024667Y382917D01*
X1024333Y382500D01*
X1022667Y381667D01*
X1021917Y381083D01*
X1021417Y380250D01*
X1021250Y379500D01*
X1024750D01*
G01X1028600Y379333D02*
X1028433Y379417D01*
Y379583D01*
X1028600Y379667D01*
X1028767Y379583D01*
Y379417D01*
X1028600Y379333D01*
G01X1032117Y384500D02*
X1034200Y379500D01*
X1036283Y384500D01*
G01X1039800Y382833D02*
Y379500D01*
G01Y384167D02*
X1039633Y384250D01*
Y384417D01*
X1039800Y384500D01*
X1039967Y384417D01*
Y384250D01*
X1039800Y384167D01*
G01X1046900Y379500D02*
Y382833D01*
G01Y382250D02*
X1046567Y382583D01*
X1046067Y382750D01*
X1045483Y382833D01*
X1044900Y382667D01*
X1044400Y382333D01*
X1044067Y381833D01*
X1043900Y381167D01*
X1044067Y380500D01*
X1044400Y380000D01*
X1044900Y379667D01*
X1045483Y379500D01*
X1046067Y379583D01*
X1046567Y379833D01*
X1046900Y380167D01*
G01X1055350Y380083D02*
X1055767Y379750D01*
X1056350Y379500D01*
X1056850D01*
X1057350Y379667D01*
X1057683Y379917D01*
X1057850Y380250D01*
X1057767Y380750D01*
X1057433Y381000D01*
X1055933Y381500D01*
X1055600Y382083D01*
X1055767Y382500D01*
X1056100Y382750D01*
X1056600Y382833D01*
X1057100Y382750D01*
X1057600Y382500D01*
G01X1060783Y379500D02*
Y384500D01*
G01Y382083D02*
X1061200Y382500D01*
X1061617Y382750D01*
X1062283Y382833D01*
X1062783Y382750D01*
X1063367Y382417D01*
X1063617Y381917D01*
Y379500D01*
G01X1067800D02*
X1067300Y379583D01*
X1066800Y379917D01*
X1066467Y380500D01*
X1066300Y381167D01*
X1066467Y381833D01*
X1066800Y382417D01*
X1067300Y382750D01*
X1067800Y382833D01*
X1068300Y382750D01*
X1068800Y382417D01*
X1069133Y381833D01*
X1069217Y381167D01*
X1069133Y380500D01*
X1068800Y379917D01*
X1068300Y379583D01*
X1067800Y379500D01*
G01X1071983Y382833D02*
Y380500D01*
X1072317Y379917D01*
X1072817Y379583D01*
X1073400Y379500D01*
X1073983Y379583D01*
X1074483Y379917D01*
X1074817Y380500D01*
G01Y379500D02*
Y382833D01*
G01X1079000Y379500D02*
Y384500D01*
G01X1086100D02*
Y379500D01*
G01Y380250D02*
X1085767Y379833D01*
X1085267Y379583D01*
X1084683Y379500D01*
X1084017Y379667D01*
X1083517Y380083D01*
X1083183Y380583D01*
X1083100Y381167D01*
X1083183Y381750D01*
X1083517Y382250D01*
X1084017Y382667D01*
X1084683Y382833D01*
X1085267Y382750D01*
X1085683Y382583D01*
X1086100Y382250D01*
G01X1094300Y379500D02*
Y384500D01*
G01Y382000D02*
X1094717Y382500D01*
X1095217Y382750D01*
X1095717Y382833D01*
X1096467Y382667D01*
X1096967Y382333D01*
X1097300Y381750D01*
Y381083D01*
X1097133Y380417D01*
X1096800Y379917D01*
X1096217Y379583D01*
X1095717Y379500D01*
X1095217Y379583D01*
X1094717Y379833D01*
X1094300Y380250D01*
G01X1100150Y381750D02*
X1102817D01*
X1102567Y382333D01*
X1102150Y382667D01*
X1101567Y382833D01*
X1100983Y382750D01*
X1100483Y382500D01*
X1100150Y381917D01*
X1099983Y381417D01*
Y380917D01*
X1100150Y380417D01*
X1100567Y379917D01*
X1101067Y379583D01*
X1101650Y379500D01*
X1102233Y379667D01*
X1102817Y380167D01*
G01X1111100Y377833D02*
Y382833D01*
G01Y382083D02*
X1111517Y382500D01*
X1111933Y382750D01*
X1112600Y382833D01*
X1113183Y382750D01*
X1113767Y382333D01*
X1114017Y381750D01*
X1114100Y381167D01*
X1114017Y380583D01*
X1113767Y380000D01*
X1113267Y379667D01*
X1112600Y379500D01*
X1112017Y379583D01*
X1111433Y379833D01*
X1111100Y380167D01*
G01X1118200Y379500D02*
Y384500D01*
G01X1122383Y382833D02*
Y380500D01*
X1122717Y379917D01*
X1123217Y379583D01*
X1123800Y379500D01*
X1124383Y379583D01*
X1124883Y379917D01*
X1125217Y380500D01*
G01Y379500D02*
Y382833D01*
G01X1128233Y378250D02*
X1128817Y377917D01*
X1129483Y377833D01*
X1130067Y377917D01*
X1130567Y378333D01*
X1130900Y378917D01*
Y382833D01*
G01Y382167D02*
X1130567Y382500D01*
X1130067Y382750D01*
X1129483Y382833D01*
X1128817Y382667D01*
X1128400Y382333D01*
X1128067Y381750D01*
X1127900Y381167D01*
X1127983Y380667D01*
X1128317Y380083D01*
X1128817Y379667D01*
X1129483Y379500D01*
X1129983Y379583D01*
X1130567Y379917D01*
X1130900Y380250D01*
G01X1133833Y378250D02*
X1134417Y377917D01*
X1135083Y377833D01*
X1135667Y377917D01*
X1136167Y378333D01*
X1136500Y378917D01*
Y382833D01*
G01Y382167D02*
X1136167Y382500D01*
X1135667Y382750D01*
X1135083Y382833D01*
X1134417Y382667D01*
X1134000Y382333D01*
X1133667Y381750D01*
X1133500Y381167D01*
X1133583Y380667D01*
X1133917Y380083D01*
X1134417Y379667D01*
X1135083Y379500D01*
X1135583Y379583D01*
X1136167Y379917D01*
X1136500Y380250D01*
G01X1139350Y381750D02*
X1142017D01*
X1141767Y382333D01*
X1141350Y382667D01*
X1140767Y382833D01*
X1140183Y382750D01*
X1139683Y382500D01*
X1139350Y381917D01*
X1139183Y381417D01*
Y380917D01*
X1139350Y380417D01*
X1139767Y379917D01*
X1140267Y379583D01*
X1140850Y379500D01*
X1141433Y379667D01*
X1142017Y380167D01*
G01X1147700Y384500D02*
Y379500D01*
G01Y380250D02*
X1147367Y379833D01*
X1146867Y379583D01*
X1146283Y379500D01*
X1145617Y379667D01*
X1145117Y380083D01*
X1144783Y380583D01*
X1144700Y381167D01*
X1144783Y381750D01*
X1145117Y382250D01*
X1145617Y382667D01*
X1146283Y382833D01*
X1146867Y382750D01*
X1147283Y382583D01*
X1147700Y382250D01*
G01X1155317Y382833D02*
X1156317Y379500D01*
X1157400Y382833D01*
X1158483Y379500D01*
X1159483Y382833D01*
G01X1163000D02*
Y379500D01*
G01Y384167D02*
X1162833Y384250D01*
Y384417D01*
X1163000Y384500D01*
X1163167Y384417D01*
Y384250D01*
X1163000Y384167D01*
G01X1168600Y384500D02*
Y379500D01*
G01X1167433Y382833D02*
X1169767D01*
G01X1172783Y379500D02*
Y384500D01*
G01Y382083D02*
X1173200Y382500D01*
X1173617Y382750D01*
X1174283Y382833D01*
X1174783Y382750D01*
X1175367Y382417D01*
X1175617Y381917D01*
Y379500D01*
G01X1183733D02*
X1187067Y381167D01*
X1183733Y382833D01*
G01X1189583Y380083D02*
X1190167Y379667D01*
X1190833Y379500D01*
X1191500Y379667D01*
X1192083Y380167D01*
X1192500Y380917D01*
X1192667Y381667D01*
Y382583D01*
X1192500Y383333D01*
X1192083Y384000D01*
X1191583Y384333D01*
X1191000Y384500D01*
X1190333Y384333D01*
X1189833Y384000D01*
X1189500Y383500D01*
X1189333Y382833D01*
X1189500Y382250D01*
X1189917Y381667D01*
X1190417Y381333D01*
X1191000Y381250D01*
X1191667Y381417D01*
X1192167Y381833D01*
X1192667Y382583D01*
G01X1196600Y384500D02*
X1195933Y384333D01*
X1195433Y383917D01*
X1195100Y383417D01*
X1194850Y382750D01*
X1194767Y382000D01*
X1194850Y381250D01*
X1195100Y380583D01*
X1195433Y380083D01*
X1195933Y379667D01*
X1196600Y379500D01*
X1197267Y379667D01*
X1197767Y380083D01*
X1198100Y380583D01*
X1198350Y381250D01*
X1198433Y382000D01*
X1198350Y382750D01*
X1198100Y383417D01*
X1197767Y383917D01*
X1197267Y384333D01*
X1196600Y384500D01*
G01X1200700Y379333D02*
X1203700Y384500D01*
G01X1200700D02*
X1200200Y384333D01*
X1199950Y384083D01*
X1199783Y383583D01*
X1199950Y383083D01*
X1200200Y382833D01*
X1200700Y382667D01*
X1201200Y382833D01*
X1201450Y383083D01*
X1201617Y383583D01*
X1201450Y384083D01*
X1201200Y384333D01*
X1200700Y384500D01*
G01X1203700Y381167D02*
X1203200Y381000D01*
X1202950Y380750D01*
X1202783Y380250D01*
X1202950Y379750D01*
X1203200Y379500D01*
X1203700Y379333D01*
X1204200Y379500D01*
X1204450Y379750D01*
X1204617Y380250D01*
X1204450Y380750D01*
X1204200Y381000D01*
X1203700Y381167D01*
G01X1212233Y379500D02*
Y382833D01*
G01Y382167D02*
X1212650Y382500D01*
X1213067Y382750D01*
X1213650Y382833D01*
X1214067Y382750D01*
X1214567Y382500D01*
G01X1217750Y381750D02*
X1220417D01*
X1220167Y382333D01*
X1219750Y382667D01*
X1219167Y382833D01*
X1218583Y382750D01*
X1218083Y382500D01*
X1217750Y381917D01*
X1217583Y381417D01*
Y380917D01*
X1217750Y380417D01*
X1218167Y379917D01*
X1218667Y379583D01*
X1219250Y379500D01*
X1219833Y379667D01*
X1220417Y380167D01*
G01X1223350Y380083D02*
X1223767Y379750D01*
X1224350Y379500D01*
X1224850D01*
X1225350Y379667D01*
X1225683Y379917D01*
X1225850Y380250D01*
X1225767Y380750D01*
X1225433Y381000D01*
X1223933Y381500D01*
X1223600Y382083D01*
X1223767Y382500D01*
X1224100Y382750D01*
X1224600Y382833D01*
X1225100Y382750D01*
X1225600Y382500D01*
G01X1230200Y382833D02*
Y379500D01*
G01Y384167D02*
X1230033Y384250D01*
Y384417D01*
X1230200Y384500D01*
X1230367Y384417D01*
Y384250D01*
X1230200Y384167D01*
G01X1234383Y379500D02*
Y382833D01*
G01Y382000D02*
X1234717Y382417D01*
X1235217Y382750D01*
X1235883Y382833D01*
X1236467Y382750D01*
X1236967Y382417D01*
X1237217Y381833D01*
Y379500D01*
G01X1246417Y378000D02*
X1247583Y379167D01*
Y380333D01*
X1246417D01*
Y379167D01*
X1247583D01*
G01Y381167D02*
Y382333D01*
X1246417D01*
Y381167D01*
X1247583D01*
G01X1250767Y379500D02*
Y384500D01*
X1252433D01*
X1253100Y384250D01*
X1253600Y383917D01*
X1254017Y383417D01*
X1254350Y382833D01*
X1254433Y382000D01*
X1254350Y381167D01*
X1254017Y380583D01*
X1253600Y380083D01*
X1253100Y379750D01*
X1252433Y379500D01*
X1250767D01*
G01X1258200D02*
X1257700Y379583D01*
X1257200Y379917D01*
X1256867Y380500D01*
X1256700Y381167D01*
X1256867Y381833D01*
X1257200Y382417D01*
X1257700Y382750D01*
X1258200Y382833D01*
X1258700Y382750D01*
X1259200Y382417D01*
X1259533Y381833D01*
X1259617Y381167D01*
X1259533Y380500D01*
X1259200Y379917D01*
X1258700Y379583D01*
X1258200Y379500D01*
G01X1267983D02*
Y382833D01*
G01Y382000D02*
X1268317Y382417D01*
X1268817Y382750D01*
X1269483Y382833D01*
X1270067Y382750D01*
X1270567Y382417D01*
X1270817Y381833D01*
Y379500D01*
G01X1275000D02*
X1274500Y379583D01*
X1274000Y379917D01*
X1273667Y380500D01*
X1273500Y381167D01*
X1273667Y381833D01*
X1274000Y382417D01*
X1274500Y382750D01*
X1275000Y382833D01*
X1275500Y382750D01*
X1276000Y382417D01*
X1276333Y381833D01*
X1276417Y381167D01*
X1276333Y380500D01*
X1276000Y379917D01*
X1275500Y379583D01*
X1275000Y379500D01*
G01X1280600Y384500D02*
Y379500D01*
G01X1279433Y382833D02*
X1281767D01*
G01X1293300Y379500D02*
Y382833D01*
G01Y382250D02*
X1292967Y382583D01*
X1292467Y382750D01*
X1291883Y382833D01*
X1291300Y382667D01*
X1290800Y382333D01*
X1290467Y381833D01*
X1290300Y381167D01*
X1290467Y380500D01*
X1290800Y380000D01*
X1291300Y379667D01*
X1291883Y379500D01*
X1292467Y379583D01*
X1292967Y379833D01*
X1293300Y380167D01*
G01X1297400Y379500D02*
Y384500D01*
G01X1303000Y379500D02*
Y384500D01*
G01X1308600Y379500D02*
X1308100Y379583D01*
X1307600Y379917D01*
X1307267Y380500D01*
X1307100Y381167D01*
X1307267Y381833D01*
X1307600Y382417D01*
X1308100Y382750D01*
X1308600Y382833D01*
X1309100Y382750D01*
X1309600Y382417D01*
X1309933Y381833D01*
X1310017Y381167D01*
X1309933Y380500D01*
X1309600Y379917D01*
X1309100Y379583D01*
X1308600Y379500D01*
G01X1312117Y382833D02*
X1313117Y379500D01*
X1314200Y382833D01*
X1315283Y379500D01*
X1316283Y382833D01*
G01X1033500Y413500D02*
Y418500D01*
G01Y416000D02*
X1033917Y416500D01*
X1034417Y416750D01*
X1034917Y416833D01*
X1035667Y416667D01*
X1036167Y416333D01*
X1036500Y415750D01*
Y415083D01*
X1036333Y414417D01*
X1036000Y413917D01*
X1035417Y413583D01*
X1034917Y413500D01*
X1034417Y413583D01*
X1033917Y413833D01*
X1033500Y414250D01*
G01X1039183Y416833D02*
Y414500D01*
X1039517Y413917D01*
X1040017Y413583D01*
X1040600Y413500D01*
X1041183Y413583D01*
X1041683Y413917D01*
X1042017Y414500D01*
G01Y413500D02*
Y416833D01*
G01X1044700Y413500D02*
Y418500D01*
G01Y416000D02*
X1045117Y416500D01*
X1045617Y416750D01*
X1046117Y416833D01*
X1046867Y416667D01*
X1047367Y416333D01*
X1047700Y415750D01*
Y415083D01*
X1047533Y414417D01*
X1047200Y413917D01*
X1046617Y413583D01*
X1046117Y413500D01*
X1045617Y413583D01*
X1045117Y413833D01*
X1044700Y414250D01*
G01X1050300Y413500D02*
Y418500D01*
G01Y416000D02*
X1050717Y416500D01*
X1051217Y416750D01*
X1051717Y416833D01*
X1052467Y416667D01*
X1052967Y416333D01*
X1053300Y415750D01*
Y415083D01*
X1053133Y414417D01*
X1052800Y413917D01*
X1052217Y413583D01*
X1051717Y413500D01*
X1051217Y413583D01*
X1050717Y413833D01*
X1050300Y414250D01*
G01X1057400Y413500D02*
Y418500D01*
G01X1061750Y415750D02*
X1064417D01*
X1064167Y416333D01*
X1063750Y416667D01*
X1063167Y416833D01*
X1062583Y416750D01*
X1062083Y416500D01*
X1061750Y415917D01*
X1061583Y415417D01*
Y414917D01*
X1061750Y414417D01*
X1062167Y413917D01*
X1062667Y413583D01*
X1063250Y413500D01*
X1063833Y413667D01*
X1064417Y414167D01*
G01X1074200Y416833D02*
Y413500D01*
G01Y418167D02*
X1074033Y418250D01*
Y418417D01*
X1074200Y418500D01*
X1074367Y418417D01*
Y418250D01*
X1074200Y418167D01*
G01X1078383Y413500D02*
Y416833D01*
G01Y416000D02*
X1078717Y416417D01*
X1079217Y416750D01*
X1079883Y416833D01*
X1080467Y416750D01*
X1080967Y416417D01*
X1081217Y415833D01*
Y413500D01*
G01X1084150Y414083D02*
X1084567Y413750D01*
X1085150Y413500D01*
X1085650D01*
X1086150Y413667D01*
X1086483Y413917D01*
X1086650Y414250D01*
X1086567Y414750D01*
X1086233Y415000D01*
X1084733Y415500D01*
X1084400Y416083D01*
X1084567Y416500D01*
X1084900Y416750D01*
X1085400Y416833D01*
X1085900Y416750D01*
X1086400Y416500D01*
G01X1091000Y416833D02*
Y413500D01*
G01Y418167D02*
X1090833Y418250D01*
Y418417D01*
X1091000Y418500D01*
X1091167Y418417D01*
Y418250D01*
X1091000Y418167D01*
G01X1098100Y418500D02*
Y413500D01*
G01Y414250D02*
X1097767Y413833D01*
X1097267Y413583D01*
X1096683Y413500D01*
X1096017Y413667D01*
X1095517Y414083D01*
X1095183Y414583D01*
X1095100Y415167D01*
X1095183Y415750D01*
X1095517Y416250D01*
X1096017Y416667D01*
X1096683Y416833D01*
X1097267Y416750D01*
X1097683Y416583D01*
X1098100Y416250D01*
G01X1100950Y415750D02*
X1103617D01*
X1103367Y416333D01*
X1102950Y416667D01*
X1102367Y416833D01*
X1101783Y416750D01*
X1101283Y416500D01*
X1100950Y415917D01*
X1100783Y415417D01*
Y414917D01*
X1100950Y414417D01*
X1101367Y413917D01*
X1101867Y413583D01*
X1102450Y413500D01*
X1103033Y413667D01*
X1103617Y414167D01*
G01X1113400Y418500D02*
Y413500D01*
G01X1112233Y416833D02*
X1114567D01*
G01X1117583Y413500D02*
Y418500D01*
G01Y416083D02*
X1118000Y416500D01*
X1118417Y416750D01*
X1119083Y416833D01*
X1119583Y416750D01*
X1120167Y416417D01*
X1120417Y415917D01*
Y413500D01*
G01X1123350Y415750D02*
X1126017D01*
X1125767Y416333D01*
X1125350Y416667D01*
X1124767Y416833D01*
X1124183Y416750D01*
X1123683Y416500D01*
X1123350Y415917D01*
X1123183Y415417D01*
Y414917D01*
X1123350Y414417D01*
X1123767Y413917D01*
X1124267Y413583D01*
X1124850Y413500D01*
X1125433Y413667D01*
X1126017Y414167D01*
G01X1134633Y413500D02*
Y416833D01*
G01Y416167D02*
X1135050Y416500D01*
X1135467Y416750D01*
X1136050Y416833D01*
X1136467Y416750D01*
X1136967Y416500D01*
G01X1140150Y415750D02*
X1142817D01*
X1142567Y416333D01*
X1142150Y416667D01*
X1141567Y416833D01*
X1140983Y416750D01*
X1140483Y416500D01*
X1140150Y415917D01*
X1139983Y415417D01*
Y414917D01*
X1140150Y414417D01*
X1140567Y413917D01*
X1141067Y413583D01*
X1141650Y413500D01*
X1142233Y413667D01*
X1142817Y414167D01*
G01X1145750Y414083D02*
X1146167Y413750D01*
X1146750Y413500D01*
X1147250D01*
X1147750Y413667D01*
X1148083Y413917D01*
X1148250Y414250D01*
X1148167Y414750D01*
X1147833Y415000D01*
X1146333Y415500D01*
X1146000Y416083D01*
X1146167Y416500D01*
X1146500Y416750D01*
X1147000Y416833D01*
X1147500Y416750D01*
X1148000Y416500D01*
G01X1152600Y416833D02*
Y413500D01*
G01Y418167D02*
X1152433Y418250D01*
Y418417D01*
X1152600Y418500D01*
X1152767Y418417D01*
Y418250D01*
X1152600Y418167D01*
G01X1156783Y413500D02*
Y416833D01*
G01Y416000D02*
X1157117Y416417D01*
X1157617Y416750D01*
X1158283Y416833D01*
X1158867Y416750D01*
X1159367Y416417D01*
X1159617Y415833D01*
Y413500D01*
G01X1163800Y413333D02*
X1163633Y413417D01*
Y413583D01*
X1163800Y413667D01*
X1163967Y413583D01*
Y413417D01*
X1163800Y413333D01*
G01X1023000Y390000D02*
Y395000D01*
X1022000Y394000D01*
G01Y390000D02*
X1024000D01*
G01X1028600Y389833D02*
X1028433Y389917D01*
Y390083D01*
X1028600Y390167D01*
X1028767Y390083D01*
Y389917D01*
X1028600Y389833D01*
G01X1032367Y390000D02*
Y395000D01*
X1034033D01*
X1034700Y394750D01*
X1035200Y394417D01*
X1035617Y393917D01*
X1035950Y393333D01*
X1036033Y392500D01*
X1035950Y391667D01*
X1035617Y391083D01*
X1035200Y390583D01*
X1034700Y390250D01*
X1034033Y390000D01*
X1032367D01*
G01X1039800Y393333D02*
Y390000D01*
G01Y394667D02*
X1039633Y394750D01*
Y394917D01*
X1039800Y395000D01*
X1039967Y394917D01*
Y394750D01*
X1039800Y394667D01*
G01X1042900Y390000D02*
Y393333D01*
G01Y392417D02*
X1043150Y392833D01*
X1043567Y393167D01*
X1044150Y393333D01*
X1044733Y393167D01*
X1045150Y392833D01*
X1045400Y392417D01*
Y390000D01*
G01Y392417D02*
X1045650Y392833D01*
X1046067Y393167D01*
X1046650Y393333D01*
X1047233Y393167D01*
X1047650Y392833D01*
X1047900Y392333D01*
Y390000D01*
G01X1049500Y388333D02*
Y393333D01*
G01Y392583D02*
X1049917Y393000D01*
X1050333Y393250D01*
X1051000Y393333D01*
X1051583Y393250D01*
X1052167Y392833D01*
X1052417Y392250D01*
X1052500Y391667D01*
X1052417Y391083D01*
X1052167Y390500D01*
X1051667Y390167D01*
X1051000Y390000D01*
X1050417Y390083D01*
X1049833Y390333D01*
X1049500Y390667D01*
G01X1056600Y390000D02*
Y395000D01*
G01X1060950Y392250D02*
X1063617D01*
X1063367Y392833D01*
X1062950Y393167D01*
X1062367Y393333D01*
X1061783Y393250D01*
X1061283Y393000D01*
X1060950Y392417D01*
X1060783Y391917D01*
Y391417D01*
X1060950Y390917D01*
X1061367Y390417D01*
X1061867Y390083D01*
X1062450Y390000D01*
X1063033Y390167D01*
X1063617Y390667D01*
G01X1075067Y390000D02*
X1071733Y391667D01*
X1075067Y393333D01*
G01X1084600Y390000D02*
Y395000D01*
X1083600Y394000D01*
G01Y390000D02*
X1085600D01*
G01X1093300D02*
Y393333D01*
G01Y392417D02*
X1093550Y392833D01*
X1093967Y393167D01*
X1094550Y393333D01*
X1095133Y393167D01*
X1095550Y392833D01*
X1095800Y392417D01*
Y390000D01*
G01Y392417D02*
X1096050Y392833D01*
X1096467Y393167D01*
X1097050Y393333D01*
X1097633Y393167D01*
X1098050Y392833D01*
X1098300Y392333D01*
Y390000D01*
G01X1101400Y393333D02*
Y390000D01*
G01Y394667D02*
X1101233Y394750D01*
Y394917D01*
X1101400Y395000D01*
X1101567Y394917D01*
Y394750D01*
X1101400Y394667D01*
G01X1107000Y390000D02*
Y395000D01*
G01X1117617Y388500D02*
X1118783Y389667D01*
Y390833D01*
X1117617D01*
Y389667D01*
X1118783D01*
G01Y391667D02*
Y392833D01*
X1117617D01*
Y391667D01*
X1118783D01*
G01X1023000Y424000D02*
Y429000D01*
X1022000Y428000D01*
G01Y424000D02*
X1024000D01*
G01X1028600Y423833D02*
X1028433Y423917D01*
Y424083D01*
X1028600Y424167D01*
X1028767Y424083D01*
Y423917D01*
X1028600Y423833D01*
G01X1032117Y429000D02*
X1034200Y424000D01*
X1036283Y429000D01*
G01X1039800Y427333D02*
Y424000D01*
G01Y428667D02*
X1039633Y428750D01*
Y428917D01*
X1039800Y429000D01*
X1039967Y428917D01*
Y428750D01*
X1039800Y428667D01*
G01X1046900Y424000D02*
Y427333D01*
G01Y426750D02*
X1046567Y427083D01*
X1046067Y427250D01*
X1045483Y427333D01*
X1044900Y427167D01*
X1044400Y426833D01*
X1044067Y426333D01*
X1043900Y425667D01*
X1044067Y425000D01*
X1044400Y424500D01*
X1044900Y424167D01*
X1045483Y424000D01*
X1046067Y424083D01*
X1046567Y424333D01*
X1046900Y424667D01*
G01X1055350Y424583D02*
X1055767Y424250D01*
X1056350Y424000D01*
X1056850D01*
X1057350Y424167D01*
X1057683Y424417D01*
X1057850Y424750D01*
X1057767Y425250D01*
X1057433Y425500D01*
X1055933Y426000D01*
X1055600Y426583D01*
X1055767Y427000D01*
X1056100Y427250D01*
X1056600Y427333D01*
X1057100Y427250D01*
X1057600Y427000D01*
G01X1060783Y424000D02*
Y429000D01*
G01Y426583D02*
X1061200Y427000D01*
X1061617Y427250D01*
X1062283Y427333D01*
X1062783Y427250D01*
X1063367Y426917D01*
X1063617Y426417D01*
Y424000D01*
G01X1067800D02*
X1067300Y424083D01*
X1066800Y424417D01*
X1066467Y425000D01*
X1066300Y425667D01*
X1066467Y426333D01*
X1066800Y426917D01*
X1067300Y427250D01*
X1067800Y427333D01*
X1068300Y427250D01*
X1068800Y426917D01*
X1069133Y426333D01*
X1069217Y425667D01*
X1069133Y425000D01*
X1068800Y424417D01*
X1068300Y424083D01*
X1067800Y424000D01*
G01X1071983Y427333D02*
Y425000D01*
X1072317Y424417D01*
X1072817Y424083D01*
X1073400Y424000D01*
X1073983Y424083D01*
X1074483Y424417D01*
X1074817Y425000D01*
G01Y424000D02*
Y427333D01*
G01X1079000Y424000D02*
Y429000D01*
G01X1086100D02*
Y424000D01*
G01Y424750D02*
X1085767Y424333D01*
X1085267Y424083D01*
X1084683Y424000D01*
X1084017Y424167D01*
X1083517Y424583D01*
X1083183Y425083D01*
X1083100Y425667D01*
X1083183Y426250D01*
X1083517Y426750D01*
X1084017Y427167D01*
X1084683Y427333D01*
X1085267Y427250D01*
X1085683Y427083D01*
X1086100Y426750D01*
G01X1094300Y424000D02*
Y429000D01*
G01Y426500D02*
X1094717Y427000D01*
X1095217Y427250D01*
X1095717Y427333D01*
X1096467Y427167D01*
X1096967Y426833D01*
X1097300Y426250D01*
Y425583D01*
X1097133Y424917D01*
X1096800Y424417D01*
X1096217Y424083D01*
X1095717Y424000D01*
X1095217Y424083D01*
X1094717Y424333D01*
X1094300Y424750D01*
G01X1100150Y426250D02*
X1102817D01*
X1102567Y426833D01*
X1102150Y427167D01*
X1101567Y427333D01*
X1100983Y427250D01*
X1100483Y427000D01*
X1100150Y426417D01*
X1099983Y425917D01*
Y425417D01*
X1100150Y424917D01*
X1100567Y424417D01*
X1101067Y424083D01*
X1101650Y424000D01*
X1102233Y424167D01*
X1102817Y424667D01*
G01X1111100Y422333D02*
Y427333D01*
G01Y426583D02*
X1111517Y427000D01*
X1111933Y427250D01*
X1112600Y427333D01*
X1113183Y427250D01*
X1113767Y426833D01*
X1114017Y426250D01*
X1114100Y425667D01*
X1114017Y425083D01*
X1113767Y424500D01*
X1113267Y424167D01*
X1112600Y424000D01*
X1112017Y424083D01*
X1111433Y424333D01*
X1111100Y424667D01*
G01X1118200Y424000D02*
Y429000D01*
G01X1122383Y427333D02*
Y425000D01*
X1122717Y424417D01*
X1123217Y424083D01*
X1123800Y424000D01*
X1124383Y424083D01*
X1124883Y424417D01*
X1125217Y425000D01*
G01Y424000D02*
Y427333D01*
G01X1128233Y422750D02*
X1128817Y422417D01*
X1129483Y422333D01*
X1130067Y422417D01*
X1130567Y422833D01*
X1130900Y423417D01*
Y427333D01*
G01Y426667D02*
X1130567Y427000D01*
X1130067Y427250D01*
X1129483Y427333D01*
X1128817Y427167D01*
X1128400Y426833D01*
X1128067Y426250D01*
X1127900Y425667D01*
X1127983Y425167D01*
X1128317Y424583D01*
X1128817Y424167D01*
X1129483Y424000D01*
X1129983Y424083D01*
X1130567Y424417D01*
X1130900Y424750D01*
G01X1133833Y422750D02*
X1134417Y422417D01*
X1135083Y422333D01*
X1135667Y422417D01*
X1136167Y422833D01*
X1136500Y423417D01*
Y427333D01*
G01Y426667D02*
X1136167Y427000D01*
X1135667Y427250D01*
X1135083Y427333D01*
X1134417Y427167D01*
X1134000Y426833D01*
X1133667Y426250D01*
X1133500Y425667D01*
X1133583Y425167D01*
X1133917Y424583D01*
X1134417Y424167D01*
X1135083Y424000D01*
X1135583Y424083D01*
X1136167Y424417D01*
X1136500Y424750D01*
G01X1139350Y426250D02*
X1142017D01*
X1141767Y426833D01*
X1141350Y427167D01*
X1140767Y427333D01*
X1140183Y427250D01*
X1139683Y427000D01*
X1139350Y426417D01*
X1139183Y425917D01*
Y425417D01*
X1139350Y424917D01*
X1139767Y424417D01*
X1140267Y424083D01*
X1140850Y424000D01*
X1141433Y424167D01*
X1142017Y424667D01*
G01X1147700Y429000D02*
Y424000D01*
G01Y424750D02*
X1147367Y424333D01*
X1146867Y424083D01*
X1146283Y424000D01*
X1145617Y424167D01*
X1145117Y424583D01*
X1144783Y425083D01*
X1144700Y425667D01*
X1144783Y426250D01*
X1145117Y426750D01*
X1145617Y427167D01*
X1146283Y427333D01*
X1146867Y427250D01*
X1147283Y427083D01*
X1147700Y426750D01*
G01X1155317Y427333D02*
X1156317Y424000D01*
X1157400Y427333D01*
X1158483Y424000D01*
X1159483Y427333D01*
G01X1163000D02*
Y424000D01*
G01Y428667D02*
X1162833Y428750D01*
Y428917D01*
X1163000Y429000D01*
X1163167Y428917D01*
Y428750D01*
X1163000Y428667D01*
G01X1168600Y429000D02*
Y424000D01*
G01X1167433Y427333D02*
X1169767D01*
G01X1172783Y424000D02*
Y429000D01*
G01Y426583D02*
X1173200Y427000D01*
X1173617Y427250D01*
X1174283Y427333D01*
X1174783Y427250D01*
X1175367Y426917D01*
X1175617Y426417D01*
Y424000D01*
G01X1183733D02*
X1187067Y425667D01*
X1183733Y427333D01*
G01X1189583Y424583D02*
X1190167Y424167D01*
X1190833Y424000D01*
X1191500Y424167D01*
X1192083Y424667D01*
X1192500Y425417D01*
X1192667Y426167D01*
Y427083D01*
X1192500Y427833D01*
X1192083Y428500D01*
X1191583Y428833D01*
X1191000Y429000D01*
X1190333Y428833D01*
X1189833Y428500D01*
X1189500Y428000D01*
X1189333Y427333D01*
X1189500Y426750D01*
X1189917Y426167D01*
X1190417Y425833D01*
X1191000Y425750D01*
X1191667Y425917D01*
X1192167Y426333D01*
X1192667Y427083D01*
G01X1196600Y429000D02*
X1195933Y428833D01*
X1195433Y428417D01*
X1195100Y427917D01*
X1194850Y427250D01*
X1194767Y426500D01*
X1194850Y425750D01*
X1195100Y425083D01*
X1195433Y424583D01*
X1195933Y424167D01*
X1196600Y424000D01*
X1197267Y424167D01*
X1197767Y424583D01*
X1198100Y425083D01*
X1198350Y425750D01*
X1198433Y426500D01*
X1198350Y427250D01*
X1198100Y427917D01*
X1197767Y428417D01*
X1197267Y428833D01*
X1196600Y429000D01*
G01X1200700Y423833D02*
X1203700Y429000D01*
G01X1200700D02*
X1200200Y428833D01*
X1199950Y428583D01*
X1199783Y428083D01*
X1199950Y427583D01*
X1200200Y427333D01*
X1200700Y427167D01*
X1201200Y427333D01*
X1201450Y427583D01*
X1201617Y428083D01*
X1201450Y428583D01*
X1201200Y428833D01*
X1200700Y429000D01*
G01X1203700Y425667D02*
X1203200Y425500D01*
X1202950Y425250D01*
X1202783Y424750D01*
X1202950Y424250D01*
X1203200Y424000D01*
X1203700Y423833D01*
X1204200Y424000D01*
X1204450Y424250D01*
X1204617Y424750D01*
X1204450Y425250D01*
X1204200Y425500D01*
X1203700Y425667D01*
G01X1212233Y424000D02*
Y427333D01*
G01Y426667D02*
X1212650Y427000D01*
X1213067Y427250D01*
X1213650Y427333D01*
X1214067Y427250D01*
X1214567Y427000D01*
G01X1217750Y426250D02*
X1220417D01*
X1220167Y426833D01*
X1219750Y427167D01*
X1219167Y427333D01*
X1218583Y427250D01*
X1218083Y427000D01*
X1217750Y426417D01*
X1217583Y425917D01*
Y425417D01*
X1217750Y424917D01*
X1218167Y424417D01*
X1218667Y424083D01*
X1219250Y424000D01*
X1219833Y424167D01*
X1220417Y424667D01*
G01X1223350Y424583D02*
X1223767Y424250D01*
X1224350Y424000D01*
X1224850D01*
X1225350Y424167D01*
X1225683Y424417D01*
X1225850Y424750D01*
X1225767Y425250D01*
X1225433Y425500D01*
X1223933Y426000D01*
X1223600Y426583D01*
X1223767Y427000D01*
X1224100Y427250D01*
X1224600Y427333D01*
X1225100Y427250D01*
X1225600Y427000D01*
G01X1230200Y427333D02*
Y424000D01*
G01Y428667D02*
X1230033Y428750D01*
Y428917D01*
X1230200Y429000D01*
X1230367Y428917D01*
Y428750D01*
X1230200Y428667D01*
G01X1234383Y424000D02*
Y427333D01*
G01Y426500D02*
X1234717Y426917D01*
X1235217Y427250D01*
X1235883Y427333D01*
X1236467Y427250D01*
X1236967Y426917D01*
X1237217Y426333D01*
Y424000D01*
G01X1246417Y422500D02*
X1247583Y423667D01*
Y424833D01*
X1246417D01*
Y423667D01*
X1247583D01*
G01Y425667D02*
Y426833D01*
X1246417D01*
Y425667D01*
X1247583D01*
G01X1250767Y424000D02*
Y429000D01*
X1252433D01*
X1253100Y428750D01*
X1253600Y428417D01*
X1254017Y427917D01*
X1254350Y427333D01*
X1254433Y426500D01*
X1254350Y425667D01*
X1254017Y425083D01*
X1253600Y424583D01*
X1253100Y424250D01*
X1252433Y424000D01*
X1250767D01*
G01X1258200D02*
X1257700Y424083D01*
X1257200Y424417D01*
X1256867Y425000D01*
X1256700Y425667D01*
X1256867Y426333D01*
X1257200Y426917D01*
X1257700Y427250D01*
X1258200Y427333D01*
X1258700Y427250D01*
X1259200Y426917D01*
X1259533Y426333D01*
X1259617Y425667D01*
X1259533Y425000D01*
X1259200Y424417D01*
X1258700Y424083D01*
X1258200Y424000D01*
G01X1267983D02*
Y427333D01*
G01Y426500D02*
X1268317Y426917D01*
X1268817Y427250D01*
X1269483Y427333D01*
X1270067Y427250D01*
X1270567Y426917D01*
X1270817Y426333D01*
Y424000D01*
G01X1275000D02*
X1274500Y424083D01*
X1274000Y424417D01*
X1273667Y425000D01*
X1273500Y425667D01*
X1273667Y426333D01*
X1274000Y426917D01*
X1274500Y427250D01*
X1275000Y427333D01*
X1275500Y427250D01*
X1276000Y426917D01*
X1276333Y426333D01*
X1276417Y425667D01*
X1276333Y425000D01*
X1276000Y424417D01*
X1275500Y424083D01*
X1275000Y424000D01*
G01X1280600Y429000D02*
Y424000D01*
G01X1279433Y427333D02*
X1281767D01*
G01X1293300Y424000D02*
Y427333D01*
G01Y426750D02*
X1292967Y427083D01*
X1292467Y427250D01*
X1291883Y427333D01*
X1291300Y427167D01*
X1290800Y426833D01*
X1290467Y426333D01*
X1290300Y425667D01*
X1290467Y425000D01*
X1290800Y424500D01*
X1291300Y424167D01*
X1291883Y424000D01*
X1292467Y424083D01*
X1292967Y424333D01*
X1293300Y424667D01*
G01X1297400Y424000D02*
Y429000D01*
G01X1303000Y424000D02*
Y429000D01*
G01X1308600Y424000D02*
X1308100Y424083D01*
X1307600Y424417D01*
X1307267Y425000D01*
X1307100Y425667D01*
X1307267Y426333D01*
X1307600Y426917D01*
X1308100Y427250D01*
X1308600Y427333D01*
X1309100Y427250D01*
X1309600Y426917D01*
X1309933Y426333D01*
X1310017Y425667D01*
X1309933Y425000D01*
X1309600Y424417D01*
X1309100Y424083D01*
X1308600Y424000D01*
G01X1312117Y427333D02*
X1313117Y424000D01*
X1314200Y427333D01*
X1315283Y424000D01*
X1316283Y427333D01*
G01X1016000Y604500D02*
Y366000D01*
G01X1025417Y445500D02*
X1027500Y440500D01*
X1029583Y445500D01*
G01X1033100Y443833D02*
Y440500D01*
G01Y445167D02*
X1032933Y445250D01*
Y445417D01*
X1033100Y445500D01*
X1033267Y445417D01*
Y445250D01*
X1033100Y445167D01*
G01X1040200Y440500D02*
Y443833D01*
G01Y443250D02*
X1039867Y443583D01*
X1039367Y443750D01*
X1038783Y443833D01*
X1038200Y443667D01*
X1037700Y443333D01*
X1037367Y442833D01*
X1037200Y442167D01*
X1037367Y441500D01*
X1037700Y441000D01*
X1038200Y440667D01*
X1038783Y440500D01*
X1039367Y440583D01*
X1039867Y440833D01*
X1040200Y441167D01*
G01X1048650Y441083D02*
X1049067Y440750D01*
X1049650Y440500D01*
X1050150D01*
X1050650Y440667D01*
X1050983Y440917D01*
X1051150Y441250D01*
X1051067Y441750D01*
X1050733Y442000D01*
X1049233Y442500D01*
X1048900Y443083D01*
X1049067Y443500D01*
X1049400Y443750D01*
X1049900Y443833D01*
X1050400Y443750D01*
X1050900Y443500D01*
G01X1054083Y440500D02*
Y445500D01*
G01Y443083D02*
X1054500Y443500D01*
X1054917Y443750D01*
X1055583Y443833D01*
X1056083Y443750D01*
X1056667Y443417D01*
X1056917Y442917D01*
Y440500D01*
G01X1061100D02*
X1060600Y440583D01*
X1060100Y440917D01*
X1059767Y441500D01*
X1059600Y442167D01*
X1059767Y442833D01*
X1060100Y443417D01*
X1060600Y443750D01*
X1061100Y443833D01*
X1061600Y443750D01*
X1062100Y443417D01*
X1062433Y442833D01*
X1062517Y442167D01*
X1062433Y441500D01*
X1062100Y440917D01*
X1061600Y440583D01*
X1061100Y440500D01*
G01X1065283Y443833D02*
Y441500D01*
X1065617Y440917D01*
X1066117Y440583D01*
X1066700Y440500D01*
X1067283Y440583D01*
X1067783Y440917D01*
X1068117Y441500D01*
G01Y440500D02*
Y443833D01*
G01X1072300Y440500D02*
Y445500D01*
G01X1079400D02*
Y440500D01*
G01Y441250D02*
X1079067Y440833D01*
X1078567Y440583D01*
X1077983Y440500D01*
X1077317Y440667D01*
X1076817Y441083D01*
X1076483Y441583D01*
X1076400Y442167D01*
X1076483Y442750D01*
X1076817Y443250D01*
X1077317Y443667D01*
X1077983Y443833D01*
X1078567Y443750D01*
X1078983Y443583D01*
X1079400Y443250D01*
G01X1087600Y440500D02*
Y445500D01*
G01Y443000D02*
X1088017Y443500D01*
X1088517Y443750D01*
X1089017Y443833D01*
X1089767Y443667D01*
X1090267Y443333D01*
X1090600Y442750D01*
Y442083D01*
X1090433Y441417D01*
X1090100Y440917D01*
X1089517Y440583D01*
X1089017Y440500D01*
X1088517Y440583D01*
X1088017Y440833D01*
X1087600Y441250D01*
G01X1093450Y442750D02*
X1096117D01*
X1095867Y443333D01*
X1095450Y443667D01*
X1094867Y443833D01*
X1094283Y443750D01*
X1093783Y443500D01*
X1093450Y442917D01*
X1093283Y442417D01*
Y441917D01*
X1093450Y441417D01*
X1093867Y440917D01*
X1094367Y440583D01*
X1094950Y440500D01*
X1095533Y440667D01*
X1096117Y441167D01*
G01X1104400Y438833D02*
Y443833D01*
G01Y443083D02*
X1104817Y443500D01*
X1105233Y443750D01*
X1105900Y443833D01*
X1106483Y443750D01*
X1107067Y443333D01*
X1107317Y442750D01*
X1107400Y442167D01*
X1107317Y441583D01*
X1107067Y441000D01*
X1106567Y440667D01*
X1105900Y440500D01*
X1105317Y440583D01*
X1104733Y440833D01*
X1104400Y441167D01*
G01X1111500Y440500D02*
Y445500D01*
G01X1115683Y443833D02*
Y441500D01*
X1116017Y440917D01*
X1116517Y440583D01*
X1117100Y440500D01*
X1117683Y440583D01*
X1118183Y440917D01*
X1118517Y441500D01*
G01Y440500D02*
Y443833D01*
G01X1121533Y439250D02*
X1122117Y438917D01*
X1122783Y438833D01*
X1123367Y438917D01*
X1123867Y439333D01*
X1124200Y439917D01*
Y443833D01*
G01Y443167D02*
X1123867Y443500D01*
X1123367Y443750D01*
X1122783Y443833D01*
X1122117Y443667D01*
X1121700Y443333D01*
X1121367Y442750D01*
X1121200Y442167D01*
X1121283Y441667D01*
X1121617Y441083D01*
X1122117Y440667D01*
X1122783Y440500D01*
X1123283Y440583D01*
X1123867Y440917D01*
X1124200Y441250D01*
G01X1127133Y439250D02*
X1127717Y438917D01*
X1128383Y438833D01*
X1128967Y438917D01*
X1129467Y439333D01*
X1129800Y439917D01*
Y443833D01*
G01Y443167D02*
X1129467Y443500D01*
X1128967Y443750D01*
X1128383Y443833D01*
X1127717Y443667D01*
X1127300Y443333D01*
X1126967Y442750D01*
X1126800Y442167D01*
X1126883Y441667D01*
X1127217Y441083D01*
X1127717Y440667D01*
X1128383Y440500D01*
X1128883Y440583D01*
X1129467Y440917D01*
X1129800Y441250D01*
G01X1132650Y442750D02*
X1135317D01*
X1135067Y443333D01*
X1134650Y443667D01*
X1134067Y443833D01*
X1133483Y443750D01*
X1132983Y443500D01*
X1132650Y442917D01*
X1132483Y442417D01*
Y441917D01*
X1132650Y441417D01*
X1133067Y440917D01*
X1133567Y440583D01*
X1134150Y440500D01*
X1134733Y440667D01*
X1135317Y441167D01*
G01X1141000Y445500D02*
Y440500D01*
G01Y441250D02*
X1140667Y440833D01*
X1140167Y440583D01*
X1139583Y440500D01*
X1138917Y440667D01*
X1138417Y441083D01*
X1138083Y441583D01*
X1138000Y442167D01*
X1138083Y442750D01*
X1138417Y443250D01*
X1138917Y443667D01*
X1139583Y443833D01*
X1140167Y443750D01*
X1140583Y443583D01*
X1141000Y443250D01*
G01X1148617Y443833D02*
X1149617Y440500D01*
X1150700Y443833D01*
X1151783Y440500D01*
X1152783Y443833D01*
G01X1156300D02*
Y440500D01*
G01Y445167D02*
X1156133Y445250D01*
Y445417D01*
X1156300Y445500D01*
X1156467Y445417D01*
Y445250D01*
X1156300Y445167D01*
G01X1161900Y445500D02*
Y440500D01*
G01X1160733Y443833D02*
X1163067D01*
G01X1166083Y440500D02*
Y445500D01*
G01Y443083D02*
X1166500Y443500D01*
X1166917Y443750D01*
X1167583Y443833D01*
X1168083Y443750D01*
X1168667Y443417D01*
X1168917Y442917D01*
Y440500D01*
G01X1177033D02*
X1180367Y442167D01*
X1177033Y443833D01*
G01X1182883Y441083D02*
X1183467Y440667D01*
X1184133Y440500D01*
X1184800Y440667D01*
X1185383Y441167D01*
X1185800Y441917D01*
X1185967Y442667D01*
Y443583D01*
X1185800Y444333D01*
X1185383Y445000D01*
X1184883Y445333D01*
X1184300Y445500D01*
X1183633Y445333D01*
X1183133Y445000D01*
X1182800Y444500D01*
X1182633Y443833D01*
X1182800Y443250D01*
X1183217Y442667D01*
X1183717Y442333D01*
X1184300Y442250D01*
X1184967Y442417D01*
X1185467Y442833D01*
X1185967Y443583D01*
G01X1189900Y445500D02*
X1189233Y445333D01*
X1188733Y444917D01*
X1188400Y444417D01*
X1188150Y443750D01*
X1188067Y443000D01*
X1188150Y442250D01*
X1188400Y441583D01*
X1188733Y441083D01*
X1189233Y440667D01*
X1189900Y440500D01*
X1190567Y440667D01*
X1191067Y441083D01*
X1191400Y441583D01*
X1191650Y442250D01*
X1191733Y443000D01*
X1191650Y443750D01*
X1191400Y444417D01*
X1191067Y444917D01*
X1190567Y445333D01*
X1189900Y445500D01*
G01X1194000Y440333D02*
X1197000Y445500D01*
G01X1194000D02*
X1193500Y445333D01*
X1193250Y445083D01*
X1193083Y444583D01*
X1193250Y444083D01*
X1193500Y443833D01*
X1194000Y443667D01*
X1194500Y443833D01*
X1194750Y444083D01*
X1194917Y444583D01*
X1194750Y445083D01*
X1194500Y445333D01*
X1194000Y445500D01*
G01X1197000Y442167D02*
X1196500Y442000D01*
X1196250Y441750D01*
X1196083Y441250D01*
X1196250Y440750D01*
X1196500Y440500D01*
X1197000Y440333D01*
X1197500Y440500D01*
X1197750Y440750D01*
X1197917Y441250D01*
X1197750Y441750D01*
X1197500Y442000D01*
X1197000Y442167D01*
G01X1205533Y440500D02*
Y443833D01*
G01Y443167D02*
X1205950Y443500D01*
X1206367Y443750D01*
X1206950Y443833D01*
X1207367Y443750D01*
X1207867Y443500D01*
G01X1211050Y442750D02*
X1213717D01*
X1213467Y443333D01*
X1213050Y443667D01*
X1212467Y443833D01*
X1211883Y443750D01*
X1211383Y443500D01*
X1211050Y442917D01*
X1210883Y442417D01*
Y441917D01*
X1211050Y441417D01*
X1211467Y440917D01*
X1211967Y440583D01*
X1212550Y440500D01*
X1213133Y440667D01*
X1213717Y441167D01*
G01X1216650Y441083D02*
X1217067Y440750D01*
X1217650Y440500D01*
X1218150D01*
X1218650Y440667D01*
X1218983Y440917D01*
X1219150Y441250D01*
X1219067Y441750D01*
X1218733Y442000D01*
X1217233Y442500D01*
X1216900Y443083D01*
X1217067Y443500D01*
X1217400Y443750D01*
X1217900Y443833D01*
X1218400Y443750D01*
X1218900Y443500D01*
G01X1223500Y443833D02*
Y440500D01*
G01Y445167D02*
X1223333Y445250D01*
Y445417D01*
X1223500Y445500D01*
X1223667Y445417D01*
Y445250D01*
X1223500Y445167D01*
G01X1227683Y440500D02*
Y443833D01*
G01Y443000D02*
X1228017Y443417D01*
X1228517Y443750D01*
X1229183Y443833D01*
X1229767Y443750D01*
X1230267Y443417D01*
X1230517Y442833D01*
Y440500D01*
G01X1023917Y466500D02*
X1026000Y461500D01*
X1028083Y466500D01*
G01X1031600Y464833D02*
Y461500D01*
G01Y466167D02*
X1031433Y466250D01*
Y466417D01*
X1031600Y466500D01*
X1031767Y466417D01*
Y466250D01*
X1031600Y466167D01*
G01X1038700Y461500D02*
Y464833D01*
G01Y464250D02*
X1038367Y464583D01*
X1037867Y464750D01*
X1037283Y464833D01*
X1036700Y464667D01*
X1036200Y464333D01*
X1035867Y463833D01*
X1035700Y463167D01*
X1035867Y462500D01*
X1036200Y462000D01*
X1036700Y461667D01*
X1037283Y461500D01*
X1037867Y461583D01*
X1038367Y461833D01*
X1038700Y462167D01*
G01X1047150Y462083D02*
X1047567Y461750D01*
X1048150Y461500D01*
X1048650D01*
X1049150Y461667D01*
X1049483Y461917D01*
X1049650Y462250D01*
X1049567Y462750D01*
X1049233Y463000D01*
X1047733Y463500D01*
X1047400Y464083D01*
X1047567Y464500D01*
X1047900Y464750D01*
X1048400Y464833D01*
X1048900Y464750D01*
X1049400Y464500D01*
G01X1052583Y461500D02*
Y466500D01*
G01Y464083D02*
X1053000Y464500D01*
X1053417Y464750D01*
X1054083Y464833D01*
X1054583Y464750D01*
X1055167Y464417D01*
X1055417Y463917D01*
Y461500D01*
G01X1059600D02*
X1059100Y461583D01*
X1058600Y461917D01*
X1058267Y462500D01*
X1058100Y463167D01*
X1058267Y463833D01*
X1058600Y464417D01*
X1059100Y464750D01*
X1059600Y464833D01*
X1060100Y464750D01*
X1060600Y464417D01*
X1060933Y463833D01*
X1061017Y463167D01*
X1060933Y462500D01*
X1060600Y461917D01*
X1060100Y461583D01*
X1059600Y461500D01*
G01X1063783Y464833D02*
Y462500D01*
X1064117Y461917D01*
X1064617Y461583D01*
X1065200Y461500D01*
X1065783Y461583D01*
X1066283Y461917D01*
X1066617Y462500D01*
G01Y461500D02*
Y464833D01*
G01X1070800Y461500D02*
Y466500D01*
G01X1077900D02*
Y461500D01*
G01Y462250D02*
X1077567Y461833D01*
X1077067Y461583D01*
X1076483Y461500D01*
X1075817Y461667D01*
X1075317Y462083D01*
X1074983Y462583D01*
X1074900Y463167D01*
X1074983Y463750D01*
X1075317Y464250D01*
X1075817Y464667D01*
X1076483Y464833D01*
X1077067Y464750D01*
X1077483Y464583D01*
X1077900Y464250D01*
G01X1086100Y461500D02*
Y466500D01*
G01Y464000D02*
X1086517Y464500D01*
X1087017Y464750D01*
X1087517Y464833D01*
X1088267Y464667D01*
X1088767Y464333D01*
X1089100Y463750D01*
Y463083D01*
X1088933Y462417D01*
X1088600Y461917D01*
X1088017Y461583D01*
X1087517Y461500D01*
X1087017Y461583D01*
X1086517Y461833D01*
X1086100Y462250D01*
G01X1091950Y463750D02*
X1094617D01*
X1094367Y464333D01*
X1093950Y464667D01*
X1093367Y464833D01*
X1092783Y464750D01*
X1092283Y464500D01*
X1091950Y463917D01*
X1091783Y463417D01*
Y462917D01*
X1091950Y462417D01*
X1092367Y461917D01*
X1092867Y461583D01*
X1093450Y461500D01*
X1094033Y461667D01*
X1094617Y462167D01*
G01X1102900Y459833D02*
Y464833D01*
G01Y464083D02*
X1103317Y464500D01*
X1103733Y464750D01*
X1104400Y464833D01*
X1104983Y464750D01*
X1105567Y464333D01*
X1105817Y463750D01*
X1105900Y463167D01*
X1105817Y462583D01*
X1105567Y462000D01*
X1105067Y461667D01*
X1104400Y461500D01*
X1103817Y461583D01*
X1103233Y461833D01*
X1102900Y462167D01*
G01X1110000Y461500D02*
Y466500D01*
G01X1114183Y464833D02*
Y462500D01*
X1114517Y461917D01*
X1115017Y461583D01*
X1115600Y461500D01*
X1116183Y461583D01*
X1116683Y461917D01*
X1117017Y462500D01*
G01Y461500D02*
Y464833D01*
G01X1120033Y460250D02*
X1120617Y459917D01*
X1121283Y459833D01*
X1121867Y459917D01*
X1122367Y460333D01*
X1122700Y460917D01*
Y464833D01*
G01Y464167D02*
X1122367Y464500D01*
X1121867Y464750D01*
X1121283Y464833D01*
X1120617Y464667D01*
X1120200Y464333D01*
X1119867Y463750D01*
X1119700Y463167D01*
X1119783Y462667D01*
X1120117Y462083D01*
X1120617Y461667D01*
X1121283Y461500D01*
X1121783Y461583D01*
X1122367Y461917D01*
X1122700Y462250D01*
G01X1125633Y460250D02*
X1126217Y459917D01*
X1126883Y459833D01*
X1127467Y459917D01*
X1127967Y460333D01*
X1128300Y460917D01*
Y464833D01*
G01Y464167D02*
X1127967Y464500D01*
X1127467Y464750D01*
X1126883Y464833D01*
X1126217Y464667D01*
X1125800Y464333D01*
X1125467Y463750D01*
X1125300Y463167D01*
X1125383Y462667D01*
X1125717Y462083D01*
X1126217Y461667D01*
X1126883Y461500D01*
X1127383Y461583D01*
X1127967Y461917D01*
X1128300Y462250D01*
G01X1131150Y463750D02*
X1133817D01*
X1133567Y464333D01*
X1133150Y464667D01*
X1132567Y464833D01*
X1131983Y464750D01*
X1131483Y464500D01*
X1131150Y463917D01*
X1130983Y463417D01*
Y462917D01*
X1131150Y462417D01*
X1131567Y461917D01*
X1132067Y461583D01*
X1132650Y461500D01*
X1133233Y461667D01*
X1133817Y462167D01*
G01X1139500Y466500D02*
Y461500D01*
G01Y462250D02*
X1139167Y461833D01*
X1138667Y461583D01*
X1138083Y461500D01*
X1137417Y461667D01*
X1136917Y462083D01*
X1136583Y462583D01*
X1136500Y463167D01*
X1136583Y463750D01*
X1136917Y464250D01*
X1137417Y464667D01*
X1138083Y464833D01*
X1138667Y464750D01*
X1139083Y464583D01*
X1139500Y464250D01*
G01X1150200Y461500D02*
Y466500D01*
X1147117Y462917D01*
X1151283D01*
G01X1154800Y466500D02*
X1154133Y466333D01*
X1153633Y465917D01*
X1153300Y465417D01*
X1153050Y464750D01*
X1152967Y464000D01*
X1153050Y463250D01*
X1153300Y462583D01*
X1153633Y462083D01*
X1154133Y461667D01*
X1154800Y461500D01*
X1155467Y461667D01*
X1155967Y462083D01*
X1156300Y462583D01*
X1156550Y463250D01*
X1156633Y464000D01*
X1156550Y464750D01*
X1156300Y465417D01*
X1155967Y465917D01*
X1155467Y466333D01*
X1154800Y466500D01*
G01X1158900Y461333D02*
X1161900Y466500D01*
G01X1158900D02*
X1158400Y466333D01*
X1158150Y466083D01*
X1157983Y465583D01*
X1158150Y465083D01*
X1158400Y464833D01*
X1158900Y464667D01*
X1159400Y464833D01*
X1159650Y465083D01*
X1159817Y465583D01*
X1159650Y466083D01*
X1159400Y466333D01*
X1158900Y466500D01*
G01X1161900Y463167D02*
X1161400Y463000D01*
X1161150Y462750D01*
X1160983Y462250D01*
X1161150Y461750D01*
X1161400Y461500D01*
X1161900Y461333D01*
X1162400Y461500D01*
X1162650Y461750D01*
X1162817Y462250D01*
X1162650Y462750D01*
X1162400Y463000D01*
X1161900Y463167D01*
G01X1169100D02*
X1169933Y464833D01*
X1170767D01*
X1172433Y461500D01*
X1173267D01*
X1174100Y463167D01*
G01X1182800Y461500D02*
Y466500D01*
X1181800Y465500D01*
G01Y461500D02*
X1183800D01*
G01X1188400Y466500D02*
X1187733Y466333D01*
X1187233Y465917D01*
X1186900Y465417D01*
X1186650Y464750D01*
X1186567Y464000D01*
X1186650Y463250D01*
X1186900Y462583D01*
X1187233Y462083D01*
X1187733Y461667D01*
X1188400Y461500D01*
X1189067Y461667D01*
X1189567Y462083D01*
X1189900Y462583D01*
X1190150Y463250D01*
X1190233Y464000D01*
X1190150Y464750D01*
X1189900Y465417D01*
X1189567Y465917D01*
X1189067Y466333D01*
X1188400Y466500D01*
G01X1194000D02*
X1193333Y466333D01*
X1192833Y465917D01*
X1192500Y465417D01*
X1192250Y464750D01*
X1192167Y464000D01*
X1192250Y463250D01*
X1192500Y462583D01*
X1192833Y462083D01*
X1193333Y461667D01*
X1194000Y461500D01*
X1194667Y461667D01*
X1195167Y462083D01*
X1195500Y462583D01*
X1195750Y463250D01*
X1195833Y464000D01*
X1195750Y464750D01*
X1195500Y465417D01*
X1195167Y465917D01*
X1194667Y466333D01*
X1194000Y466500D01*
G01X1198100Y461333D02*
X1201100Y466500D01*
G01X1198100D02*
X1197600Y466333D01*
X1197350Y466083D01*
X1197183Y465583D01*
X1197350Y465083D01*
X1197600Y464833D01*
X1198100Y464667D01*
X1198600Y464833D01*
X1198850Y465083D01*
X1199017Y465583D01*
X1198850Y466083D01*
X1198600Y466333D01*
X1198100Y466500D01*
G01X1201100Y463167D02*
X1200600Y463000D01*
X1200350Y462750D01*
X1200183Y462250D01*
X1200350Y461750D01*
X1200600Y461500D01*
X1201100Y461333D01*
X1201600Y461500D01*
X1201850Y461750D01*
X1202017Y462250D01*
X1201850Y462750D01*
X1201600Y463000D01*
X1201100Y463167D01*
G01X1209550Y462083D02*
X1209967Y461750D01*
X1210550Y461500D01*
X1211050D01*
X1211550Y461667D01*
X1211883Y461917D01*
X1212050Y462250D01*
X1211967Y462750D01*
X1211633Y463000D01*
X1210133Y463500D01*
X1209800Y464083D01*
X1209967Y464500D01*
X1210300Y464750D01*
X1210800Y464833D01*
X1211300Y464750D01*
X1211800Y464500D01*
G01X1216400Y461500D02*
X1215900Y461583D01*
X1215400Y461917D01*
X1215067Y462500D01*
X1214900Y463167D01*
X1215067Y463833D01*
X1215400Y464417D01*
X1215900Y464750D01*
X1216400Y464833D01*
X1216900Y464750D01*
X1217400Y464417D01*
X1217733Y463833D01*
X1217817Y463167D01*
X1217733Y462500D01*
X1217400Y461917D01*
X1216900Y461583D01*
X1216400Y461500D01*
G01X1222000D02*
Y466500D01*
G01X1229100D02*
Y461500D01*
G01Y462250D02*
X1228767Y461833D01*
X1228267Y461583D01*
X1227683Y461500D01*
X1227017Y461667D01*
X1226517Y462083D01*
X1226183Y462583D01*
X1226100Y463167D01*
X1226183Y463750D01*
X1226517Y464250D01*
X1227017Y464667D01*
X1227683Y464833D01*
X1228267Y464750D01*
X1228683Y464583D01*
X1229100Y464250D01*
G01X1231950Y463750D02*
X1234617D01*
X1234367Y464333D01*
X1233950Y464667D01*
X1233367Y464833D01*
X1232783Y464750D01*
X1232283Y464500D01*
X1231950Y463917D01*
X1231783Y463417D01*
Y462917D01*
X1231950Y462417D01*
X1232367Y461917D01*
X1232867Y461583D01*
X1233450Y461500D01*
X1234033Y461667D01*
X1234617Y462167D01*
G01X1237633Y461500D02*
Y464833D01*
G01Y464167D02*
X1238050Y464500D01*
X1238467Y464750D01*
X1239050Y464833D01*
X1239467Y464750D01*
X1239967Y464500D01*
G01X1247500Y461500D02*
Y464833D01*
G01Y463917D02*
X1247750Y464333D01*
X1248167Y464667D01*
X1248750Y464833D01*
X1249333Y464667D01*
X1249750Y464333D01*
X1250000Y463917D01*
Y461500D01*
G01Y463917D02*
X1250250Y464333D01*
X1250667Y464667D01*
X1251250Y464833D01*
X1251833Y464667D01*
X1252250Y464333D01*
X1252500Y463833D01*
Y461500D01*
G01X1257100D02*
Y464833D01*
G01Y464250D02*
X1256767Y464583D01*
X1256267Y464750D01*
X1255683Y464833D01*
X1255100Y464667D01*
X1254600Y464333D01*
X1254267Y463833D01*
X1254100Y463167D01*
X1254267Y462500D01*
X1254600Y462000D01*
X1255100Y461667D01*
X1255683Y461500D01*
X1256267Y461583D01*
X1256767Y461833D01*
X1257100Y462167D01*
G01X1259950Y462083D02*
X1260367Y461750D01*
X1260950Y461500D01*
X1261450D01*
X1261950Y461667D01*
X1262283Y461917D01*
X1262450Y462250D01*
X1262367Y462750D01*
X1262033Y463000D01*
X1260533Y463500D01*
X1260200Y464083D01*
X1260367Y464500D01*
X1260700Y464750D01*
X1261200Y464833D01*
X1261700Y464750D01*
X1262200Y464500D01*
G01X1265383Y461500D02*
Y466500D01*
G01X1268050Y464833D02*
X1265383Y462917D01*
G01X1266467Y463667D02*
X1268217Y461500D01*
G01X1046500Y485833D02*
X1048000Y482500D01*
X1049500Y485833D01*
G01X1053600D02*
Y482500D01*
G01Y487167D02*
X1053433Y487250D01*
Y487417D01*
X1053600Y487500D01*
X1053767Y487417D01*
Y487250D01*
X1053600Y487167D01*
G01X1060700Y482500D02*
Y485833D01*
G01Y485250D02*
X1060367Y485583D01*
X1059867Y485750D01*
X1059283Y485833D01*
X1058700Y485667D01*
X1058200Y485333D01*
X1057867Y484833D01*
X1057700Y484167D01*
X1057867Y483500D01*
X1058200Y483000D01*
X1058700Y482667D01*
X1059283Y482500D01*
X1059867Y482583D01*
X1060367Y482833D01*
X1060700Y483167D01*
G01X1069150Y483083D02*
X1069567Y482750D01*
X1070150Y482500D01*
X1070650D01*
X1071150Y482667D01*
X1071483Y482917D01*
X1071650Y483250D01*
X1071567Y483750D01*
X1071233Y484000D01*
X1069733Y484500D01*
X1069400Y485083D01*
X1069567Y485500D01*
X1069900Y485750D01*
X1070400Y485833D01*
X1070900Y485750D01*
X1071400Y485500D01*
G01X1074583Y482500D02*
Y487500D01*
G01Y485083D02*
X1075000Y485500D01*
X1075417Y485750D01*
X1076083Y485833D01*
X1076583Y485750D01*
X1077167Y485417D01*
X1077417Y484917D01*
Y482500D01*
G01X1083100D02*
Y485833D01*
G01Y485250D02*
X1082767Y485583D01*
X1082267Y485750D01*
X1081683Y485833D01*
X1081100Y485667D01*
X1080600Y485333D01*
X1080267Y484833D01*
X1080100Y484167D01*
X1080267Y483500D01*
X1080600Y483000D01*
X1081100Y482667D01*
X1081683Y482500D01*
X1082267Y482583D01*
X1082767Y482833D01*
X1083100Y483167D01*
G01X1087200Y482500D02*
Y487500D01*
G01X1092800Y482500D02*
Y487500D01*
G01X1102500Y482500D02*
Y487500D01*
G01Y485000D02*
X1102917Y485500D01*
X1103417Y485750D01*
X1103917Y485833D01*
X1104667Y485667D01*
X1105167Y485333D01*
X1105500Y484750D01*
Y484083D01*
X1105333Y483417D01*
X1105000Y482917D01*
X1104417Y482583D01*
X1103917Y482500D01*
X1103417Y482583D01*
X1102917Y482833D01*
X1102500Y483250D01*
G01X1108350Y484750D02*
X1111017D01*
X1110767Y485333D01*
X1110350Y485667D01*
X1109767Y485833D01*
X1109183Y485750D01*
X1108683Y485500D01*
X1108350Y484917D01*
X1108183Y484417D01*
Y483917D01*
X1108350Y483417D01*
X1108767Y482917D01*
X1109267Y482583D01*
X1109850Y482500D01*
X1110433Y482667D01*
X1111017Y483167D01*
G01X1118717Y485833D02*
X1119717Y482500D01*
X1120800Y485833D01*
X1121883Y482500D01*
X1122883Y485833D01*
G01X1126400D02*
Y482500D01*
G01Y487167D02*
X1126233Y487250D01*
Y487417D01*
X1126400Y487500D01*
X1126567Y487417D01*
Y487250D01*
X1126400Y487167D01*
G01X1132000Y487500D02*
Y482500D01*
G01X1130833Y485833D02*
X1133167D01*
G01X1136183Y482500D02*
Y487500D01*
G01Y485083D02*
X1136600Y485500D01*
X1137017Y485750D01*
X1137683Y485833D01*
X1138183Y485750D01*
X1138767Y485417D01*
X1139017Y484917D01*
Y482500D01*
G01X1150467D02*
X1147133Y484167D01*
X1150467Y485833D01*
G01X1160000Y482500D02*
X1160583Y482583D01*
X1161250Y482833D01*
X1161667Y483250D01*
X1161833Y483833D01*
X1161667Y484417D01*
X1161167Y484917D01*
X1160417Y485167D01*
X1159583D01*
X1159083Y485333D01*
X1158667Y485750D01*
X1158500Y486333D01*
X1158750Y486917D01*
X1159333Y487333D01*
X1160000Y487500D01*
X1160667Y487333D01*
X1161250Y486917D01*
X1161500Y486333D01*
X1161333Y485750D01*
X1160917Y485333D01*
X1160417Y485167D01*
X1159583D01*
X1158833Y484917D01*
X1158333Y484417D01*
X1158167Y483833D01*
X1158333Y483250D01*
X1158750Y482833D01*
X1159417Y482583D01*
X1160000Y482500D01*
G01X1165600Y487500D02*
X1164933Y487333D01*
X1164433Y486917D01*
X1164100Y486417D01*
X1163850Y485750D01*
X1163767Y485000D01*
X1163850Y484250D01*
X1164100Y483583D01*
X1164433Y483083D01*
X1164933Y482667D01*
X1165600Y482500D01*
X1166267Y482667D01*
X1166767Y483083D01*
X1167100Y483583D01*
X1167350Y484250D01*
X1167433Y485000D01*
X1167350Y485750D01*
X1167100Y486417D01*
X1166767Y486917D01*
X1166267Y487333D01*
X1165600Y487500D01*
G01X1175300Y482333D02*
X1178300Y487500D01*
G01X1175300D02*
X1174800Y487333D01*
X1174550Y487083D01*
X1174383Y486583D01*
X1174550Y486083D01*
X1174800Y485833D01*
X1175300Y485667D01*
X1175800Y485833D01*
X1176050Y486083D01*
X1176217Y486583D01*
X1176050Y487083D01*
X1175800Y487333D01*
X1175300Y487500D01*
G01X1178300Y484167D02*
X1177800Y484000D01*
X1177550Y483750D01*
X1177383Y483250D01*
X1177550Y482750D01*
X1177800Y482500D01*
X1178300Y482333D01*
X1178800Y482500D01*
X1179050Y482750D01*
X1179217Y483250D01*
X1179050Y483750D01*
X1178800Y484000D01*
X1178300Y484167D01*
G01X1186750Y483083D02*
X1187167Y482750D01*
X1187750Y482500D01*
X1188250D01*
X1188750Y482667D01*
X1189083Y482917D01*
X1189250Y483250D01*
X1189167Y483750D01*
X1188833Y484000D01*
X1187333Y484500D01*
X1187000Y485083D01*
X1187167Y485500D01*
X1187500Y485750D01*
X1188000Y485833D01*
X1188500Y485750D01*
X1189000Y485500D01*
G01X1193600Y482500D02*
X1193100Y482583D01*
X1192600Y482917D01*
X1192267Y483500D01*
X1192100Y484167D01*
X1192267Y484833D01*
X1192600Y485417D01*
X1193100Y485750D01*
X1193600Y485833D01*
X1194100Y485750D01*
X1194600Y485417D01*
X1194933Y484833D01*
X1195017Y484167D01*
X1194933Y483500D01*
X1194600Y482917D01*
X1194100Y482583D01*
X1193600Y482500D01*
G01X1199200D02*
Y487500D01*
G01X1206300D02*
Y482500D01*
G01Y483250D02*
X1205967Y482833D01*
X1205467Y482583D01*
X1204883Y482500D01*
X1204217Y482667D01*
X1203717Y483083D01*
X1203383Y483583D01*
X1203300Y484167D01*
X1203383Y484750D01*
X1203717Y485250D01*
X1204217Y485667D01*
X1204883Y485833D01*
X1205467Y485750D01*
X1205883Y485583D01*
X1206300Y485250D01*
G01X1209150Y484750D02*
X1211817D01*
X1211567Y485333D01*
X1211150Y485667D01*
X1210567Y485833D01*
X1209983Y485750D01*
X1209483Y485500D01*
X1209150Y484917D01*
X1208983Y484417D01*
Y483917D01*
X1209150Y483417D01*
X1209567Y482917D01*
X1210067Y482583D01*
X1210650Y482500D01*
X1211233Y482667D01*
X1211817Y483167D01*
G01X1214833Y482500D02*
Y485833D01*
G01Y485167D02*
X1215250Y485500D01*
X1215667Y485750D01*
X1216250Y485833D01*
X1216667Y485750D01*
X1217167Y485500D01*
G01X1224700Y482500D02*
Y485833D01*
G01Y484917D02*
X1224950Y485333D01*
X1225367Y485667D01*
X1225950Y485833D01*
X1226533Y485667D01*
X1226950Y485333D01*
X1227200Y484917D01*
Y482500D01*
G01Y484917D02*
X1227450Y485333D01*
X1227867Y485667D01*
X1228450Y485833D01*
X1229033Y485667D01*
X1229450Y485333D01*
X1229700Y484833D01*
Y482500D01*
G01X1234300D02*
Y485833D01*
G01Y485250D02*
X1233967Y485583D01*
X1233467Y485750D01*
X1232883Y485833D01*
X1232300Y485667D01*
X1231800Y485333D01*
X1231467Y484833D01*
X1231300Y484167D01*
X1231467Y483500D01*
X1231800Y483000D01*
X1232300Y482667D01*
X1232883Y482500D01*
X1233467Y482583D01*
X1233967Y482833D01*
X1234300Y483167D01*
G01X1237150Y483083D02*
X1237567Y482750D01*
X1238150Y482500D01*
X1238650D01*
X1239150Y482667D01*
X1239483Y482917D01*
X1239650Y483250D01*
X1239567Y483750D01*
X1239233Y484000D01*
X1237733Y484500D01*
X1237400Y485083D01*
X1237567Y485500D01*
X1237900Y485750D01*
X1238400Y485833D01*
X1238900Y485750D01*
X1239400Y485500D01*
G01X1242583Y482500D02*
Y487500D01*
G01X1245250Y485833D02*
X1242583Y483917D01*
G01X1243667Y484667D02*
X1245417Y482500D01*
G01X1035500Y491500D02*
Y496500D01*
G01Y494000D02*
X1035917Y494500D01*
X1036417Y494750D01*
X1036917Y494833D01*
X1037667Y494667D01*
X1038167Y494333D01*
X1038500Y493750D01*
Y493083D01*
X1038333Y492417D01*
X1038000Y491917D01*
X1037417Y491583D01*
X1036917Y491500D01*
X1036417Y491583D01*
X1035917Y491833D01*
X1035500Y492250D01*
G01X1042600Y491333D02*
X1042433Y491417D01*
Y491583D01*
X1042600Y491667D01*
X1042767Y491583D01*
Y491417D01*
X1042600Y491333D01*
G01X1048867Y494167D02*
X1049200Y494417D01*
X1049450Y494833D01*
X1049617Y495417D01*
X1049450Y495917D01*
X1049117Y496250D01*
X1048533Y496500D01*
X1046283D01*
Y491500D01*
X1049033D01*
X1049617Y491833D01*
X1049950Y492333D01*
X1050117Y492917D01*
X1049950Y493500D01*
X1049450Y494000D01*
X1048867Y494167D01*
X1046283D01*
G01X1053800Y491500D02*
X1053300Y491583D01*
X1052800Y491917D01*
X1052467Y492500D01*
X1052300Y493167D01*
X1052467Y493833D01*
X1052800Y494417D01*
X1053300Y494750D01*
X1053800Y494833D01*
X1054300Y494750D01*
X1054800Y494417D01*
X1055133Y493833D01*
X1055217Y493167D01*
X1055133Y492500D01*
X1054800Y491917D01*
X1054300Y491583D01*
X1053800Y491500D01*
G01X1060900D02*
Y494833D01*
G01Y494250D02*
X1060567Y494583D01*
X1060067Y494750D01*
X1059483Y494833D01*
X1058900Y494667D01*
X1058400Y494333D01*
X1058067Y493833D01*
X1057900Y493167D01*
X1058067Y492500D01*
X1058400Y492000D01*
X1058900Y491667D01*
X1059483Y491500D01*
X1060067Y491583D01*
X1060567Y491833D01*
X1060900Y492167D01*
G01X1063833Y491500D02*
Y494833D01*
G01Y494167D02*
X1064250Y494500D01*
X1064667Y494750D01*
X1065250Y494833D01*
X1065667Y494750D01*
X1066167Y494500D01*
G01X1072100Y496500D02*
Y491500D01*
G01Y492250D02*
X1071767Y491833D01*
X1071267Y491583D01*
X1070683Y491500D01*
X1070017Y491667D01*
X1069517Y492083D01*
X1069183Y492583D01*
X1069100Y493167D01*
X1069183Y493750D01*
X1069517Y494250D01*
X1070017Y494667D01*
X1070683Y494833D01*
X1071267Y494750D01*
X1071683Y494583D01*
X1072100Y494250D01*
G01X1081800Y496500D02*
Y491500D01*
G01X1080633Y494833D02*
X1082967D01*
G01X1085983Y491500D02*
Y496500D01*
G01Y494083D02*
X1086400Y494500D01*
X1086817Y494750D01*
X1087483Y494833D01*
X1087983Y494750D01*
X1088567Y494417D01*
X1088817Y493917D01*
Y491500D01*
G01X1093000Y494833D02*
Y491500D01*
G01Y496167D02*
X1092833Y496250D01*
Y496417D01*
X1093000Y496500D01*
X1093167Y496417D01*
Y496250D01*
X1093000Y496167D01*
G01X1099933Y494417D02*
X1099350Y494750D01*
X1098850Y494833D01*
X1098183Y494667D01*
X1097683Y494333D01*
X1097350Y493750D01*
X1097267Y493167D01*
X1097350Y492583D01*
X1097683Y492083D01*
X1098183Y491667D01*
X1098850Y491500D01*
X1099433Y491667D01*
X1099933Y492000D01*
G01X1102783Y491500D02*
Y496500D01*
G01X1105450Y494833D02*
X1102783Y492917D01*
G01X1103867Y493667D02*
X1105617Y491500D01*
G01X1108383D02*
Y494833D01*
G01Y494000D02*
X1108717Y494417D01*
X1109217Y494750D01*
X1109883Y494833D01*
X1110467Y494750D01*
X1110967Y494417D01*
X1111217Y493833D01*
Y491500D01*
G01X1114150Y493750D02*
X1116817D01*
X1116567Y494333D01*
X1116150Y494667D01*
X1115567Y494833D01*
X1114983Y494750D01*
X1114483Y494500D01*
X1114150Y493917D01*
X1113983Y493417D01*
Y492917D01*
X1114150Y492417D01*
X1114567Y491917D01*
X1115067Y491583D01*
X1115650Y491500D01*
X1116233Y491667D01*
X1116817Y492167D01*
G01X1119750Y492083D02*
X1120167Y491750D01*
X1120750Y491500D01*
X1121250D01*
X1121750Y491667D01*
X1122083Y491917D01*
X1122250Y492250D01*
X1122167Y492750D01*
X1121833Y493000D01*
X1120333Y493500D01*
X1120000Y494083D01*
X1120167Y494500D01*
X1120500Y494750D01*
X1121000Y494833D01*
X1121500Y494750D01*
X1122000Y494500D01*
G01X1125350Y492083D02*
X1125767Y491750D01*
X1126350Y491500D01*
X1126850D01*
X1127350Y491667D01*
X1127683Y491917D01*
X1127850Y492250D01*
X1127767Y492750D01*
X1127433Y493000D01*
X1125933Y493500D01*
X1125600Y494083D01*
X1125767Y494500D01*
X1126100Y494750D01*
X1126600Y494833D01*
X1127100Y494750D01*
X1127600Y494500D01*
G01X1139467Y491500D02*
X1136133Y493167D01*
X1139467Y494833D01*
G01X1149000Y496500D02*
X1148333Y496333D01*
X1147833Y495917D01*
X1147500Y495417D01*
X1147250Y494750D01*
X1147167Y494000D01*
X1147250Y493250D01*
X1147500Y492583D01*
X1147833Y492083D01*
X1148333Y491667D01*
X1149000Y491500D01*
X1149667Y491667D01*
X1150167Y492083D01*
X1150500Y492583D01*
X1150750Y493250D01*
X1150833Y494000D01*
X1150750Y494750D01*
X1150500Y495417D01*
X1150167Y495917D01*
X1149667Y496333D01*
X1149000Y496500D01*
G01X1154600Y491333D02*
X1154433Y491417D01*
Y491583D01*
X1154600Y491667D01*
X1154767Y491583D01*
Y491417D01*
X1154600Y491333D01*
G01X1158783Y492083D02*
X1159367Y491667D01*
X1160033Y491500D01*
X1160700Y491667D01*
X1161283Y492167D01*
X1161700Y492917D01*
X1161867Y493667D01*
Y494583D01*
X1161700Y495333D01*
X1161283Y496000D01*
X1160783Y496333D01*
X1160200Y496500D01*
X1159533Y496333D01*
X1159033Y496000D01*
X1158700Y495500D01*
X1158533Y494833D01*
X1158700Y494250D01*
X1159117Y493667D01*
X1159617Y493333D01*
X1160200Y493250D01*
X1160867Y493417D01*
X1161367Y493833D01*
X1161867Y494583D01*
G01X1163300Y491500D02*
Y494833D01*
G01Y493917D02*
X1163550Y494333D01*
X1163967Y494667D01*
X1164550Y494833D01*
X1165133Y494667D01*
X1165550Y494333D01*
X1165800Y493917D01*
Y491500D01*
G01Y493917D02*
X1166050Y494333D01*
X1166467Y494667D01*
X1167050Y494833D01*
X1167633Y494667D01*
X1168050Y494333D01*
X1168300Y493833D01*
Y491500D01*
G01X1168900D02*
Y494833D01*
G01Y493917D02*
X1169150Y494333D01*
X1169567Y494667D01*
X1170150Y494833D01*
X1170733Y494667D01*
X1171150Y494333D01*
X1171400Y493917D01*
Y491500D01*
G01Y493917D02*
X1171650Y494333D01*
X1172067Y494667D01*
X1172650Y494833D01*
X1173233Y494667D01*
X1173650Y494333D01*
X1173900Y493833D01*
Y491500D01*
G01X1177000Y491333D02*
X1176833Y491417D01*
Y491583D01*
X1177000Y491667D01*
X1177167Y491583D01*
Y491417D01*
X1177000Y491333D01*
G01Y493583D02*
X1176833Y493667D01*
Y493833D01*
X1177000Y493917D01*
X1177167Y493833D01*
Y493667D01*
X1177000Y493583D01*
G01X1045500Y504833D02*
X1047000Y501500D01*
X1048500Y504833D01*
G01X1052600D02*
Y501500D01*
G01Y506167D02*
X1052433Y506250D01*
Y506417D01*
X1052600Y506500D01*
X1052767Y506417D01*
Y506250D01*
X1052600Y506167D01*
G01X1059700Y501500D02*
Y504833D01*
G01Y504250D02*
X1059367Y504583D01*
X1058867Y504750D01*
X1058283Y504833D01*
X1057700Y504667D01*
X1057200Y504333D01*
X1056867Y503833D01*
X1056700Y503167D01*
X1056867Y502500D01*
X1057200Y502000D01*
X1057700Y501667D01*
X1058283Y501500D01*
X1058867Y501583D01*
X1059367Y501833D01*
X1059700Y502167D01*
G01X1068150Y502083D02*
X1068567Y501750D01*
X1069150Y501500D01*
X1069650D01*
X1070150Y501667D01*
X1070483Y501917D01*
X1070650Y502250D01*
X1070567Y502750D01*
X1070233Y503000D01*
X1068733Y503500D01*
X1068400Y504083D01*
X1068567Y504500D01*
X1068900Y504750D01*
X1069400Y504833D01*
X1069900Y504750D01*
X1070400Y504500D01*
G01X1073583Y501500D02*
Y506500D01*
G01Y504083D02*
X1074000Y504500D01*
X1074417Y504750D01*
X1075083Y504833D01*
X1075583Y504750D01*
X1076167Y504417D01*
X1076417Y503917D01*
Y501500D01*
G01X1082100D02*
Y504833D01*
G01Y504250D02*
X1081767Y504583D01*
X1081267Y504750D01*
X1080683Y504833D01*
X1080100Y504667D01*
X1079600Y504333D01*
X1079267Y503833D01*
X1079100Y503167D01*
X1079267Y502500D01*
X1079600Y502000D01*
X1080100Y501667D01*
X1080683Y501500D01*
X1081267Y501583D01*
X1081767Y501833D01*
X1082100Y502167D01*
G01X1086200Y501500D02*
Y506500D01*
G01X1091800Y501500D02*
Y506500D01*
G01X1101500Y501500D02*
Y506500D01*
G01Y504000D02*
X1101917Y504500D01*
X1102417Y504750D01*
X1102917Y504833D01*
X1103667Y504667D01*
X1104167Y504333D01*
X1104500Y503750D01*
Y503083D01*
X1104333Y502417D01*
X1104000Y501917D01*
X1103417Y501583D01*
X1102917Y501500D01*
X1102417Y501583D01*
X1101917Y501833D01*
X1101500Y502250D01*
G01X1107350Y503750D02*
X1110017D01*
X1109767Y504333D01*
X1109350Y504667D01*
X1108767Y504833D01*
X1108183Y504750D01*
X1107683Y504500D01*
X1107350Y503917D01*
X1107183Y503417D01*
Y502917D01*
X1107350Y502417D01*
X1107767Y501917D01*
X1108267Y501583D01*
X1108850Y501500D01*
X1109433Y501667D01*
X1110017Y502167D01*
G01X1118300Y499833D02*
Y504833D01*
G01Y504083D02*
X1118717Y504500D01*
X1119133Y504750D01*
X1119800Y504833D01*
X1120383Y504750D01*
X1120967Y504333D01*
X1121217Y503750D01*
X1121300Y503167D01*
X1121217Y502583D01*
X1120967Y502000D01*
X1120467Y501667D01*
X1119800Y501500D01*
X1119217Y501583D01*
X1118633Y501833D01*
X1118300Y502167D01*
G01X1125400Y501500D02*
Y506500D01*
G01X1129583Y504833D02*
Y502500D01*
X1129917Y501917D01*
X1130417Y501583D01*
X1131000Y501500D01*
X1131583Y501583D01*
X1132083Y501917D01*
X1132417Y502500D01*
G01Y501500D02*
Y504833D01*
G01X1135433Y500250D02*
X1136017Y499917D01*
X1136683Y499833D01*
X1137267Y499917D01*
X1137767Y500333D01*
X1138100Y500917D01*
Y504833D01*
G01Y504167D02*
X1137767Y504500D01*
X1137267Y504750D01*
X1136683Y504833D01*
X1136017Y504667D01*
X1135600Y504333D01*
X1135267Y503750D01*
X1135100Y503167D01*
X1135183Y502667D01*
X1135517Y502083D01*
X1136017Y501667D01*
X1136683Y501500D01*
X1137183Y501583D01*
X1137767Y501917D01*
X1138100Y502250D01*
G01X1141033Y500250D02*
X1141617Y499917D01*
X1142283Y499833D01*
X1142867Y499917D01*
X1143367Y500333D01*
X1143700Y500917D01*
Y504833D01*
G01Y504167D02*
X1143367Y504500D01*
X1142867Y504750D01*
X1142283Y504833D01*
X1141617Y504667D01*
X1141200Y504333D01*
X1140867Y503750D01*
X1140700Y503167D01*
X1140783Y502667D01*
X1141117Y502083D01*
X1141617Y501667D01*
X1142283Y501500D01*
X1142783Y501583D01*
X1143367Y501917D01*
X1143700Y502250D01*
G01X1146550Y503750D02*
X1149217D01*
X1148967Y504333D01*
X1148550Y504667D01*
X1147967Y504833D01*
X1147383Y504750D01*
X1146883Y504500D01*
X1146550Y503917D01*
X1146383Y503417D01*
Y502917D01*
X1146550Y502417D01*
X1146967Y501917D01*
X1147467Y501583D01*
X1148050Y501500D01*
X1148633Y501667D01*
X1149217Y502167D01*
G01X1154900Y506500D02*
Y501500D01*
G01Y502250D02*
X1154567Y501833D01*
X1154067Y501583D01*
X1153483Y501500D01*
X1152817Y501667D01*
X1152317Y502083D01*
X1151983Y502583D01*
X1151900Y503167D01*
X1151983Y503750D01*
X1152317Y504250D01*
X1152817Y504667D01*
X1153483Y504833D01*
X1154067Y504750D01*
X1154483Y504583D01*
X1154900Y504250D01*
G01X1162517Y504833D02*
X1163517Y501500D01*
X1164600Y504833D01*
X1165683Y501500D01*
X1166683Y504833D01*
G01X1170200D02*
Y501500D01*
G01Y506167D02*
X1170033Y506250D01*
Y506417D01*
X1170200Y506500D01*
X1170367Y506417D01*
Y506250D01*
X1170200Y506167D01*
G01X1175800Y506500D02*
Y501500D01*
G01X1174633Y504833D02*
X1176967D01*
G01X1179983Y501500D02*
Y506500D01*
G01Y504083D02*
X1180400Y504500D01*
X1180817Y504750D01*
X1181483Y504833D01*
X1181983Y504750D01*
X1182567Y504417D01*
X1182817Y503917D01*
Y501500D01*
G01X1194267D02*
X1190933Y503167D01*
X1194267Y504833D01*
G01X1201967Y502250D02*
X1202467Y501833D01*
X1203050Y501583D01*
X1203800Y501500D01*
X1204550Y501667D01*
X1205133Y502000D01*
X1205550Y502583D01*
X1205633Y503250D01*
X1205467Y503917D01*
X1205050Y504333D01*
X1204467Y504667D01*
X1203883Y504750D01*
X1203300Y504667D01*
X1202550Y504333D01*
X1202800Y506500D01*
X1205050D01*
G01X1209400D02*
X1208733Y506333D01*
X1208233Y505917D01*
X1207900Y505417D01*
X1207650Y504750D01*
X1207567Y504000D01*
X1207650Y503250D01*
X1207900Y502583D01*
X1208233Y502083D01*
X1208733Y501667D01*
X1209400Y501500D01*
X1210067Y501667D01*
X1210567Y502083D01*
X1210900Y502583D01*
X1211150Y503250D01*
X1211233Y504000D01*
X1211150Y504750D01*
X1210900Y505417D01*
X1210567Y505917D01*
X1210067Y506333D01*
X1209400Y506500D01*
G01X1219100Y501333D02*
X1222100Y506500D01*
G01X1219100D02*
X1218600Y506333D01*
X1218350Y506083D01*
X1218183Y505583D01*
X1218350Y505083D01*
X1218600Y504833D01*
X1219100Y504667D01*
X1219600Y504833D01*
X1219850Y505083D01*
X1220017Y505583D01*
X1219850Y506083D01*
X1219600Y506333D01*
X1219100Y506500D01*
G01X1222100Y503167D02*
X1221600Y503000D01*
X1221350Y502750D01*
X1221183Y502250D01*
X1221350Y501750D01*
X1221600Y501500D01*
X1222100Y501333D01*
X1222600Y501500D01*
X1222850Y501750D01*
X1223017Y502250D01*
X1222850Y502750D01*
X1222600Y503000D01*
X1222100Y503167D01*
G01X1230550Y502083D02*
X1230967Y501750D01*
X1231550Y501500D01*
X1232050D01*
X1232550Y501667D01*
X1232883Y501917D01*
X1233050Y502250D01*
X1232967Y502750D01*
X1232633Y503000D01*
X1231133Y503500D01*
X1230800Y504083D01*
X1230967Y504500D01*
X1231300Y504750D01*
X1231800Y504833D01*
X1232300Y504750D01*
X1232800Y504500D01*
G01X1237400Y501500D02*
X1236900Y501583D01*
X1236400Y501917D01*
X1236067Y502500D01*
X1235900Y503167D01*
X1236067Y503833D01*
X1236400Y504417D01*
X1236900Y504750D01*
X1237400Y504833D01*
X1237900Y504750D01*
X1238400Y504417D01*
X1238733Y503833D01*
X1238817Y503167D01*
X1238733Y502500D01*
X1238400Y501917D01*
X1237900Y501583D01*
X1237400Y501500D01*
G01X1243000D02*
Y506500D01*
G01X1250100D02*
Y501500D01*
G01Y502250D02*
X1249767Y501833D01*
X1249267Y501583D01*
X1248683Y501500D01*
X1248017Y501667D01*
X1247517Y502083D01*
X1247183Y502583D01*
X1247100Y503167D01*
X1247183Y503750D01*
X1247517Y504250D01*
X1248017Y504667D01*
X1248683Y504833D01*
X1249267Y504750D01*
X1249683Y504583D01*
X1250100Y504250D01*
G01X1252950Y503750D02*
X1255617D01*
X1255367Y504333D01*
X1254950Y504667D01*
X1254367Y504833D01*
X1253783Y504750D01*
X1253283Y504500D01*
X1252950Y503917D01*
X1252783Y503417D01*
Y502917D01*
X1252950Y502417D01*
X1253367Y501917D01*
X1253867Y501583D01*
X1254450Y501500D01*
X1255033Y501667D01*
X1255617Y502167D01*
G01X1258633Y501500D02*
Y504833D01*
G01Y504167D02*
X1259050Y504500D01*
X1259467Y504750D01*
X1260050Y504833D01*
X1260467Y504750D01*
X1260967Y504500D01*
G01X1268500Y501500D02*
Y504833D01*
G01Y503917D02*
X1268750Y504333D01*
X1269167Y504667D01*
X1269750Y504833D01*
X1270333Y504667D01*
X1270750Y504333D01*
X1271000Y503917D01*
Y501500D01*
G01Y503917D02*
X1271250Y504333D01*
X1271667Y504667D01*
X1272250Y504833D01*
X1272833Y504667D01*
X1273250Y504333D01*
X1273500Y503833D01*
Y501500D01*
G01X1278100D02*
Y504833D01*
G01Y504250D02*
X1277767Y504583D01*
X1277267Y504750D01*
X1276683Y504833D01*
X1276100Y504667D01*
X1275600Y504333D01*
X1275267Y503833D01*
X1275100Y503167D01*
X1275267Y502500D01*
X1275600Y502000D01*
X1276100Y501667D01*
X1276683Y501500D01*
X1277267Y501583D01*
X1277767Y501833D01*
X1278100Y502167D01*
G01X1280950Y502083D02*
X1281367Y501750D01*
X1281950Y501500D01*
X1282450D01*
X1282950Y501667D01*
X1283283Y501917D01*
X1283450Y502250D01*
X1283367Y502750D01*
X1283033Y503000D01*
X1281533Y503500D01*
X1281200Y504083D01*
X1281367Y504500D01*
X1281700Y504750D01*
X1282200Y504833D01*
X1282700Y504750D01*
X1283200Y504500D01*
G01X1286383Y501500D02*
Y506500D01*
G01X1289050Y504833D02*
X1286383Y502917D01*
G01X1287467Y503667D02*
X1289217Y501500D01*
G01X1293233Y500583D02*
X1293567Y501667D01*
G01X1038500Y510500D02*
Y513833D01*
G01Y513250D02*
X1038167Y513583D01*
X1037667Y513750D01*
X1037083Y513833D01*
X1036500Y513667D01*
X1036000Y513333D01*
X1035667Y512833D01*
X1035500Y512167D01*
X1035667Y511500D01*
X1036000Y511000D01*
X1036500Y510667D01*
X1037083Y510500D01*
X1037667Y510583D01*
X1038167Y510833D01*
X1038500Y511167D01*
G01X1042600Y510333D02*
X1042433Y510417D01*
Y510583D01*
X1042600Y510667D01*
X1042767Y510583D01*
Y510417D01*
X1042600Y510333D01*
G01X1048867Y513167D02*
X1049200Y513417D01*
X1049450Y513833D01*
X1049617Y514417D01*
X1049450Y514917D01*
X1049117Y515250D01*
X1048533Y515500D01*
X1046283D01*
Y510500D01*
X1049033D01*
X1049617Y510833D01*
X1049950Y511333D01*
X1050117Y511917D01*
X1049950Y512500D01*
X1049450Y513000D01*
X1048867Y513167D01*
X1046283D01*
G01X1053800Y510500D02*
X1053300Y510583D01*
X1052800Y510917D01*
X1052467Y511500D01*
X1052300Y512167D01*
X1052467Y512833D01*
X1052800Y513417D01*
X1053300Y513750D01*
X1053800Y513833D01*
X1054300Y513750D01*
X1054800Y513417D01*
X1055133Y512833D01*
X1055217Y512167D01*
X1055133Y511500D01*
X1054800Y510917D01*
X1054300Y510583D01*
X1053800Y510500D01*
G01X1060900D02*
Y513833D01*
G01Y513250D02*
X1060567Y513583D01*
X1060067Y513750D01*
X1059483Y513833D01*
X1058900Y513667D01*
X1058400Y513333D01*
X1058067Y512833D01*
X1057900Y512167D01*
X1058067Y511500D01*
X1058400Y511000D01*
X1058900Y510667D01*
X1059483Y510500D01*
X1060067Y510583D01*
X1060567Y510833D01*
X1060900Y511167D01*
G01X1063833Y510500D02*
Y513833D01*
G01Y513167D02*
X1064250Y513500D01*
X1064667Y513750D01*
X1065250Y513833D01*
X1065667Y513750D01*
X1066167Y513500D01*
G01X1072100Y515500D02*
Y510500D01*
G01Y511250D02*
X1071767Y510833D01*
X1071267Y510583D01*
X1070683Y510500D01*
X1070017Y510667D01*
X1069517Y511083D01*
X1069183Y511583D01*
X1069100Y512167D01*
X1069183Y512750D01*
X1069517Y513250D01*
X1070017Y513667D01*
X1070683Y513833D01*
X1071267Y513750D01*
X1071683Y513583D01*
X1072100Y513250D01*
G01X1081800Y515500D02*
Y510500D01*
G01X1080633Y513833D02*
X1082967D01*
G01X1085983Y510500D02*
Y515500D01*
G01Y513083D02*
X1086400Y513500D01*
X1086817Y513750D01*
X1087483Y513833D01*
X1087983Y513750D01*
X1088567Y513417D01*
X1088817Y512917D01*
Y510500D01*
G01X1093000Y513833D02*
Y510500D01*
G01Y515167D02*
X1092833Y515250D01*
Y515417D01*
X1093000Y515500D01*
X1093167Y515417D01*
Y515250D01*
X1093000Y515167D01*
G01X1099933Y513417D02*
X1099350Y513750D01*
X1098850Y513833D01*
X1098183Y513667D01*
X1097683Y513333D01*
X1097350Y512750D01*
X1097267Y512167D01*
X1097350Y511583D01*
X1097683Y511083D01*
X1098183Y510667D01*
X1098850Y510500D01*
X1099433Y510667D01*
X1099933Y511000D01*
G01X1102783Y510500D02*
Y515500D01*
G01X1105450Y513833D02*
X1102783Y511917D01*
G01X1103867Y512667D02*
X1105617Y510500D01*
G01X1108383D02*
Y513833D01*
G01Y513000D02*
X1108717Y513417D01*
X1109217Y513750D01*
X1109883Y513833D01*
X1110467Y513750D01*
X1110967Y513417D01*
X1111217Y512833D01*
Y510500D01*
G01X1114150Y512750D02*
X1116817D01*
X1116567Y513333D01*
X1116150Y513667D01*
X1115567Y513833D01*
X1114983Y513750D01*
X1114483Y513500D01*
X1114150Y512917D01*
X1113983Y512417D01*
Y511917D01*
X1114150Y511417D01*
X1114567Y510917D01*
X1115067Y510583D01*
X1115650Y510500D01*
X1116233Y510667D01*
X1116817Y511167D01*
G01X1119750Y511083D02*
X1120167Y510750D01*
X1120750Y510500D01*
X1121250D01*
X1121750Y510667D01*
X1122083Y510917D01*
X1122250Y511250D01*
X1122167Y511750D01*
X1121833Y512000D01*
X1120333Y512500D01*
X1120000Y513083D01*
X1120167Y513500D01*
X1120500Y513750D01*
X1121000Y513833D01*
X1121500Y513750D01*
X1122000Y513500D01*
G01X1125350Y511083D02*
X1125767Y510750D01*
X1126350Y510500D01*
X1126850D01*
X1127350Y510667D01*
X1127683Y510917D01*
X1127850Y511250D01*
X1127767Y511750D01*
X1127433Y512000D01*
X1125933Y512500D01*
X1125600Y513083D01*
X1125767Y513500D01*
X1126100Y513750D01*
X1126600Y513833D01*
X1127100Y513750D01*
X1127600Y513500D01*
G01X1130533Y510500D02*
X1133867Y512167D01*
X1130533Y513833D01*
G01X1136717Y511417D02*
X1138883D01*
G01Y512917D02*
X1136717D01*
G01X1149000Y515500D02*
X1148333Y515333D01*
X1147833Y514917D01*
X1147500Y514417D01*
X1147250Y513750D01*
X1147167Y513000D01*
X1147250Y512250D01*
X1147500Y511583D01*
X1147833Y511083D01*
X1148333Y510667D01*
X1149000Y510500D01*
X1149667Y510667D01*
X1150167Y511083D01*
X1150500Y511583D01*
X1150750Y512250D01*
X1150833Y513000D01*
X1150750Y513750D01*
X1150500Y514417D01*
X1150167Y514917D01*
X1149667Y515333D01*
X1149000Y515500D01*
G01X1154600Y510333D02*
X1154433Y510417D01*
Y510583D01*
X1154600Y510667D01*
X1154767Y510583D01*
Y510417D01*
X1154600Y510333D01*
G01X1158783Y511083D02*
X1159367Y510667D01*
X1160033Y510500D01*
X1160700Y510667D01*
X1161283Y511167D01*
X1161700Y511917D01*
X1161867Y512667D01*
Y513583D01*
X1161700Y514333D01*
X1161283Y515000D01*
X1160783Y515333D01*
X1160200Y515500D01*
X1159533Y515333D01*
X1159033Y515000D01*
X1158700Y514500D01*
X1158533Y513833D01*
X1158700Y513250D01*
X1159117Y512667D01*
X1159617Y512333D01*
X1160200Y512250D01*
X1160867Y512417D01*
X1161367Y512833D01*
X1161867Y513583D01*
G01X1163300Y510500D02*
Y513833D01*
G01Y512917D02*
X1163550Y513333D01*
X1163967Y513667D01*
X1164550Y513833D01*
X1165133Y513667D01*
X1165550Y513333D01*
X1165800Y512917D01*
Y510500D01*
G01Y512917D02*
X1166050Y513333D01*
X1166467Y513667D01*
X1167050Y513833D01*
X1167633Y513667D01*
X1168050Y513333D01*
X1168300Y512833D01*
Y510500D01*
G01X1171400Y510333D02*
X1171233Y510417D01*
Y510583D01*
X1171400Y510667D01*
X1171567Y510583D01*
Y510417D01*
X1171400Y510333D01*
G01Y512583D02*
X1171233Y512667D01*
Y512833D01*
X1171400Y512917D01*
X1171567Y512833D01*
Y512667D01*
X1171400Y512583D01*
G01X1034250Y520500D02*
Y525500D01*
G01X1037750D02*
Y520500D01*
G01Y523000D02*
X1034250D01*
G01X1043100Y520500D02*
Y523833D01*
G01Y523250D02*
X1042767Y523583D01*
X1042267Y523750D01*
X1041683Y523833D01*
X1041100Y523667D01*
X1040600Y523333D01*
X1040267Y522833D01*
X1040100Y522167D01*
X1040267Y521500D01*
X1040600Y521000D01*
X1041100Y520667D01*
X1041683Y520500D01*
X1042267Y520583D01*
X1042767Y520833D01*
X1043100Y521167D01*
G01X1047200Y520500D02*
Y525500D01*
G01X1052300Y520500D02*
Y524750D01*
X1052467Y525167D01*
X1052800Y525417D01*
X1053300Y525500D01*
X1053800Y525333D01*
X1054050Y524917D01*
G01X1053050Y523500D02*
X1051383D01*
G01X1057317Y522167D02*
X1059483D01*
G01X1062500Y518833D02*
Y523833D01*
G01Y523083D02*
X1062917Y523500D01*
X1063333Y523750D01*
X1064000Y523833D01*
X1064583Y523750D01*
X1065167Y523333D01*
X1065417Y522750D01*
X1065500Y522167D01*
X1065417Y521583D01*
X1065167Y521000D01*
X1064667Y520667D01*
X1064000Y520500D01*
X1063417Y520583D01*
X1062833Y520833D01*
X1062500Y521167D01*
G01X1069600Y520500D02*
Y525500D01*
G01X1073783Y523833D02*
Y521500D01*
X1074117Y520917D01*
X1074617Y520583D01*
X1075200Y520500D01*
X1075783Y520583D01*
X1076283Y520917D01*
X1076617Y521500D01*
G01Y520500D02*
Y523833D01*
G01X1079633Y519250D02*
X1080217Y518917D01*
X1080883Y518833D01*
X1081467Y518917D01*
X1081967Y519333D01*
X1082300Y519917D01*
Y523833D01*
G01Y523167D02*
X1081967Y523500D01*
X1081467Y523750D01*
X1080883Y523833D01*
X1080217Y523667D01*
X1079800Y523333D01*
X1079467Y522750D01*
X1079300Y522167D01*
X1079383Y521667D01*
X1079717Y521083D01*
X1080217Y520667D01*
X1080883Y520500D01*
X1081383Y520583D01*
X1081967Y520917D01*
X1082300Y521250D01*
G01X1085233Y519250D02*
X1085817Y518917D01*
X1086483Y518833D01*
X1087067Y518917D01*
X1087567Y519333D01*
X1087900Y519917D01*
Y523833D01*
G01Y523167D02*
X1087567Y523500D01*
X1087067Y523750D01*
X1086483Y523833D01*
X1085817Y523667D01*
X1085400Y523333D01*
X1085067Y522750D01*
X1084900Y522167D01*
X1084983Y521667D01*
X1085317Y521083D01*
X1085817Y520667D01*
X1086483Y520500D01*
X1086983Y520583D01*
X1087567Y520917D01*
X1087900Y521250D01*
G01X1092000Y523833D02*
Y520500D01*
G01Y525167D02*
X1091833Y525250D01*
Y525417D01*
X1092000Y525500D01*
X1092167Y525417D01*
Y525250D01*
X1092000Y525167D01*
G01X1096183Y520500D02*
Y523833D01*
G01Y523000D02*
X1096517Y523417D01*
X1097017Y523750D01*
X1097683Y523833D01*
X1098267Y523750D01*
X1098767Y523417D01*
X1099017Y522833D01*
Y520500D01*
G01X1102033Y519250D02*
X1102617Y518917D01*
X1103283Y518833D01*
X1103867Y518917D01*
X1104367Y519333D01*
X1104700Y519917D01*
Y523833D01*
G01Y523167D02*
X1104367Y523500D01*
X1103867Y523750D01*
X1103283Y523833D01*
X1102617Y523667D01*
X1102200Y523333D01*
X1101867Y522750D01*
X1101700Y522167D01*
X1101783Y521667D01*
X1102117Y521083D01*
X1102617Y520667D01*
X1103283Y520500D01*
X1103783Y520583D01*
X1104367Y520917D01*
X1104700Y521250D01*
G01X1114400Y520333D02*
X1114233Y520417D01*
Y520583D01*
X1114400Y520667D01*
X1114567Y520583D01*
Y520417D01*
X1114400Y520333D01*
G01Y522583D02*
X1114233Y522667D01*
Y522833D01*
X1114400Y522917D01*
X1114567Y522833D01*
Y522667D01*
X1114400Y522583D01*
G01X1125600Y525500D02*
Y520500D01*
G01X1124433Y523833D02*
X1126767D01*
G01X1129783Y520500D02*
Y525500D01*
G01Y523083D02*
X1130200Y523500D01*
X1130617Y523750D01*
X1131283Y523833D01*
X1131783Y523750D01*
X1132367Y523417D01*
X1132617Y522917D01*
Y520500D01*
G01X1135550Y522750D02*
X1138217D01*
X1137967Y523333D01*
X1137550Y523667D01*
X1136967Y523833D01*
X1136383Y523750D01*
X1135883Y523500D01*
X1135550Y522917D01*
X1135383Y522417D01*
Y521917D01*
X1135550Y521417D01*
X1135967Y520917D01*
X1136467Y520583D01*
X1137050Y520500D01*
X1137633Y520667D01*
X1138217Y521167D01*
G01X1146500Y518833D02*
Y523833D01*
G01Y523083D02*
X1146917Y523500D01*
X1147333Y523750D01*
X1148000Y523833D01*
X1148583Y523750D01*
X1149167Y523333D01*
X1149417Y522750D01*
X1149500Y522167D01*
X1149417Y521583D01*
X1149167Y521000D01*
X1148667Y520667D01*
X1148000Y520500D01*
X1147417Y520583D01*
X1146833Y520833D01*
X1146500Y521167D01*
G01X1153600Y520500D02*
Y525500D01*
G01X1157783Y523833D02*
Y521500D01*
X1158117Y520917D01*
X1158617Y520583D01*
X1159200Y520500D01*
X1159783Y520583D01*
X1160283Y520917D01*
X1160617Y521500D01*
G01Y520500D02*
Y523833D01*
G01X1163633Y519250D02*
X1164217Y518917D01*
X1164883Y518833D01*
X1165467Y518917D01*
X1165967Y519333D01*
X1166300Y519917D01*
Y523833D01*
G01Y523167D02*
X1165967Y523500D01*
X1165467Y523750D01*
X1164883Y523833D01*
X1164217Y523667D01*
X1163800Y523333D01*
X1163467Y522750D01*
X1163300Y522167D01*
X1163383Y521667D01*
X1163717Y521083D01*
X1164217Y520667D01*
X1164883Y520500D01*
X1165383Y520583D01*
X1165967Y520917D01*
X1166300Y521250D01*
G01X1169233Y519250D02*
X1169817Y518917D01*
X1170483Y518833D01*
X1171067Y518917D01*
X1171567Y519333D01*
X1171900Y519917D01*
Y523833D01*
G01Y523167D02*
X1171567Y523500D01*
X1171067Y523750D01*
X1170483Y523833D01*
X1169817Y523667D01*
X1169400Y523333D01*
X1169067Y522750D01*
X1168900Y522167D01*
X1168983Y521667D01*
X1169317Y521083D01*
X1169817Y520667D01*
X1170483Y520500D01*
X1170983Y520583D01*
X1171567Y520917D01*
X1171900Y521250D01*
G01X1176000Y523833D02*
Y520500D01*
G01Y525167D02*
X1175833Y525250D01*
Y525417D01*
X1176000Y525500D01*
X1176167Y525417D01*
Y525250D01*
X1176000Y525167D01*
G01X1180183Y520500D02*
Y523833D01*
G01Y523000D02*
X1180517Y523417D01*
X1181017Y523750D01*
X1181683Y523833D01*
X1182267Y523750D01*
X1182767Y523417D01*
X1183017Y522833D01*
Y520500D01*
G01X1186033Y519250D02*
X1186617Y518917D01*
X1187283Y518833D01*
X1187867Y518917D01*
X1188367Y519333D01*
X1188700Y519917D01*
Y523833D01*
G01Y523167D02*
X1188367Y523500D01*
X1187867Y523750D01*
X1187283Y523833D01*
X1186617Y523667D01*
X1186200Y523333D01*
X1185867Y522750D01*
X1185700Y522167D01*
X1185783Y521667D01*
X1186117Y521083D01*
X1186617Y520667D01*
X1187283Y520500D01*
X1187783Y520583D01*
X1188367Y520917D01*
X1188700Y521250D01*
G01X1197233Y520500D02*
Y523833D01*
G01Y523167D02*
X1197650Y523500D01*
X1198067Y523750D01*
X1198650Y523833D01*
X1199067Y523750D01*
X1199567Y523500D01*
G01X1205500Y520500D02*
Y523833D01*
G01Y523250D02*
X1205167Y523583D01*
X1204667Y523750D01*
X1204083Y523833D01*
X1203500Y523667D01*
X1203000Y523333D01*
X1202667Y522833D01*
X1202500Y522167D01*
X1202667Y521500D01*
X1203000Y521000D01*
X1203500Y520667D01*
X1204083Y520500D01*
X1204667Y520583D01*
X1205167Y520833D01*
X1205500Y521167D01*
G01X1209600Y525500D02*
Y520500D01*
G01X1208433Y523833D02*
X1210767D01*
G01X1215200D02*
Y520500D01*
G01Y525167D02*
X1215033Y525250D01*
Y525417D01*
X1215200Y525500D01*
X1215367Y525417D01*
Y525250D01*
X1215200Y525167D01*
G01X1220800Y520500D02*
X1220300Y520583D01*
X1219800Y520917D01*
X1219467Y521500D01*
X1219300Y522167D01*
X1219467Y522833D01*
X1219800Y523417D01*
X1220300Y523750D01*
X1220800Y523833D01*
X1221300Y523750D01*
X1221800Y523417D01*
X1222133Y522833D01*
X1222217Y522167D01*
X1222133Y521500D01*
X1221800Y520917D01*
X1221300Y520583D01*
X1220800Y520500D01*
G01X1230500Y518833D02*
Y523833D01*
G01Y523083D02*
X1230917Y523500D01*
X1231333Y523750D01*
X1232000Y523833D01*
X1232583Y523750D01*
X1233167Y523333D01*
X1233417Y522750D01*
X1233500Y522167D01*
X1233417Y521583D01*
X1233167Y521000D01*
X1232667Y520667D01*
X1232000Y520500D01*
X1231417Y520583D01*
X1230833Y520833D01*
X1230500Y521167D01*
G01X1236350Y522750D02*
X1239017D01*
X1238767Y523333D01*
X1238350Y523667D01*
X1237767Y523833D01*
X1237183Y523750D01*
X1236683Y523500D01*
X1236350Y522917D01*
X1236183Y522417D01*
Y521917D01*
X1236350Y521417D01*
X1236767Y520917D01*
X1237267Y520583D01*
X1237850Y520500D01*
X1238433Y520667D01*
X1239017Y521167D01*
G01X1242033Y520500D02*
Y523833D01*
G01Y523167D02*
X1242450Y523500D01*
X1242867Y523750D01*
X1243450Y523833D01*
X1243867Y523750D01*
X1244367Y523500D01*
G01X1253900Y520500D02*
Y524750D01*
X1254067Y525167D01*
X1254400Y525417D01*
X1254900Y525500D01*
X1255400Y525333D01*
X1255650Y524917D01*
G01X1254650Y523500D02*
X1252983D01*
G01X1260000Y520500D02*
X1259500Y520583D01*
X1259000Y520917D01*
X1258667Y521500D01*
X1258500Y522167D01*
X1258667Y522833D01*
X1259000Y523417D01*
X1259500Y523750D01*
X1260000Y523833D01*
X1260500Y523750D01*
X1261000Y523417D01*
X1261333Y522833D01*
X1261417Y522167D01*
X1261333Y521500D01*
X1261000Y520917D01*
X1260500Y520583D01*
X1260000Y520500D01*
G01X1265600D02*
Y525500D01*
G01X1271200Y520500D02*
Y525500D01*
G01X1276800Y520500D02*
X1276300Y520583D01*
X1275800Y520917D01*
X1275467Y521500D01*
X1275300Y522167D01*
X1275467Y522833D01*
X1275800Y523417D01*
X1276300Y523750D01*
X1276800Y523833D01*
X1277300Y523750D01*
X1277800Y523417D01*
X1278133Y522833D01*
X1278217Y522167D01*
X1278133Y521500D01*
X1277800Y520917D01*
X1277300Y520583D01*
X1276800Y520500D01*
G01X1280317Y523833D02*
X1281317Y520500D01*
X1282400Y523833D01*
X1283483Y520500D01*
X1284483Y523833D01*
G01X1288000D02*
Y520500D01*
G01Y525167D02*
X1287833Y525250D01*
Y525417D01*
X1288000Y525500D01*
X1288167Y525417D01*
Y525250D01*
X1288000Y525167D01*
G01X1292183Y520500D02*
Y523833D01*
G01Y523000D02*
X1292517Y523417D01*
X1293017Y523750D01*
X1293683Y523833D01*
X1294267Y523750D01*
X1294767Y523417D01*
X1295017Y522833D01*
Y520500D01*
G01X1298033Y519250D02*
X1298617Y518917D01*
X1299283Y518833D01*
X1299867Y518917D01*
X1300367Y519333D01*
X1300700Y519917D01*
Y523833D01*
G01Y523167D02*
X1300367Y523500D01*
X1299867Y523750D01*
X1299283Y523833D01*
X1298617Y523667D01*
X1298200Y523333D01*
X1297867Y522750D01*
X1297700Y522167D01*
X1297783Y521667D01*
X1298117Y521083D01*
X1298617Y520667D01*
X1299283Y520500D01*
X1299783Y520583D01*
X1300367Y520917D01*
X1300700Y521250D01*
G01X1304800Y520333D02*
X1304633Y520417D01*
Y520583D01*
X1304800Y520667D01*
X1304967Y520583D01*
Y520417D01*
X1304800Y520333D01*
G01Y522583D02*
X1304633Y522667D01*
Y522833D01*
X1304800Y522917D01*
X1304967Y522833D01*
Y522667D01*
X1304800Y522583D01*
G01X1033500Y529500D02*
Y534500D01*
G01Y532000D02*
X1033917Y532500D01*
X1034417Y532750D01*
X1034917Y532833D01*
X1035667Y532667D01*
X1036167Y532333D01*
X1036500Y531750D01*
Y531083D01*
X1036333Y530417D01*
X1036000Y529917D01*
X1035417Y529583D01*
X1034917Y529500D01*
X1034417Y529583D01*
X1033917Y529833D01*
X1033500Y530250D01*
G01X1039350Y531750D02*
X1042017D01*
X1041767Y532333D01*
X1041350Y532667D01*
X1040767Y532833D01*
X1040183Y532750D01*
X1039683Y532500D01*
X1039350Y531917D01*
X1039183Y531417D01*
Y530917D01*
X1039350Y530417D01*
X1039767Y529917D01*
X1040267Y529583D01*
X1040850Y529500D01*
X1041433Y529667D01*
X1042017Y530167D01*
G01X1051300Y529500D02*
Y533750D01*
X1051467Y534167D01*
X1051800Y534417D01*
X1052300Y534500D01*
X1052800Y534333D01*
X1053050Y533917D01*
G01X1052050Y532500D02*
X1050383D01*
G01X1056233Y529500D02*
Y532833D01*
G01Y532167D02*
X1056650Y532500D01*
X1057067Y532750D01*
X1057650Y532833D01*
X1058067Y532750D01*
X1058567Y532500D01*
G01X1061750Y531750D02*
X1064417D01*
X1064167Y532333D01*
X1063750Y532667D01*
X1063167Y532833D01*
X1062583Y532750D01*
X1062083Y532500D01*
X1061750Y531917D01*
X1061583Y531417D01*
Y530917D01*
X1061750Y530417D01*
X1062167Y529917D01*
X1062667Y529583D01*
X1063250Y529500D01*
X1063833Y529667D01*
X1064417Y530167D01*
G01X1067350Y531750D02*
X1070017D01*
X1069767Y532333D01*
X1069350Y532667D01*
X1068767Y532833D01*
X1068183Y532750D01*
X1067683Y532500D01*
X1067350Y531917D01*
X1067183Y531417D01*
Y530917D01*
X1067350Y530417D01*
X1067767Y529917D01*
X1068267Y529583D01*
X1068850Y529500D01*
X1069433Y529667D01*
X1070017Y530167D01*
G01X1079300Y529500D02*
Y533750D01*
X1079467Y534167D01*
X1079800Y534417D01*
X1080300Y534500D01*
X1080800Y534333D01*
X1081050Y533917D01*
G01X1080050Y532500D02*
X1078383D01*
G01X1084233Y529500D02*
Y532833D01*
G01Y532167D02*
X1084650Y532500D01*
X1085067Y532750D01*
X1085650Y532833D01*
X1086067Y532750D01*
X1086567Y532500D01*
G01X1091000Y529500D02*
X1090500Y529583D01*
X1090000Y529917D01*
X1089667Y530500D01*
X1089500Y531167D01*
X1089667Y531833D01*
X1090000Y532417D01*
X1090500Y532750D01*
X1091000Y532833D01*
X1091500Y532750D01*
X1092000Y532417D01*
X1092333Y531833D01*
X1092417Y531167D01*
X1092333Y530500D01*
X1092000Y529917D01*
X1091500Y529583D01*
X1091000Y529500D01*
G01X1094100D02*
Y532833D01*
G01Y531917D02*
X1094350Y532333D01*
X1094767Y532667D01*
X1095350Y532833D01*
X1095933Y532667D01*
X1096350Y532333D01*
X1096600Y531917D01*
Y529500D01*
G01Y531917D02*
X1096850Y532333D01*
X1097267Y532667D01*
X1097850Y532833D01*
X1098433Y532667D01*
X1098850Y532333D01*
X1099100Y531833D01*
Y529500D01*
G01X1106550Y530083D02*
X1106967Y529750D01*
X1107550Y529500D01*
X1108050D01*
X1108550Y529667D01*
X1108883Y529917D01*
X1109050Y530250D01*
X1108967Y530750D01*
X1108633Y531000D01*
X1107133Y531500D01*
X1106800Y532083D01*
X1106967Y532500D01*
X1107300Y532750D01*
X1107800Y532833D01*
X1108300Y532750D01*
X1108800Y532500D01*
G01X1113400Y529500D02*
X1112900Y529583D01*
X1112400Y529917D01*
X1112067Y530500D01*
X1111900Y531167D01*
X1112067Y531833D01*
X1112400Y532417D01*
X1112900Y532750D01*
X1113400Y532833D01*
X1113900Y532750D01*
X1114400Y532417D01*
X1114733Y531833D01*
X1114817Y531167D01*
X1114733Y530500D01*
X1114400Y529917D01*
X1113900Y529583D01*
X1113400Y529500D01*
G01X1119000D02*
Y534500D01*
G01X1126100D02*
Y529500D01*
G01Y530250D02*
X1125767Y529833D01*
X1125267Y529583D01*
X1124683Y529500D01*
X1124017Y529667D01*
X1123517Y530083D01*
X1123183Y530583D01*
X1123100Y531167D01*
X1123183Y531750D01*
X1123517Y532250D01*
X1124017Y532667D01*
X1124683Y532833D01*
X1125267Y532750D01*
X1125683Y532583D01*
X1126100Y532250D01*
G01X1128950Y531750D02*
X1131617D01*
X1131367Y532333D01*
X1130950Y532667D01*
X1130367Y532833D01*
X1129783Y532750D01*
X1129283Y532500D01*
X1128950Y531917D01*
X1128783Y531417D01*
Y530917D01*
X1128950Y530417D01*
X1129367Y529917D01*
X1129867Y529583D01*
X1130450Y529500D01*
X1131033Y529667D01*
X1131617Y530167D01*
G01X1134633Y529500D02*
Y532833D01*
G01Y532167D02*
X1135050Y532500D01*
X1135467Y532750D01*
X1136050Y532833D01*
X1136467Y532750D01*
X1136967Y532500D01*
G01X1144500Y529500D02*
Y532833D01*
G01Y531917D02*
X1144750Y532333D01*
X1145167Y532667D01*
X1145750Y532833D01*
X1146333Y532667D01*
X1146750Y532333D01*
X1147000Y531917D01*
Y529500D01*
G01Y531917D02*
X1147250Y532333D01*
X1147667Y532667D01*
X1148250Y532833D01*
X1148833Y532667D01*
X1149250Y532333D01*
X1149500Y531833D01*
Y529500D01*
G01X1154100D02*
Y532833D01*
G01Y532250D02*
X1153767Y532583D01*
X1153267Y532750D01*
X1152683Y532833D01*
X1152100Y532667D01*
X1151600Y532333D01*
X1151267Y531833D01*
X1151100Y531167D01*
X1151267Y530500D01*
X1151600Y530000D01*
X1152100Y529667D01*
X1152683Y529500D01*
X1153267Y529583D01*
X1153767Y529833D01*
X1154100Y530167D01*
G01X1156950Y530083D02*
X1157367Y529750D01*
X1157950Y529500D01*
X1158450D01*
X1158950Y529667D01*
X1159283Y529917D01*
X1159450Y530250D01*
X1159367Y530750D01*
X1159033Y531000D01*
X1157533Y531500D01*
X1157200Y532083D01*
X1157367Y532500D01*
X1157700Y532750D01*
X1158200Y532833D01*
X1158700Y532750D01*
X1159200Y532500D01*
G01X1162383Y529500D02*
Y534500D01*
G01X1165050Y532833D02*
X1162383Y530917D01*
G01X1163467Y531667D02*
X1165217Y529500D01*
G01X1169400Y529333D02*
X1169233Y529417D01*
Y529583D01*
X1169400Y529667D01*
X1169567Y529583D01*
Y529417D01*
X1169400Y529333D01*
G01X1020417Y542667D02*
X1020917Y543167D01*
X1021500Y543417D01*
X1022167Y543500D01*
X1023000Y543333D01*
X1023583Y542917D01*
X1023750Y542417D01*
X1023667Y541917D01*
X1023333Y541500D01*
X1021667Y540667D01*
X1020917Y540083D01*
X1020417Y539250D01*
X1020250Y538500D01*
X1023750D01*
G01X1027600Y538333D02*
X1027433Y538417D01*
Y538583D01*
X1027600Y538667D01*
X1027767Y538583D01*
Y538417D01*
X1027600Y538333D01*
G01X1033200Y543500D02*
Y538500D01*
G01X1031283Y543500D02*
X1035117D01*
G01X1037383Y538500D02*
Y543500D01*
G01Y541083D02*
X1037800Y541500D01*
X1038217Y541750D01*
X1038883Y541833D01*
X1039383Y541750D01*
X1039967Y541417D01*
X1040217Y540917D01*
Y538500D01*
G01X1043150Y540750D02*
X1045817D01*
X1045567Y541333D01*
X1045150Y541667D01*
X1044567Y541833D01*
X1043983Y541750D01*
X1043483Y541500D01*
X1043150Y540917D01*
X1042983Y540417D01*
Y539917D01*
X1043150Y539417D01*
X1043567Y538917D01*
X1044067Y538583D01*
X1044650Y538500D01*
X1045233Y538667D01*
X1045817Y539167D01*
G01X1054350Y539083D02*
X1054767Y538750D01*
X1055350Y538500D01*
X1055850D01*
X1056350Y538667D01*
X1056683Y538917D01*
X1056850Y539250D01*
X1056767Y539750D01*
X1056433Y540000D01*
X1054933Y540500D01*
X1054600Y541083D01*
X1054767Y541500D01*
X1055100Y541750D01*
X1055600Y541833D01*
X1056100Y541750D01*
X1056600Y541500D01*
G01X1061200Y541833D02*
Y538500D01*
G01Y543167D02*
X1061033Y543250D01*
Y543417D01*
X1061200Y543500D01*
X1061367Y543417D01*
Y543250D01*
X1061200Y543167D01*
G01X1068300Y543500D02*
Y538500D01*
G01Y539250D02*
X1067967Y538833D01*
X1067467Y538583D01*
X1066883Y538500D01*
X1066217Y538667D01*
X1065717Y539083D01*
X1065383Y539583D01*
X1065300Y540167D01*
X1065383Y540750D01*
X1065717Y541250D01*
X1066217Y541667D01*
X1066883Y541833D01*
X1067467Y541750D01*
X1067883Y541583D01*
X1068300Y541250D01*
G01X1071150Y540750D02*
X1073817D01*
X1073567Y541333D01*
X1073150Y541667D01*
X1072567Y541833D01*
X1071983Y541750D01*
X1071483Y541500D01*
X1071150Y540917D01*
X1070983Y540417D01*
Y539917D01*
X1071150Y539417D01*
X1071567Y538917D01*
X1072067Y538583D01*
X1072650Y538500D01*
X1073233Y538667D01*
X1073817Y539167D01*
G01X1081517Y541833D02*
X1082517Y538500D01*
X1083600Y541833D01*
X1084683Y538500D01*
X1085683Y541833D01*
G01X1089200D02*
Y538500D01*
G01Y543167D02*
X1089033Y543250D01*
Y543417D01*
X1089200Y543500D01*
X1089367Y543417D01*
Y543250D01*
X1089200Y543167D01*
G01X1094800Y543500D02*
Y538500D01*
G01X1093633Y541833D02*
X1095967D01*
G01X1098983Y538500D02*
Y543500D01*
G01Y541083D02*
X1099400Y541500D01*
X1099817Y541750D01*
X1100483Y541833D01*
X1100983Y541750D01*
X1101567Y541417D01*
X1101817Y540917D01*
Y538500D01*
G01X1110350Y539083D02*
X1110767Y538750D01*
X1111350Y538500D01*
X1111850D01*
X1112350Y538667D01*
X1112683Y538917D01*
X1112850Y539250D01*
X1112767Y539750D01*
X1112433Y540000D01*
X1110933Y540500D01*
X1110600Y541083D01*
X1110767Y541500D01*
X1111100Y541750D01*
X1111600Y541833D01*
X1112100Y541750D01*
X1112600Y541500D01*
G01X1117200Y538500D02*
X1116700Y538583D01*
X1116200Y538917D01*
X1115867Y539500D01*
X1115700Y540167D01*
X1115867Y540833D01*
X1116200Y541417D01*
X1116700Y541750D01*
X1117200Y541833D01*
X1117700Y541750D01*
X1118200Y541417D01*
X1118533Y540833D01*
X1118617Y540167D01*
X1118533Y539500D01*
X1118200Y538917D01*
X1117700Y538583D01*
X1117200Y538500D01*
G01X1122800D02*
Y543500D01*
G01X1129900D02*
Y538500D01*
G01Y539250D02*
X1129567Y538833D01*
X1129067Y538583D01*
X1128483Y538500D01*
X1127817Y538667D01*
X1127317Y539083D01*
X1126983Y539583D01*
X1126900Y540167D01*
X1126983Y540750D01*
X1127317Y541250D01*
X1127817Y541667D01*
X1128483Y541833D01*
X1129067Y541750D01*
X1129483Y541583D01*
X1129900Y541250D01*
G01X1132750Y540750D02*
X1135417D01*
X1135167Y541333D01*
X1134750Y541667D01*
X1134167Y541833D01*
X1133583Y541750D01*
X1133083Y541500D01*
X1132750Y540917D01*
X1132583Y540417D01*
Y539917D01*
X1132750Y539417D01*
X1133167Y538917D01*
X1133667Y538583D01*
X1134250Y538500D01*
X1134833Y538667D01*
X1135417Y539167D01*
G01X1138433Y538500D02*
Y541833D01*
G01Y541167D02*
X1138850Y541500D01*
X1139267Y541750D01*
X1139850Y541833D01*
X1140267Y541750D01*
X1140767Y541500D01*
G01X1148300Y538500D02*
Y541833D01*
G01Y540917D02*
X1148550Y541333D01*
X1148967Y541667D01*
X1149550Y541833D01*
X1150133Y541667D01*
X1150550Y541333D01*
X1150800Y540917D01*
Y538500D01*
G01Y540917D02*
X1151050Y541333D01*
X1151467Y541667D01*
X1152050Y541833D01*
X1152633Y541667D01*
X1153050Y541333D01*
X1153300Y540833D01*
Y538500D01*
G01X1157900D02*
Y541833D01*
G01Y541250D02*
X1157567Y541583D01*
X1157067Y541750D01*
X1156483Y541833D01*
X1155900Y541667D01*
X1155400Y541333D01*
X1155067Y540833D01*
X1154900Y540167D01*
X1155067Y539500D01*
X1155400Y539000D01*
X1155900Y538667D01*
X1156483Y538500D01*
X1157067Y538583D01*
X1157567Y538833D01*
X1157900Y539167D01*
G01X1160750Y539083D02*
X1161167Y538750D01*
X1161750Y538500D01*
X1162250D01*
X1162750Y538667D01*
X1163083Y538917D01*
X1163250Y539250D01*
X1163167Y539750D01*
X1162833Y540000D01*
X1161333Y540500D01*
X1161000Y541083D01*
X1161167Y541500D01*
X1161500Y541750D01*
X1162000Y541833D01*
X1162500Y541750D01*
X1163000Y541500D01*
G01X1166183Y538500D02*
Y543500D01*
G01X1168850Y541833D02*
X1166183Y539917D01*
G01X1167267Y540667D02*
X1169017Y538500D01*
G01X1177300Y536833D02*
Y541833D01*
G01Y541083D02*
X1177717Y541500D01*
X1178133Y541750D01*
X1178800Y541833D01*
X1179383Y541750D01*
X1179967Y541333D01*
X1180217Y540750D01*
X1180300Y540167D01*
X1180217Y539583D01*
X1179967Y539000D01*
X1179467Y538667D01*
X1178800Y538500D01*
X1178217Y538583D01*
X1177633Y538833D01*
X1177300Y539167D01*
G01X1185900Y538500D02*
Y541833D01*
G01Y541250D02*
X1185567Y541583D01*
X1185067Y541750D01*
X1184483Y541833D01*
X1183900Y541667D01*
X1183400Y541333D01*
X1183067Y540833D01*
X1182900Y540167D01*
X1183067Y539500D01*
X1183400Y539000D01*
X1183900Y538667D01*
X1184483Y538500D01*
X1185067Y538583D01*
X1185567Y538833D01*
X1185900Y539167D01*
G01X1191500Y543500D02*
Y538500D01*
G01Y539250D02*
X1191167Y538833D01*
X1190667Y538583D01*
X1190083Y538500D01*
X1189417Y538667D01*
X1188917Y539083D01*
X1188583Y539583D01*
X1188500Y540167D01*
X1188583Y540750D01*
X1188917Y541250D01*
X1189417Y541667D01*
X1190083Y541833D01*
X1190667Y541750D01*
X1191083Y541583D01*
X1191500Y541250D01*
G01X1195433Y537583D02*
X1195767Y538667D01*
G01X1206800Y543500D02*
Y538500D01*
G01X1205633Y541833D02*
X1207967D01*
G01X1210983Y538500D02*
Y543500D01*
G01Y541083D02*
X1211400Y541500D01*
X1211817Y541750D01*
X1212483Y541833D01*
X1212983Y541750D01*
X1213567Y541417D01*
X1213817Y540917D01*
Y538500D01*
G01X1216750Y540750D02*
X1219417D01*
X1219167Y541333D01*
X1218750Y541667D01*
X1218167Y541833D01*
X1217583Y541750D01*
X1217083Y541500D01*
X1216750Y540917D01*
X1216583Y540417D01*
Y539917D01*
X1216750Y539417D01*
X1217167Y538917D01*
X1217667Y538583D01*
X1218250Y538500D01*
X1218833Y538667D01*
X1219417Y539167D01*
G01X1230700Y538500D02*
Y541833D01*
G01Y541250D02*
X1230367Y541583D01*
X1229867Y541750D01*
X1229283Y541833D01*
X1228700Y541667D01*
X1228200Y541333D01*
X1227867Y540833D01*
X1227700Y540167D01*
X1227867Y539500D01*
X1228200Y539000D01*
X1228700Y538667D01*
X1229283Y538500D01*
X1229867Y538583D01*
X1230367Y538833D01*
X1230700Y539167D01*
G01X1233383Y538500D02*
Y541833D01*
G01Y541000D02*
X1233717Y541417D01*
X1234217Y541750D01*
X1234883Y541833D01*
X1235467Y541750D01*
X1235967Y541417D01*
X1236217Y540833D01*
Y538500D01*
G01X1238983D02*
Y541833D01*
G01Y541000D02*
X1239317Y541417D01*
X1239817Y541750D01*
X1240483Y541833D01*
X1241067Y541750D01*
X1241567Y541417D01*
X1241817Y540833D01*
Y538500D01*
G01X1244583Y541833D02*
Y539500D01*
X1244917Y538917D01*
X1245417Y538583D01*
X1246000Y538500D01*
X1246583Y538583D01*
X1247083Y538917D01*
X1247417Y539500D01*
G01Y538500D02*
Y541833D01*
G01X1253100Y538500D02*
Y541833D01*
G01Y541250D02*
X1252767Y541583D01*
X1252267Y541750D01*
X1251683Y541833D01*
X1251100Y541667D01*
X1250600Y541333D01*
X1250267Y540833D01*
X1250100Y540167D01*
X1250267Y539500D01*
X1250600Y539000D01*
X1251100Y538667D01*
X1251683Y538500D01*
X1252267Y538583D01*
X1252767Y538833D01*
X1253100Y539167D01*
G01X1257200Y538500D02*
Y543500D01*
G01X1267233Y538500D02*
Y541833D01*
G01Y541167D02*
X1267650Y541500D01*
X1268067Y541750D01*
X1268650Y541833D01*
X1269067Y541750D01*
X1269567Y541500D01*
G01X1274000Y541833D02*
Y538500D01*
G01Y543167D02*
X1273833Y543250D01*
Y543417D01*
X1274000Y543500D01*
X1274167Y543417D01*
Y543250D01*
X1274000Y543167D01*
G01X1278183Y538500D02*
Y541833D01*
G01Y541000D02*
X1278517Y541417D01*
X1279017Y541750D01*
X1279683Y541833D01*
X1280267Y541750D01*
X1280767Y541417D01*
X1281017Y540833D01*
Y538500D01*
G01X1284033Y537250D02*
X1284617Y536917D01*
X1285283Y536833D01*
X1285867Y536917D01*
X1286367Y537333D01*
X1286700Y537917D01*
Y541833D01*
G01Y541167D02*
X1286367Y541500D01*
X1285867Y541750D01*
X1285283Y541833D01*
X1284617Y541667D01*
X1284200Y541333D01*
X1283867Y540750D01*
X1283700Y540167D01*
X1283783Y539667D01*
X1284117Y539083D01*
X1284617Y538667D01*
X1285283Y538500D01*
X1285783Y538583D01*
X1286367Y538917D01*
X1286700Y539250D01*
G01X1295150Y539083D02*
X1295567Y538750D01*
X1296150Y538500D01*
X1296650D01*
X1297150Y538667D01*
X1297483Y538917D01*
X1297650Y539250D01*
X1297567Y539750D01*
X1297233Y540000D01*
X1295733Y540500D01*
X1295400Y541083D01*
X1295567Y541500D01*
X1295900Y541750D01*
X1296400Y541833D01*
X1296900Y541750D01*
X1297400Y541500D01*
G01X1300583Y538500D02*
Y543500D01*
G01Y541083D02*
X1301000Y541500D01*
X1301417Y541750D01*
X1302083Y541833D01*
X1302583Y541750D01*
X1303167Y541417D01*
X1303417Y540917D01*
Y538500D01*
G01X1307600D02*
X1307100Y538583D01*
X1306600Y538917D01*
X1306267Y539500D01*
X1306100Y540167D01*
X1306267Y540833D01*
X1306600Y541417D01*
X1307100Y541750D01*
X1307600Y541833D01*
X1308100Y541750D01*
X1308600Y541417D01*
X1308933Y540833D01*
X1309017Y540167D01*
X1308933Y539500D01*
X1308600Y538917D01*
X1308100Y538583D01*
X1307600Y538500D01*
G01X1311783Y541833D02*
Y539500D01*
X1312117Y538917D01*
X1312617Y538583D01*
X1313200Y538500D01*
X1313783Y538583D01*
X1314283Y538917D01*
X1314617Y539500D01*
G01Y538500D02*
Y541833D01*
G01X1318800Y538500D02*
Y543500D01*
G01X1325900D02*
Y538500D01*
G01Y539250D02*
X1325567Y538833D01*
X1325067Y538583D01*
X1324483Y538500D01*
X1323817Y538667D01*
X1323317Y539083D01*
X1322983Y539583D01*
X1322900Y540167D01*
X1322983Y540750D01*
X1323317Y541250D01*
X1323817Y541667D01*
X1324483Y541833D01*
X1325067Y541750D01*
X1325483Y541583D01*
X1325900Y541250D01*
G01X1032500Y552500D02*
Y557500D01*
G01Y555000D02*
X1032917Y555500D01*
X1033417Y555750D01*
X1033917Y555833D01*
X1034667Y555667D01*
X1035167Y555333D01*
X1035500Y554750D01*
Y554083D01*
X1035333Y553417D01*
X1035000Y552917D01*
X1034417Y552583D01*
X1033917Y552500D01*
X1033417Y552583D01*
X1032917Y552833D01*
X1032500Y553250D01*
G01X1038350Y554750D02*
X1041017D01*
X1040767Y555333D01*
X1040350Y555667D01*
X1039767Y555833D01*
X1039183Y555750D01*
X1038683Y555500D01*
X1038350Y554917D01*
X1038183Y554417D01*
Y553917D01*
X1038350Y553417D01*
X1038767Y552917D01*
X1039267Y552583D01*
X1039850Y552500D01*
X1040433Y552667D01*
X1041017Y553167D01*
G01X1050800Y557500D02*
Y552500D01*
G01X1049633Y555833D02*
X1051967D01*
G01X1055150Y554750D02*
X1057817D01*
X1057567Y555333D01*
X1057150Y555667D01*
X1056567Y555833D01*
X1055983Y555750D01*
X1055483Y555500D01*
X1055150Y554917D01*
X1054983Y554417D01*
Y553917D01*
X1055150Y553417D01*
X1055567Y552917D01*
X1056067Y552583D01*
X1056650Y552500D01*
X1057233Y552667D01*
X1057817Y553167D01*
G01X1060583Y552500D02*
Y555833D01*
G01Y555000D02*
X1060917Y555417D01*
X1061417Y555750D01*
X1062083Y555833D01*
X1062667Y555750D01*
X1063167Y555417D01*
X1063417Y554833D01*
Y552500D01*
G01X1067600Y557500D02*
Y552500D01*
G01X1066433Y555833D02*
X1068767D01*
G01X1071950Y554750D02*
X1074617D01*
X1074367Y555333D01*
X1073950Y555667D01*
X1073367Y555833D01*
X1072783Y555750D01*
X1072283Y555500D01*
X1071950Y554917D01*
X1071783Y554417D01*
Y553917D01*
X1071950Y553417D01*
X1072367Y552917D01*
X1072867Y552583D01*
X1073450Y552500D01*
X1074033Y552667D01*
X1074617Y553167D01*
G01X1080300Y557500D02*
Y552500D01*
G01Y553250D02*
X1079967Y552833D01*
X1079467Y552583D01*
X1078883Y552500D01*
X1078217Y552667D01*
X1077717Y553083D01*
X1077383Y553583D01*
X1077300Y554167D01*
X1077383Y554750D01*
X1077717Y555250D01*
X1078217Y555667D01*
X1078883Y555833D01*
X1079467Y555750D01*
X1079883Y555583D01*
X1080300Y555250D01*
G01X1087917Y555833D02*
X1088917Y552500D01*
X1090000Y555833D01*
X1091083Y552500D01*
X1092083Y555833D01*
G01X1095600D02*
Y552500D01*
G01Y557167D02*
X1095433Y557250D01*
Y557417D01*
X1095600Y557500D01*
X1095767Y557417D01*
Y557250D01*
X1095600Y557167D01*
G01X1101200Y557500D02*
Y552500D01*
G01X1100033Y555833D02*
X1102367D01*
G01X1105383Y552500D02*
Y557500D01*
G01Y555083D02*
X1105800Y555500D01*
X1106217Y555750D01*
X1106883Y555833D01*
X1107383Y555750D01*
X1107967Y555417D01*
X1108217Y554917D01*
Y552500D01*
G01X1116750Y553083D02*
X1117167Y552750D01*
X1117750Y552500D01*
X1118250D01*
X1118750Y552667D01*
X1119083Y552917D01*
X1119250Y553250D01*
X1119167Y553750D01*
X1118833Y554000D01*
X1117333Y554500D01*
X1117000Y555083D01*
X1117167Y555500D01*
X1117500Y555750D01*
X1118000Y555833D01*
X1118500Y555750D01*
X1119000Y555500D01*
G01X1123600Y552500D02*
X1123100Y552583D01*
X1122600Y552917D01*
X1122267Y553500D01*
X1122100Y554167D01*
X1122267Y554833D01*
X1122600Y555417D01*
X1123100Y555750D01*
X1123600Y555833D01*
X1124100Y555750D01*
X1124600Y555417D01*
X1124933Y554833D01*
X1125017Y554167D01*
X1124933Y553500D01*
X1124600Y552917D01*
X1124100Y552583D01*
X1123600Y552500D01*
G01X1129200D02*
Y557500D01*
G01X1136300D02*
Y552500D01*
G01Y553250D02*
X1135967Y552833D01*
X1135467Y552583D01*
X1134883Y552500D01*
X1134217Y552667D01*
X1133717Y553083D01*
X1133383Y553583D01*
X1133300Y554167D01*
X1133383Y554750D01*
X1133717Y555250D01*
X1134217Y555667D01*
X1134883Y555833D01*
X1135467Y555750D01*
X1135883Y555583D01*
X1136300Y555250D01*
G01X1139150Y554750D02*
X1141817D01*
X1141567Y555333D01*
X1141150Y555667D01*
X1140567Y555833D01*
X1139983Y555750D01*
X1139483Y555500D01*
X1139150Y554917D01*
X1138983Y554417D01*
Y553917D01*
X1139150Y553417D01*
X1139567Y552917D01*
X1140067Y552583D01*
X1140650Y552500D01*
X1141233Y552667D01*
X1141817Y553167D01*
G01X1144833Y552500D02*
Y555833D01*
G01Y555167D02*
X1145250Y555500D01*
X1145667Y555750D01*
X1146250Y555833D01*
X1146667Y555750D01*
X1147167Y555500D01*
G01X1154700Y552500D02*
Y555833D01*
G01Y554917D02*
X1154950Y555333D01*
X1155367Y555667D01*
X1155950Y555833D01*
X1156533Y555667D01*
X1156950Y555333D01*
X1157200Y554917D01*
Y552500D01*
G01Y554917D02*
X1157450Y555333D01*
X1157867Y555667D01*
X1158450Y555833D01*
X1159033Y555667D01*
X1159450Y555333D01*
X1159700Y554833D01*
Y552500D01*
G01X1164300D02*
Y555833D01*
G01Y555250D02*
X1163967Y555583D01*
X1163467Y555750D01*
X1162883Y555833D01*
X1162300Y555667D01*
X1161800Y555333D01*
X1161467Y554833D01*
X1161300Y554167D01*
X1161467Y553500D01*
X1161800Y553000D01*
X1162300Y552667D01*
X1162883Y552500D01*
X1163467Y552583D01*
X1163967Y552833D01*
X1164300Y553167D01*
G01X1167150Y553083D02*
X1167567Y552750D01*
X1168150Y552500D01*
X1168650D01*
X1169150Y552667D01*
X1169483Y552917D01*
X1169650Y553250D01*
X1169567Y553750D01*
X1169233Y554000D01*
X1167733Y554500D01*
X1167400Y555083D01*
X1167567Y555500D01*
X1167900Y555750D01*
X1168400Y555833D01*
X1168900Y555750D01*
X1169400Y555500D01*
G01X1172583Y552500D02*
Y557500D01*
G01X1175250Y555833D02*
X1172583Y553917D01*
G01X1173667Y554667D02*
X1175417Y552500D01*
G01X1179600Y552333D02*
X1179433Y552417D01*
Y552583D01*
X1179600Y552667D01*
X1179767Y552583D01*
Y552417D01*
X1179600Y552333D01*
G01X1034000Y566500D02*
Y561500D01*
G01X1032833Y564833D02*
X1035167D01*
G01X1039600Y561500D02*
X1039100Y561583D01*
X1038600Y561917D01*
X1038267Y562500D01*
X1038100Y563167D01*
X1038267Y563833D01*
X1038600Y564417D01*
X1039100Y564750D01*
X1039600Y564833D01*
X1040100Y564750D01*
X1040600Y564417D01*
X1040933Y563833D01*
X1041017Y563167D01*
X1040933Y562500D01*
X1040600Y561917D01*
X1040100Y561583D01*
X1039600Y561500D01*
G01X1049300D02*
Y566500D01*
G01Y564000D02*
X1049717Y564500D01*
X1050217Y564750D01*
X1050717Y564833D01*
X1051467Y564667D01*
X1051967Y564333D01*
X1052300Y563750D01*
Y563083D01*
X1052133Y562417D01*
X1051800Y561917D01*
X1051217Y561583D01*
X1050717Y561500D01*
X1050217Y561583D01*
X1049717Y561833D01*
X1049300Y562250D01*
G01X1055150Y563750D02*
X1057817D01*
X1057567Y564333D01*
X1057150Y564667D01*
X1056567Y564833D01*
X1055983Y564750D01*
X1055483Y564500D01*
X1055150Y563917D01*
X1054983Y563417D01*
Y562917D01*
X1055150Y562417D01*
X1055567Y561917D01*
X1056067Y561583D01*
X1056650Y561500D01*
X1057233Y561667D01*
X1057817Y562167D01*
G01X1068933Y564417D02*
X1068350Y564750D01*
X1067850Y564833D01*
X1067183Y564667D01*
X1066683Y564333D01*
X1066350Y563750D01*
X1066267Y563167D01*
X1066350Y562583D01*
X1066683Y562083D01*
X1067183Y561667D01*
X1067850Y561500D01*
X1068433Y561667D01*
X1068933Y562000D01*
G01X1073200Y561500D02*
X1072700Y561583D01*
X1072200Y561917D01*
X1071867Y562500D01*
X1071700Y563167D01*
X1071867Y563833D01*
X1072200Y564417D01*
X1072700Y564750D01*
X1073200Y564833D01*
X1073700Y564750D01*
X1074200Y564417D01*
X1074533Y563833D01*
X1074617Y563167D01*
X1074533Y562500D01*
X1074200Y561917D01*
X1073700Y561583D01*
X1073200Y561500D01*
G01X1077300Y564833D02*
X1078800Y561500D01*
X1080300Y564833D01*
G01X1083150Y563750D02*
X1085817D01*
X1085567Y564333D01*
X1085150Y564667D01*
X1084567Y564833D01*
X1083983Y564750D01*
X1083483Y564500D01*
X1083150Y563917D01*
X1082983Y563417D01*
Y562917D01*
X1083150Y562417D01*
X1083567Y561917D01*
X1084067Y561583D01*
X1084650Y561500D01*
X1085233Y561667D01*
X1085817Y562167D01*
G01X1088833Y561500D02*
Y564833D01*
G01Y564167D02*
X1089250Y564500D01*
X1089667Y564750D01*
X1090250Y564833D01*
X1090667Y564750D01*
X1091167Y564500D01*
G01X1094350Y563750D02*
X1097017D01*
X1096767Y564333D01*
X1096350Y564667D01*
X1095767Y564833D01*
X1095183Y564750D01*
X1094683Y564500D01*
X1094350Y563917D01*
X1094183Y563417D01*
Y562917D01*
X1094350Y562417D01*
X1094767Y561917D01*
X1095267Y561583D01*
X1095850Y561500D01*
X1096433Y561667D01*
X1097017Y562167D01*
G01X1102700Y566500D02*
Y561500D01*
G01Y562250D02*
X1102367Y561833D01*
X1101867Y561583D01*
X1101283Y561500D01*
X1100617Y561667D01*
X1100117Y562083D01*
X1099783Y562583D01*
X1099700Y563167D01*
X1099783Y563750D01*
X1100117Y564250D01*
X1100617Y564667D01*
X1101283Y564833D01*
X1101867Y564750D01*
X1102283Y564583D01*
X1102700Y564250D01*
G01X1110900Y561500D02*
Y566500D01*
G01Y564000D02*
X1111317Y564500D01*
X1111817Y564750D01*
X1112317Y564833D01*
X1113067Y564667D01*
X1113567Y564333D01*
X1113900Y563750D01*
Y563083D01*
X1113733Y562417D01*
X1113400Y561917D01*
X1112817Y561583D01*
X1112317Y561500D01*
X1111817Y561583D01*
X1111317Y561833D01*
X1110900Y562250D01*
G01X1116250Y560000D02*
X1116750Y559833D01*
X1117417Y560000D01*
X1117833Y560333D01*
X1118167Y560750D01*
X1118667Y562083D01*
X1119750Y564833D01*
G01X1117083D02*
X1118667Y562083D01*
G01X1127950D02*
X1128367Y561750D01*
X1128950Y561500D01*
X1129450D01*
X1129950Y561667D01*
X1130283Y561917D01*
X1130450Y562250D01*
X1130367Y562750D01*
X1130033Y563000D01*
X1128533Y563500D01*
X1128200Y564083D01*
X1128367Y564500D01*
X1128700Y564750D01*
X1129200Y564833D01*
X1129700Y564750D01*
X1130200Y564500D01*
G01X1134800Y561500D02*
X1134300Y561583D01*
X1133800Y561917D01*
X1133467Y562500D01*
X1133300Y563167D01*
X1133467Y563833D01*
X1133800Y564417D01*
X1134300Y564750D01*
X1134800Y564833D01*
X1135300Y564750D01*
X1135800Y564417D01*
X1136133Y563833D01*
X1136217Y563167D01*
X1136133Y562500D01*
X1135800Y561917D01*
X1135300Y561583D01*
X1134800Y561500D01*
G01X1140400D02*
Y566500D01*
G01X1147500D02*
Y561500D01*
G01Y562250D02*
X1147167Y561833D01*
X1146667Y561583D01*
X1146083Y561500D01*
X1145417Y561667D01*
X1144917Y562083D01*
X1144583Y562583D01*
X1144500Y563167D01*
X1144583Y563750D01*
X1144917Y564250D01*
X1145417Y564667D01*
X1146083Y564833D01*
X1146667Y564750D01*
X1147083Y564583D01*
X1147500Y564250D01*
G01X1150350Y563750D02*
X1153017D01*
X1152767Y564333D01*
X1152350Y564667D01*
X1151767Y564833D01*
X1151183Y564750D01*
X1150683Y564500D01*
X1150350Y563917D01*
X1150183Y563417D01*
Y562917D01*
X1150350Y562417D01*
X1150767Y561917D01*
X1151267Y561583D01*
X1151850Y561500D01*
X1152433Y561667D01*
X1153017Y562167D01*
G01X1156033Y561500D02*
Y564833D01*
G01Y564167D02*
X1156450Y564500D01*
X1156867Y564750D01*
X1157450Y564833D01*
X1157867Y564750D01*
X1158367Y564500D01*
G01X1165900Y561500D02*
Y564833D01*
G01Y563917D02*
X1166150Y564333D01*
X1166567Y564667D01*
X1167150Y564833D01*
X1167733Y564667D01*
X1168150Y564333D01*
X1168400Y563917D01*
Y561500D01*
G01Y563917D02*
X1168650Y564333D01*
X1169067Y564667D01*
X1169650Y564833D01*
X1170233Y564667D01*
X1170650Y564333D01*
X1170900Y563833D01*
Y561500D01*
G01X1175500D02*
Y564833D01*
G01Y564250D02*
X1175167Y564583D01*
X1174667Y564750D01*
X1174083Y564833D01*
X1173500Y564667D01*
X1173000Y564333D01*
X1172667Y563833D01*
X1172500Y563167D01*
X1172667Y562500D01*
X1173000Y562000D01*
X1173500Y561667D01*
X1174083Y561500D01*
X1174667Y561583D01*
X1175167Y561833D01*
X1175500Y562167D01*
G01X1178350Y562083D02*
X1178767Y561750D01*
X1179350Y561500D01*
X1179850D01*
X1180350Y561667D01*
X1180683Y561917D01*
X1180850Y562250D01*
X1180767Y562750D01*
X1180433Y563000D01*
X1178933Y563500D01*
X1178600Y564083D01*
X1178767Y564500D01*
X1179100Y564750D01*
X1179600Y564833D01*
X1180100Y564750D01*
X1180600Y564500D01*
G01X1183783Y561500D02*
Y566500D01*
G01X1186450Y564833D02*
X1183783Y562917D01*
G01X1184867Y563667D02*
X1186617Y561500D01*
G01X1197900D02*
Y564833D01*
G01Y564250D02*
X1197567Y564583D01*
X1197067Y564750D01*
X1196483Y564833D01*
X1195900Y564667D01*
X1195400Y564333D01*
X1195067Y563833D01*
X1194900Y563167D01*
X1195067Y562500D01*
X1195400Y562000D01*
X1195900Y561667D01*
X1196483Y561500D01*
X1197067Y561583D01*
X1197567Y561833D01*
X1197900Y562167D01*
G01X1200583Y561500D02*
Y564833D01*
G01Y564000D02*
X1200917Y564417D01*
X1201417Y564750D01*
X1202083Y564833D01*
X1202667Y564750D01*
X1203167Y564417D01*
X1203417Y563833D01*
Y561500D01*
G01X1209100Y566500D02*
Y561500D01*
G01Y562250D02*
X1208767Y561833D01*
X1208267Y561583D01*
X1207683Y561500D01*
X1207017Y561667D01*
X1206517Y562083D01*
X1206183Y562583D01*
X1206100Y563167D01*
X1206183Y563750D01*
X1206517Y564250D01*
X1207017Y564667D01*
X1207683Y564833D01*
X1208267Y564750D01*
X1208683Y564583D01*
X1209100Y564250D01*
G01X1217383Y561500D02*
Y566500D01*
G01Y564083D02*
X1217800Y564500D01*
X1218217Y564750D01*
X1218883Y564833D01*
X1219383Y564750D01*
X1219967Y564417D01*
X1220217Y563917D01*
Y561500D01*
G01X1224400D02*
X1223900Y561583D01*
X1223400Y561917D01*
X1223067Y562500D01*
X1222900Y563167D01*
X1223067Y563833D01*
X1223400Y564417D01*
X1223900Y564750D01*
X1224400Y564833D01*
X1224900Y564750D01*
X1225400Y564417D01*
X1225733Y563833D01*
X1225817Y563167D01*
X1225733Y562500D01*
X1225400Y561917D01*
X1224900Y561583D01*
X1224400Y561500D01*
G01X1230000D02*
Y566500D01*
G01X1234350Y563750D02*
X1237017D01*
X1236767Y564333D01*
X1236350Y564667D01*
X1235767Y564833D01*
X1235183Y564750D01*
X1234683Y564500D01*
X1234350Y563917D01*
X1234183Y563417D01*
Y562917D01*
X1234350Y562417D01*
X1234767Y561917D01*
X1235267Y561583D01*
X1235850Y561500D01*
X1236433Y561667D01*
X1237017Y562167D01*
G01X1248300Y561500D02*
Y564833D01*
G01Y564250D02*
X1247967Y564583D01*
X1247467Y564750D01*
X1246883Y564833D01*
X1246300Y564667D01*
X1245800Y564333D01*
X1245467Y563833D01*
X1245300Y563167D01*
X1245467Y562500D01*
X1245800Y562000D01*
X1246300Y561667D01*
X1246883Y561500D01*
X1247467Y561583D01*
X1247967Y561833D01*
X1248300Y562167D01*
G01X1252400Y561500D02*
Y566500D01*
G01X1256750Y562083D02*
X1257167Y561750D01*
X1257750Y561500D01*
X1258250D01*
X1258750Y561667D01*
X1259083Y561917D01*
X1259250Y562250D01*
X1259167Y562750D01*
X1258833Y563000D01*
X1257333Y563500D01*
X1257000Y564083D01*
X1257167Y564500D01*
X1257500Y564750D01*
X1258000Y564833D01*
X1258500Y564750D01*
X1259000Y564500D01*
G01X1263600Y561500D02*
X1263100Y561583D01*
X1262600Y561917D01*
X1262267Y562500D01*
X1262100Y563167D01*
X1262267Y563833D01*
X1262600Y564417D01*
X1263100Y564750D01*
X1263600Y564833D01*
X1264100Y564750D01*
X1264600Y564417D01*
X1264933Y563833D01*
X1265017Y563167D01*
X1264933Y562500D01*
X1264600Y561917D01*
X1264100Y561583D01*
X1263600Y561500D01*
G01X1273383D02*
Y564833D01*
G01Y564000D02*
X1273717Y564417D01*
X1274217Y564750D01*
X1274883Y564833D01*
X1275467Y564750D01*
X1275967Y564417D01*
X1276217Y563833D01*
Y561500D01*
G01X1279150Y563750D02*
X1281817D01*
X1281567Y564333D01*
X1281150Y564667D01*
X1280567Y564833D01*
X1279983Y564750D01*
X1279483Y564500D01*
X1279150Y563917D01*
X1278983Y563417D01*
Y562917D01*
X1279150Y562417D01*
X1279567Y561917D01*
X1280067Y561583D01*
X1280650Y561500D01*
X1281233Y561667D01*
X1281817Y562167D01*
G01X1284750Y563750D02*
X1287417D01*
X1287167Y564333D01*
X1286750Y564667D01*
X1286167Y564833D01*
X1285583Y564750D01*
X1285083Y564500D01*
X1284750Y563917D01*
X1284583Y563417D01*
Y562917D01*
X1284750Y562417D01*
X1285167Y561917D01*
X1285667Y561583D01*
X1286250Y561500D01*
X1286833Y561667D01*
X1287417Y562167D01*
G01X1293100Y566500D02*
Y561500D01*
G01Y562250D02*
X1292767Y561833D01*
X1292267Y561583D01*
X1291683Y561500D01*
X1291017Y561667D01*
X1290517Y562083D01*
X1290183Y562583D01*
X1290100Y563167D01*
X1290183Y563750D01*
X1290517Y564250D01*
X1291017Y564667D01*
X1291683Y564833D01*
X1292267Y564750D01*
X1292683Y564583D01*
X1293100Y564250D01*
G01X1302800Y566500D02*
Y561500D01*
G01X1301633Y564833D02*
X1303967D01*
G01X1308400Y561500D02*
X1307900Y561583D01*
X1307400Y561917D01*
X1307067Y562500D01*
X1306900Y563167D01*
X1307067Y563833D01*
X1307400Y564417D01*
X1307900Y564750D01*
X1308400Y564833D01*
X1308900Y564750D01*
X1309400Y564417D01*
X1309733Y563833D01*
X1309817Y563167D01*
X1309733Y562500D01*
X1309400Y561917D01*
X1308900Y561583D01*
X1308400Y561500D01*
G01X1022000Y569500D02*
Y574500D01*
X1021000Y573500D01*
G01Y569500D02*
X1023000D01*
G01X1027600Y569333D02*
X1027433Y569417D01*
Y569583D01*
X1027600Y569667D01*
X1027767Y569583D01*
Y569417D01*
X1027600Y569333D01*
G01X1033200Y574500D02*
Y569500D01*
G01X1031283Y574500D02*
X1035117D01*
G01X1037383Y569500D02*
Y574500D01*
G01Y572083D02*
X1037800Y572500D01*
X1038217Y572750D01*
X1038883Y572833D01*
X1039383Y572750D01*
X1039967Y572417D01*
X1040217Y571917D01*
Y569500D01*
G01X1043150Y571750D02*
X1045817D01*
X1045567Y572333D01*
X1045150Y572667D01*
X1044567Y572833D01*
X1043983Y572750D01*
X1043483Y572500D01*
X1043150Y571917D01*
X1042983Y571417D01*
Y570917D01*
X1043150Y570417D01*
X1043567Y569917D01*
X1044067Y569583D01*
X1044650Y569500D01*
X1045233Y569667D01*
X1045817Y570167D01*
G01X1054350Y570083D02*
X1054767Y569750D01*
X1055350Y569500D01*
X1055850D01*
X1056350Y569667D01*
X1056683Y569917D01*
X1056850Y570250D01*
X1056767Y570750D01*
X1056433Y571000D01*
X1054933Y571500D01*
X1054600Y572083D01*
X1054767Y572500D01*
X1055100Y572750D01*
X1055600Y572833D01*
X1056100Y572750D01*
X1056600Y572500D01*
G01X1061200Y572833D02*
Y569500D01*
G01Y574167D02*
X1061033Y574250D01*
Y574417D01*
X1061200Y574500D01*
X1061367Y574417D01*
Y574250D01*
X1061200Y574167D01*
G01X1068300Y574500D02*
Y569500D01*
G01Y570250D02*
X1067967Y569833D01*
X1067467Y569583D01*
X1066883Y569500D01*
X1066217Y569667D01*
X1065717Y570083D01*
X1065383Y570583D01*
X1065300Y571167D01*
X1065383Y571750D01*
X1065717Y572250D01*
X1066217Y572667D01*
X1066883Y572833D01*
X1067467Y572750D01*
X1067883Y572583D01*
X1068300Y572250D01*
G01X1071150Y571750D02*
X1073817D01*
X1073567Y572333D01*
X1073150Y572667D01*
X1072567Y572833D01*
X1071983Y572750D01*
X1071483Y572500D01*
X1071150Y571917D01*
X1070983Y571417D01*
Y570917D01*
X1071150Y570417D01*
X1071567Y569917D01*
X1072067Y569583D01*
X1072650Y569500D01*
X1073233Y569667D01*
X1073817Y570167D01*
G01X1081517Y572833D02*
X1082517Y569500D01*
X1083600Y572833D01*
X1084683Y569500D01*
X1085683Y572833D01*
G01X1089200D02*
Y569500D01*
G01Y574167D02*
X1089033Y574250D01*
Y574417D01*
X1089200Y574500D01*
X1089367Y574417D01*
Y574250D01*
X1089200Y574167D01*
G01X1094800Y574500D02*
Y569500D01*
G01X1093633Y572833D02*
X1095967D01*
G01X1098983Y569500D02*
Y574500D01*
G01Y572083D02*
X1099400Y572500D01*
X1099817Y572750D01*
X1100483Y572833D01*
X1100983Y572750D01*
X1101567Y572417D01*
X1101817Y571917D01*
Y569500D01*
G01X1106000D02*
X1105500Y569583D01*
X1105000Y569917D01*
X1104667Y570500D01*
X1104500Y571167D01*
X1104667Y571833D01*
X1105000Y572417D01*
X1105500Y572750D01*
X1106000Y572833D01*
X1106500Y572750D01*
X1107000Y572417D01*
X1107333Y571833D01*
X1107417Y571167D01*
X1107333Y570500D01*
X1107000Y569917D01*
X1106500Y569583D01*
X1106000Y569500D01*
G01X1110183Y572833D02*
Y570500D01*
X1110517Y569917D01*
X1111017Y569583D01*
X1111600Y569500D01*
X1112183Y569583D01*
X1112683Y569917D01*
X1113017Y570500D01*
G01Y569500D02*
Y572833D01*
G01X1117200Y574500D02*
Y569500D01*
G01X1116033Y572833D02*
X1118367D01*
G01X1127150Y570083D02*
X1127567Y569750D01*
X1128150Y569500D01*
X1128650D01*
X1129150Y569667D01*
X1129483Y569917D01*
X1129650Y570250D01*
X1129567Y570750D01*
X1129233Y571000D01*
X1127733Y571500D01*
X1127400Y572083D01*
X1127567Y572500D01*
X1127900Y572750D01*
X1128400Y572833D01*
X1128900Y572750D01*
X1129400Y572500D01*
G01X1134000Y569500D02*
X1133500Y569583D01*
X1133000Y569917D01*
X1132667Y570500D01*
X1132500Y571167D01*
X1132667Y571833D01*
X1133000Y572417D01*
X1133500Y572750D01*
X1134000Y572833D01*
X1134500Y572750D01*
X1135000Y572417D01*
X1135333Y571833D01*
X1135417Y571167D01*
X1135333Y570500D01*
X1135000Y569917D01*
X1134500Y569583D01*
X1134000Y569500D01*
G01X1139600D02*
Y574500D01*
G01X1146700D02*
Y569500D01*
G01Y570250D02*
X1146367Y569833D01*
X1145867Y569583D01*
X1145283Y569500D01*
X1144617Y569667D01*
X1144117Y570083D01*
X1143783Y570583D01*
X1143700Y571167D01*
X1143783Y571750D01*
X1144117Y572250D01*
X1144617Y572667D01*
X1145283Y572833D01*
X1145867Y572750D01*
X1146283Y572583D01*
X1146700Y572250D01*
G01X1149550Y571750D02*
X1152217D01*
X1151967Y572333D01*
X1151550Y572667D01*
X1150967Y572833D01*
X1150383Y572750D01*
X1149883Y572500D01*
X1149550Y571917D01*
X1149383Y571417D01*
Y570917D01*
X1149550Y570417D01*
X1149967Y569917D01*
X1150467Y569583D01*
X1151050Y569500D01*
X1151633Y569667D01*
X1152217Y570167D01*
G01X1155233Y569500D02*
Y572833D01*
G01Y572167D02*
X1155650Y572500D01*
X1156067Y572750D01*
X1156650Y572833D01*
X1157067Y572750D01*
X1157567Y572500D01*
G01X1165100Y569500D02*
Y572833D01*
G01Y571917D02*
X1165350Y572333D01*
X1165767Y572667D01*
X1166350Y572833D01*
X1166933Y572667D01*
X1167350Y572333D01*
X1167600Y571917D01*
Y569500D01*
G01Y571917D02*
X1167850Y572333D01*
X1168267Y572667D01*
X1168850Y572833D01*
X1169433Y572667D01*
X1169850Y572333D01*
X1170100Y571833D01*
Y569500D01*
G01X1174700D02*
Y572833D01*
G01Y572250D02*
X1174367Y572583D01*
X1173867Y572750D01*
X1173283Y572833D01*
X1172700Y572667D01*
X1172200Y572333D01*
X1171867Y571833D01*
X1171700Y571167D01*
X1171867Y570500D01*
X1172200Y570000D01*
X1172700Y569667D01*
X1173283Y569500D01*
X1173867Y569583D01*
X1174367Y569833D01*
X1174700Y570167D01*
G01X1177550Y570083D02*
X1177967Y569750D01*
X1178550Y569500D01*
X1179050D01*
X1179550Y569667D01*
X1179883Y569917D01*
X1180050Y570250D01*
X1179967Y570750D01*
X1179633Y571000D01*
X1178133Y571500D01*
X1177800Y572083D01*
X1177967Y572500D01*
X1178300Y572750D01*
X1178800Y572833D01*
X1179300Y572750D01*
X1179800Y572500D01*
G01X1182983Y569500D02*
Y574500D01*
G01X1185650Y572833D02*
X1182983Y570917D01*
G01X1184067Y571667D02*
X1185817Y569500D01*
G01X1194100Y567833D02*
Y572833D01*
G01Y572083D02*
X1194517Y572500D01*
X1194933Y572750D01*
X1195600Y572833D01*
X1196183Y572750D01*
X1196767Y572333D01*
X1197017Y571750D01*
X1197100Y571167D01*
X1197017Y570583D01*
X1196767Y570000D01*
X1196267Y569667D01*
X1195600Y569500D01*
X1195017Y569583D01*
X1194433Y569833D01*
X1194100Y570167D01*
G01X1202700Y569500D02*
Y572833D01*
G01Y572250D02*
X1202367Y572583D01*
X1201867Y572750D01*
X1201283Y572833D01*
X1200700Y572667D01*
X1200200Y572333D01*
X1199867Y571833D01*
X1199700Y571167D01*
X1199867Y570500D01*
X1200200Y570000D01*
X1200700Y569667D01*
X1201283Y569500D01*
X1201867Y569583D01*
X1202367Y569833D01*
X1202700Y570167D01*
G01X1208300Y574500D02*
Y569500D01*
G01Y570250D02*
X1207967Y569833D01*
X1207467Y569583D01*
X1206883Y569500D01*
X1206217Y569667D01*
X1205717Y570083D01*
X1205383Y570583D01*
X1205300Y571167D01*
X1205383Y571750D01*
X1205717Y572250D01*
X1206217Y572667D01*
X1206883Y572833D01*
X1207467Y572750D01*
X1207883Y572583D01*
X1208300Y572250D01*
G01X1217833Y568583D02*
X1218167Y569667D01*
G01X1230700Y569500D02*
Y572833D01*
G01Y572250D02*
X1230367Y572583D01*
X1229867Y572750D01*
X1229283Y572833D01*
X1228700Y572667D01*
X1228200Y572333D01*
X1227867Y571833D01*
X1227700Y571167D01*
X1227867Y570500D01*
X1228200Y570000D01*
X1228700Y569667D01*
X1229283Y569500D01*
X1229867Y569583D01*
X1230367Y569833D01*
X1230700Y570167D01*
G01X1233383Y569500D02*
Y572833D01*
G01Y572000D02*
X1233717Y572417D01*
X1234217Y572750D01*
X1234883Y572833D01*
X1235467Y572750D01*
X1235967Y572417D01*
X1236217Y571833D01*
Y569500D01*
G01X1238983D02*
Y572833D01*
G01Y572000D02*
X1239317Y572417D01*
X1239817Y572750D01*
X1240483Y572833D01*
X1241067Y572750D01*
X1241567Y572417D01*
X1241817Y571833D01*
Y569500D01*
G01X1244583Y572833D02*
Y570500D01*
X1244917Y569917D01*
X1245417Y569583D01*
X1246000Y569500D01*
X1246583Y569583D01*
X1247083Y569917D01*
X1247417Y570500D01*
G01Y569500D02*
Y572833D01*
G01X1253100Y569500D02*
Y572833D01*
G01Y572250D02*
X1252767Y572583D01*
X1252267Y572750D01*
X1251683Y572833D01*
X1251100Y572667D01*
X1250600Y572333D01*
X1250267Y571833D01*
X1250100Y571167D01*
X1250267Y570500D01*
X1250600Y570000D01*
X1251100Y569667D01*
X1251683Y569500D01*
X1252267Y569583D01*
X1252767Y569833D01*
X1253100Y570167D01*
G01X1257200Y569500D02*
Y574500D01*
G01X1267233Y569500D02*
Y572833D01*
G01Y572167D02*
X1267650Y572500D01*
X1268067Y572750D01*
X1268650Y572833D01*
X1269067Y572750D01*
X1269567Y572500D01*
G01X1274000Y572833D02*
Y569500D01*
G01Y574167D02*
X1273833Y574250D01*
Y574417D01*
X1274000Y574500D01*
X1274167Y574417D01*
Y574250D01*
X1274000Y574167D01*
G01X1278183Y569500D02*
Y572833D01*
G01Y572000D02*
X1278517Y572417D01*
X1279017Y572750D01*
X1279683Y572833D01*
X1280267Y572750D01*
X1280767Y572417D01*
X1281017Y571833D01*
Y569500D01*
G01X1284033Y568250D02*
X1284617Y567917D01*
X1285283Y567833D01*
X1285867Y567917D01*
X1286367Y568333D01*
X1286700Y568917D01*
Y572833D01*
G01Y572167D02*
X1286367Y572500D01*
X1285867Y572750D01*
X1285283Y572833D01*
X1284617Y572667D01*
X1284200Y572333D01*
X1283867Y571750D01*
X1283700Y571167D01*
X1283783Y570667D01*
X1284117Y570083D01*
X1284617Y569667D01*
X1285283Y569500D01*
X1285783Y569583D01*
X1286367Y569917D01*
X1286700Y570250D01*
G01X1294983Y569500D02*
Y572833D01*
G01Y572000D02*
X1295317Y572417D01*
X1295817Y572750D01*
X1296483Y572833D01*
X1297067Y572750D01*
X1297567Y572417D01*
X1297817Y571833D01*
Y569500D01*
G01X1300750Y571750D02*
X1303417D01*
X1303167Y572333D01*
X1302750Y572667D01*
X1302167Y572833D01*
X1301583Y572750D01*
X1301083Y572500D01*
X1300750Y571917D01*
X1300583Y571417D01*
Y570917D01*
X1300750Y570417D01*
X1301167Y569917D01*
X1301667Y569583D01*
X1302250Y569500D01*
X1302833Y569667D01*
X1303417Y570167D01*
G01X1306350Y571750D02*
X1309017D01*
X1308767Y572333D01*
X1308350Y572667D01*
X1307767Y572833D01*
X1307183Y572750D01*
X1306683Y572500D01*
X1306350Y571917D01*
X1306183Y571417D01*
Y570917D01*
X1306350Y570417D01*
X1306767Y569917D01*
X1307267Y569583D01*
X1307850Y569500D01*
X1308433Y569667D01*
X1309017Y570167D01*
G01X1314700Y574500D02*
Y569500D01*
G01Y570250D02*
X1314367Y569833D01*
X1313867Y569583D01*
X1313283Y569500D01*
X1312617Y569667D01*
X1312117Y570083D01*
X1311783Y570583D01*
X1311700Y571167D01*
X1311783Y571750D01*
X1312117Y572250D01*
X1312617Y572667D01*
X1313283Y572833D01*
X1313867Y572750D01*
X1314283Y572583D01*
X1314700Y572250D01*
G01X1012083Y730500D02*
Y733833D01*
G01Y733000D02*
X1012417Y733417D01*
X1012917Y733750D01*
X1013583Y733833D01*
X1014167Y733750D01*
X1014667Y733417D01*
X1014917Y732833D01*
Y730500D01*
G01X1019100D02*
X1018600Y730583D01*
X1018100Y730917D01*
X1017767Y731500D01*
X1017600Y732167D01*
X1017767Y732833D01*
X1018100Y733417D01*
X1018600Y733750D01*
X1019100Y733833D01*
X1019600Y733750D01*
X1020100Y733417D01*
X1020433Y732833D01*
X1020517Y732167D01*
X1020433Y731500D01*
X1020100Y730917D01*
X1019600Y730583D01*
X1019100Y730500D01*
G01X1028800Y728833D02*
Y733833D01*
G01Y733083D02*
X1029217Y733500D01*
X1029633Y733750D01*
X1030300Y733833D01*
X1030883Y733750D01*
X1031467Y733333D01*
X1031717Y732750D01*
X1031800Y732167D01*
X1031717Y731583D01*
X1031467Y731000D01*
X1030967Y730667D01*
X1030300Y730500D01*
X1029717Y730583D01*
X1029133Y730833D01*
X1028800Y731167D01*
G01X1035900Y730500D02*
Y735500D01*
G01X1040083Y733833D02*
Y731500D01*
X1040417Y730917D01*
X1040917Y730583D01*
X1041500Y730500D01*
X1042083Y730583D01*
X1042583Y730917D01*
X1042917Y731500D01*
G01Y730500D02*
Y733833D01*
G01X1045933Y729250D02*
X1046517Y728917D01*
X1047183Y728833D01*
X1047767Y728917D01*
X1048267Y729333D01*
X1048600Y729917D01*
Y733833D01*
G01Y733167D02*
X1048267Y733500D01*
X1047767Y733750D01*
X1047183Y733833D01*
X1046517Y733667D01*
X1046100Y733333D01*
X1045767Y732750D01*
X1045600Y732167D01*
X1045683Y731667D01*
X1046017Y731083D01*
X1046517Y730667D01*
X1047183Y730500D01*
X1047683Y730583D01*
X1048267Y730917D01*
X1048600Y731250D01*
G01X1051533Y729250D02*
X1052117Y728917D01*
X1052783Y728833D01*
X1053367Y728917D01*
X1053867Y729333D01*
X1054200Y729917D01*
Y733833D01*
G01Y733167D02*
X1053867Y733500D01*
X1053367Y733750D01*
X1052783Y733833D01*
X1052117Y733667D01*
X1051700Y733333D01*
X1051367Y732750D01*
X1051200Y732167D01*
X1051283Y731667D01*
X1051617Y731083D01*
X1052117Y730667D01*
X1052783Y730500D01*
X1053283Y730583D01*
X1053867Y730917D01*
X1054200Y731250D01*
G01X1058300Y733833D02*
Y730500D01*
G01Y735167D02*
X1058133Y735250D01*
Y735417D01*
X1058300Y735500D01*
X1058467Y735417D01*
Y735250D01*
X1058300Y735167D01*
G01X1062483Y730500D02*
Y733833D01*
G01Y733000D02*
X1062817Y733417D01*
X1063317Y733750D01*
X1063983Y733833D01*
X1064567Y733750D01*
X1065067Y733417D01*
X1065317Y732833D01*
Y730500D01*
G01X1068333Y729250D02*
X1068917Y728917D01*
X1069583Y728833D01*
X1070167Y728917D01*
X1070667Y729333D01*
X1071000Y729917D01*
Y733833D01*
G01Y733167D02*
X1070667Y733500D01*
X1070167Y733750D01*
X1069583Y733833D01*
X1068917Y733667D01*
X1068500Y733333D01*
X1068167Y732750D01*
X1068000Y732167D01*
X1068083Y731667D01*
X1068417Y731083D01*
X1068917Y730667D01*
X1069583Y730500D01*
X1070083Y730583D01*
X1070667Y730917D01*
X1071000Y731250D01*
G01X1089493Y104700D02*
Y99700D01*
X1092827D01*
G01X1095510Y103033D02*
X1098010Y99700D01*
G01Y103033D02*
X1095510Y99700D01*
G01X1102360Y99533D02*
X1102193Y99617D01*
Y99783D01*
X1102360Y99867D01*
X1102527Y99783D01*
Y99617D01*
X1102360Y99533D01*
G01Y101783D02*
X1102193Y101867D01*
Y102033D01*
X1102360Y102117D01*
X1102527Y102033D01*
Y101867D01*
X1102360Y101783D01*
G01X1111060Y99700D02*
Y103033D01*
G01Y102117D02*
X1111310Y102533D01*
X1111727Y102867D01*
X1112310Y103033D01*
X1112893Y102867D01*
X1113310Y102533D01*
X1113560Y102117D01*
Y99700D01*
G01Y102117D02*
X1113810Y102533D01*
X1114227Y102867D01*
X1114810Y103033D01*
X1115393Y102867D01*
X1115810Y102533D01*
X1116060Y102033D01*
Y99700D01*
G01X1117743Y103033D02*
Y100700D01*
X1118077Y100117D01*
X1118577Y99783D01*
X1119160Y99700D01*
X1119743Y99783D01*
X1120243Y100117D01*
X1120577Y100700D01*
G01Y99700D02*
Y103033D01*
G01X1123510Y100283D02*
X1123927Y99950D01*
X1124510Y99700D01*
X1125010D01*
X1125510Y99867D01*
X1125843Y100117D01*
X1126010Y100450D01*
X1125927Y100950D01*
X1125593Y101200D01*
X1124093Y101700D01*
X1123760Y102283D01*
X1123927Y102700D01*
X1124260Y102950D01*
X1124760Y103033D01*
X1125260Y102950D01*
X1125760Y102700D01*
G01X1130360Y104700D02*
Y99700D01*
G01X1129193Y103033D02*
X1131527D01*
G01X1140060Y99700D02*
Y104700D01*
G01Y102200D02*
X1140477Y102700D01*
X1140977Y102950D01*
X1141477Y103033D01*
X1142227Y102867D01*
X1142727Y102533D01*
X1143060Y101950D01*
Y101283D01*
X1142893Y100617D01*
X1142560Y100117D01*
X1141977Y99783D01*
X1141477Y99700D01*
X1140977Y99783D01*
X1140477Y100033D01*
X1140060Y100450D01*
G01X1145910Y101950D02*
X1148577D01*
X1148327Y102533D01*
X1147910Y102867D01*
X1147327Y103033D01*
X1146743Y102950D01*
X1146243Y102700D01*
X1145910Y102117D01*
X1145743Y101617D01*
Y101117D01*
X1145910Y100617D01*
X1146327Y100117D01*
X1146827Y99783D01*
X1147410Y99700D01*
X1147993Y99867D01*
X1148577Y100367D01*
G01X1156860Y99700D02*
Y104700D01*
G01Y102200D02*
X1157277Y102700D01*
X1157777Y102950D01*
X1158277Y103033D01*
X1159027Y102867D01*
X1159527Y102533D01*
X1159860Y101950D01*
Y101283D01*
X1159693Y100617D01*
X1159360Y100117D01*
X1158777Y99783D01*
X1158277Y99700D01*
X1157777Y99783D01*
X1157277Y100033D01*
X1156860Y100450D01*
G01X1162793Y99700D02*
Y103033D01*
G01Y102367D02*
X1163210Y102700D01*
X1163627Y102950D01*
X1164210Y103033D01*
X1164627Y102950D01*
X1165127Y102700D01*
G01X1169560Y99700D02*
X1169060Y99783D01*
X1168560Y100117D01*
X1168227Y100700D01*
X1168060Y101367D01*
X1168227Y102033D01*
X1168560Y102617D01*
X1169060Y102950D01*
X1169560Y103033D01*
X1170060Y102950D01*
X1170560Y102617D01*
X1170893Y102033D01*
X1170977Y101367D01*
X1170893Y100700D01*
X1170560Y100117D01*
X1170060Y99783D01*
X1169560Y99700D01*
G01X1173743D02*
Y104700D01*
G01X1176410Y103033D02*
X1173743Y101117D01*
G01X1174827Y101867D02*
X1176577Y99700D01*
G01X1179510Y101950D02*
X1182177D01*
X1181927Y102533D01*
X1181510Y102867D01*
X1180927Y103033D01*
X1180343Y102950D01*
X1179843Y102700D01*
X1179510Y102117D01*
X1179343Y101617D01*
Y101117D01*
X1179510Y100617D01*
X1179927Y100117D01*
X1180427Y99783D01*
X1181010Y99700D01*
X1181593Y99867D01*
X1182177Y100367D01*
G01X1184943Y99700D02*
Y103033D01*
G01Y102200D02*
X1185277Y102617D01*
X1185777Y102950D01*
X1186443Y103033D01*
X1187027Y102950D01*
X1187527Y102617D01*
X1187777Y102033D01*
Y99700D01*
G01X1197560D02*
Y104700D01*
G01X1204660Y99700D02*
Y103033D01*
G01Y102450D02*
X1204327Y102783D01*
X1203827Y102950D01*
X1203243Y103033D01*
X1202660Y102867D01*
X1202160Y102533D01*
X1201827Y102033D01*
X1201660Y101367D01*
X1201827Y100700D01*
X1202160Y100200D01*
X1202660Y99867D01*
X1203243Y99700D01*
X1203827Y99783D01*
X1204327Y100033D01*
X1204660Y100367D01*
G01X1207010Y98200D02*
X1207510Y98033D01*
X1208177Y98200D01*
X1208593Y98533D01*
X1208927Y98950D01*
X1209427Y100283D01*
X1210510Y103033D01*
G01X1207843D02*
X1209427Y100283D01*
G01X1213110Y101950D02*
X1215777D01*
X1215527Y102533D01*
X1215110Y102867D01*
X1214527Y103033D01*
X1213943Y102950D01*
X1213443Y102700D01*
X1213110Y102117D01*
X1212943Y101617D01*
Y101117D01*
X1213110Y100617D01*
X1213527Y100117D01*
X1214027Y99783D01*
X1214610Y99700D01*
X1215193Y99867D01*
X1215777Y100367D01*
G01X1218793Y99700D02*
Y103033D01*
G01Y102367D02*
X1219210Y102700D01*
X1219627Y102950D01*
X1220210Y103033D01*
X1220627Y102950D01*
X1221127Y102700D01*
G01X1088893Y117200D02*
Y112200D01*
X1092227D01*
G01X1094743D02*
Y115533D01*
G01Y114700D02*
X1095077Y115117D01*
X1095577Y115450D01*
X1096243Y115533D01*
X1096827Y115450D01*
X1097327Y115117D01*
X1097577Y114533D01*
Y112200D01*
G01X1101760Y112033D02*
X1101593Y112117D01*
Y112283D01*
X1101760Y112367D01*
X1101927Y112283D01*
Y112117D01*
X1101760Y112033D01*
G01Y114283D02*
X1101593Y114367D01*
Y114533D01*
X1101760Y114617D01*
X1101927Y114533D01*
Y114367D01*
X1101760Y114283D01*
G01X1114293Y115117D02*
X1113710Y115450D01*
X1113210Y115533D01*
X1112543Y115367D01*
X1112043Y115033D01*
X1111710Y114450D01*
X1111627Y113867D01*
X1111710Y113283D01*
X1112043Y112783D01*
X1112543Y112367D01*
X1113210Y112200D01*
X1113793Y112367D01*
X1114293Y112700D01*
G01X1120060Y112200D02*
Y115533D01*
G01Y114950D02*
X1119727Y115283D01*
X1119227Y115450D01*
X1118643Y115533D01*
X1118060Y115367D01*
X1117560Y115033D01*
X1117227Y114533D01*
X1117060Y113867D01*
X1117227Y113200D01*
X1117560Y112700D01*
X1118060Y112367D01*
X1118643Y112200D01*
X1119227Y112283D01*
X1119727Y112533D01*
X1120060Y112867D01*
G01X1122743Y112200D02*
Y115533D01*
G01Y114700D02*
X1123077Y115117D01*
X1123577Y115450D01*
X1124243Y115533D01*
X1124827Y115450D01*
X1125327Y115117D01*
X1125577Y114533D01*
Y112200D01*
G01X1129760Y115533D02*
X1130593Y116575D01*
Y117200D01*
X1129968D01*
Y116575D01*
X1130593D01*
G01X1135360Y117200D02*
Y112200D01*
G01X1134193Y115533D02*
X1136527D01*
G01X1145060Y112200D02*
Y117200D01*
G01Y114700D02*
X1145477Y115200D01*
X1145977Y115450D01*
X1146477Y115533D01*
X1147227Y115367D01*
X1147727Y115033D01*
X1148060Y114450D01*
Y113783D01*
X1147893Y113117D01*
X1147560Y112617D01*
X1146977Y112283D01*
X1146477Y112200D01*
X1145977Y112283D01*
X1145477Y112533D01*
X1145060Y112950D01*
G01X1150910Y114450D02*
X1153577D01*
X1153327Y115033D01*
X1152910Y115367D01*
X1152327Y115533D01*
X1151743Y115450D01*
X1151243Y115200D01*
X1150910Y114617D01*
X1150743Y114117D01*
Y113617D01*
X1150910Y113117D01*
X1151327Y112617D01*
X1151827Y112283D01*
X1152410Y112200D01*
X1152993Y112367D01*
X1153577Y112867D01*
G01X1161860Y112200D02*
Y117200D01*
G01Y114700D02*
X1162277Y115200D01*
X1162777Y115450D01*
X1163277Y115533D01*
X1164027Y115367D01*
X1164527Y115033D01*
X1164860Y114450D01*
Y113783D01*
X1164693Y113117D01*
X1164360Y112617D01*
X1163777Y112283D01*
X1163277Y112200D01*
X1162777Y112283D01*
X1162277Y112533D01*
X1161860Y112950D01*
G01X1167793Y112200D02*
Y115533D01*
G01Y114867D02*
X1168210Y115200D01*
X1168627Y115450D01*
X1169210Y115533D01*
X1169627Y115450D01*
X1170127Y115200D01*
G01X1174560Y112200D02*
X1174060Y112283D01*
X1173560Y112617D01*
X1173227Y113200D01*
X1173060Y113867D01*
X1173227Y114533D01*
X1173560Y115117D01*
X1174060Y115450D01*
X1174560Y115533D01*
X1175060Y115450D01*
X1175560Y115117D01*
X1175893Y114533D01*
X1175977Y113867D01*
X1175893Y113200D01*
X1175560Y112617D01*
X1175060Y112283D01*
X1174560Y112200D01*
G01X1178743D02*
Y117200D01*
G01X1181410Y115533D02*
X1178743Y113617D01*
G01X1179827Y114367D02*
X1181577Y112200D01*
G01X1184510Y114450D02*
X1187177D01*
X1186927Y115033D01*
X1186510Y115367D01*
X1185927Y115533D01*
X1185343Y115450D01*
X1184843Y115200D01*
X1184510Y114617D01*
X1184343Y114117D01*
Y113617D01*
X1184510Y113117D01*
X1184927Y112617D01*
X1185427Y112283D01*
X1186010Y112200D01*
X1186593Y112367D01*
X1187177Y112867D01*
G01X1189943Y112200D02*
Y115533D01*
G01Y114700D02*
X1190277Y115117D01*
X1190777Y115450D01*
X1191443Y115533D01*
X1192027Y115450D01*
X1192527Y115117D01*
X1192777Y114533D01*
Y112200D01*
G01X1202560D02*
Y117200D01*
G01X1209660Y112200D02*
Y115533D01*
G01Y114950D02*
X1209327Y115283D01*
X1208827Y115450D01*
X1208243Y115533D01*
X1207660Y115367D01*
X1207160Y115033D01*
X1206827Y114533D01*
X1206660Y113867D01*
X1206827Y113200D01*
X1207160Y112700D01*
X1207660Y112367D01*
X1208243Y112200D01*
X1208827Y112283D01*
X1209327Y112533D01*
X1209660Y112867D01*
G01X1212010Y110700D02*
X1212510Y110533D01*
X1213177Y110700D01*
X1213593Y111033D01*
X1213927Y111450D01*
X1214427Y112783D01*
X1215510Y115533D01*
G01X1212843D02*
X1214427Y112783D01*
G01X1218110Y114450D02*
X1220777D01*
X1220527Y115033D01*
X1220110Y115367D01*
X1219527Y115533D01*
X1218943Y115450D01*
X1218443Y115200D01*
X1218110Y114617D01*
X1217943Y114117D01*
Y113617D01*
X1218110Y113117D01*
X1218527Y112617D01*
X1219027Y112283D01*
X1219610Y112200D01*
X1220193Y112367D01*
X1220777Y112867D01*
G01X1223793Y112200D02*
Y115533D01*
G01Y114867D02*
X1224210Y115200D01*
X1224627Y115450D01*
X1225210Y115533D01*
X1225627Y115450D01*
X1226127Y115200D01*
G01X1087667Y124000D02*
Y129000D01*
X1089333D01*
X1090000Y128750D01*
X1090500Y128417D01*
X1090917Y127917D01*
X1091250Y127333D01*
X1091333Y126500D01*
X1091250Y125667D01*
X1090917Y125083D01*
X1090500Y124583D01*
X1090000Y124250D01*
X1089333Y124000D01*
X1087667D01*
G01X1093933D02*
Y127333D01*
G01Y126667D02*
X1094350Y127000D01*
X1094767Y127250D01*
X1095350Y127333D01*
X1095767Y127250D01*
X1096267Y127000D01*
G01X1100700Y127333D02*
Y124000D01*
G01Y128667D02*
X1100533Y128750D01*
Y128917D01*
X1100700Y129000D01*
X1100867Y128917D01*
Y128750D01*
X1100700Y128667D01*
G01X1106300Y124000D02*
Y129000D01*
G01X1111900Y124000D02*
Y129000D01*
G01X1121517Y124000D02*
Y129000D01*
X1124683D01*
G01X1123517Y126583D02*
X1121517D01*
G01X1127533Y124000D02*
Y127333D01*
G01Y126667D02*
X1127950Y127000D01*
X1128367Y127250D01*
X1128950Y127333D01*
X1129367Y127250D01*
X1129867Y127000D01*
G01X1134300Y124000D02*
X1133800Y124083D01*
X1133300Y124417D01*
X1132967Y125000D01*
X1132800Y125667D01*
X1132967Y126333D01*
X1133300Y126917D01*
X1133800Y127250D01*
X1134300Y127333D01*
X1134800Y127250D01*
X1135300Y126917D01*
X1135633Y126333D01*
X1135717Y125667D01*
X1135633Y125000D01*
X1135300Y124417D01*
X1134800Y124083D01*
X1134300Y124000D01*
G01X1137400D02*
Y127333D01*
G01Y126417D02*
X1137650Y126833D01*
X1138067Y127167D01*
X1138650Y127333D01*
X1139233Y127167D01*
X1139650Y126833D01*
X1139900Y126417D01*
Y124000D01*
G01Y126417D02*
X1140150Y126833D01*
X1140567Y127167D01*
X1141150Y127333D01*
X1141733Y127167D01*
X1142150Y126833D01*
X1142400Y126333D01*
Y124000D01*
G01X1167483Y122333D02*
X1166650Y123167D01*
X1166233Y124000D01*
Y127333D01*
X1166650Y128167D01*
X1167483Y129000D01*
G01X1174167Y126667D02*
X1174500Y126917D01*
X1174750Y127333D01*
X1174917Y127917D01*
X1174750Y128417D01*
X1174417Y128750D01*
X1173833Y129000D01*
X1171583D01*
Y124000D01*
X1174333D01*
X1174917Y124333D01*
X1175250Y124833D01*
X1175417Y125417D01*
X1175250Y126000D01*
X1174750Y126500D01*
X1174167Y126667D01*
X1171583D01*
G01X1179100Y124000D02*
X1178433Y124083D01*
X1177850Y124417D01*
X1177350Y124917D01*
X1177017Y125500D01*
X1176850Y126167D01*
Y126833D01*
X1177017Y127500D01*
X1177350Y128083D01*
X1177850Y128583D01*
X1178433Y128917D01*
X1179100Y129000D01*
X1179767Y128917D01*
X1180350Y128583D01*
X1180850Y128083D01*
X1181183Y127500D01*
X1181350Y126833D01*
Y126167D01*
X1181183Y125500D01*
X1180850Y124917D01*
X1180350Y124417D01*
X1179767Y124083D01*
X1179100Y124000D01*
G01X1184700Y129000D02*
Y124000D01*
G01X1182783Y129000D02*
X1186617D01*
G01X1190300D02*
Y124000D01*
G01X1188383Y129000D02*
X1192217D01*
G01X1195900Y124000D02*
X1195233Y124083D01*
X1194650Y124417D01*
X1194150Y124917D01*
X1193817Y125500D01*
X1193650Y126167D01*
Y126833D01*
X1193817Y127500D01*
X1194150Y128083D01*
X1194650Y128583D01*
X1195233Y128917D01*
X1195900Y129000D01*
X1196567Y128917D01*
X1197150Y128583D01*
X1197650Y128083D01*
X1197983Y127500D01*
X1198150Y126833D01*
Y126167D01*
X1197983Y125500D01*
X1197650Y124917D01*
X1197150Y124417D01*
X1196567Y124083D01*
X1195900Y124000D01*
G01X1199333D02*
Y129000D01*
X1201500Y124833D01*
X1203667Y129000D01*
Y124000D01*
G01X1207517Y122333D02*
X1208350Y123167D01*
X1208767Y124000D01*
Y127333D01*
X1208350Y128167D01*
X1207517Y129000D01*
G01X1218300D02*
Y124000D01*
G01X1217133Y127333D02*
X1219467D01*
G01X1223900Y124000D02*
X1223400Y124083D01*
X1222900Y124417D01*
X1222567Y125000D01*
X1222400Y125667D01*
X1222567Y126333D01*
X1222900Y126917D01*
X1223400Y127250D01*
X1223900Y127333D01*
X1224400Y127250D01*
X1224900Y126917D01*
X1225233Y126333D01*
X1225317Y125667D01*
X1225233Y125000D01*
X1224900Y124417D01*
X1224400Y124083D01*
X1223900Y124000D01*
G01X1233433Y129000D02*
Y124000D01*
X1236767D01*
G01X1239450Y127333D02*
X1241950Y124000D01*
G01Y127333D02*
X1239450Y124000D01*
G01X1109833Y590500D02*
Y595500D01*
X1111833D01*
X1112500Y595250D01*
X1113000Y594667D01*
X1113167Y594000D01*
X1113000Y593333D01*
X1112583Y592833D01*
X1111833Y592583D01*
X1109833D01*
G01X1117100Y590500D02*
Y595500D01*
G01X1121283Y593833D02*
Y591500D01*
X1121617Y590917D01*
X1122117Y590583D01*
X1122700Y590500D01*
X1123283Y590583D01*
X1123783Y590917D01*
X1124117Y591500D01*
G01Y590500D02*
Y593833D01*
G01X1127133Y589250D02*
X1127717Y588917D01*
X1128383Y588833D01*
X1128967Y588917D01*
X1129467Y589333D01*
X1129800Y589917D01*
Y593833D01*
G01Y593167D02*
X1129467Y593500D01*
X1128967Y593750D01*
X1128383Y593833D01*
X1127717Y593667D01*
X1127300Y593333D01*
X1126967Y592750D01*
X1126800Y592167D01*
X1126883Y591667D01*
X1127217Y591083D01*
X1127717Y590667D01*
X1128383Y590500D01*
X1128883Y590583D01*
X1129467Y590917D01*
X1129800Y591250D01*
G01X1132733Y589250D02*
X1133317Y588917D01*
X1133983Y588833D01*
X1134567Y588917D01*
X1135067Y589333D01*
X1135400Y589917D01*
Y593833D01*
G01Y593167D02*
X1135067Y593500D01*
X1134567Y593750D01*
X1133983Y593833D01*
X1133317Y593667D01*
X1132900Y593333D01*
X1132567Y592750D01*
X1132400Y592167D01*
X1132483Y591667D01*
X1132817Y591083D01*
X1133317Y590667D01*
X1133983Y590500D01*
X1134483Y590583D01*
X1135067Y590917D01*
X1135400Y591250D01*
G01X1139500Y593833D02*
Y590500D01*
G01Y595167D02*
X1139333Y595250D01*
Y595417D01*
X1139500Y595500D01*
X1139667Y595417D01*
Y595250D01*
X1139500Y595167D01*
G01X1143683Y590500D02*
Y593833D01*
G01Y593000D02*
X1144017Y593417D01*
X1144517Y593750D01*
X1145183Y593833D01*
X1145767Y593750D01*
X1146267Y593417D01*
X1146517Y592833D01*
Y590500D01*
G01X1149533Y589250D02*
X1150117Y588917D01*
X1150783Y588833D01*
X1151367Y588917D01*
X1151867Y589333D01*
X1152200Y589917D01*
Y593833D01*
G01Y593167D02*
X1151867Y593500D01*
X1151367Y593750D01*
X1150783Y593833D01*
X1150117Y593667D01*
X1149700Y593333D01*
X1149367Y592750D01*
X1149200Y592167D01*
X1149283Y591667D01*
X1149617Y591083D01*
X1150117Y590667D01*
X1150783Y590500D01*
X1151283Y590583D01*
X1151867Y590917D01*
X1152200Y591250D01*
G01X1163233Y593417D02*
X1162650Y593750D01*
X1162150Y593833D01*
X1161483Y593667D01*
X1160983Y593333D01*
X1160650Y592750D01*
X1160567Y592167D01*
X1160650Y591583D01*
X1160983Y591083D01*
X1161483Y590667D01*
X1162150Y590500D01*
X1162733Y590667D01*
X1163233Y591000D01*
G01X1166333Y590500D02*
Y593833D01*
G01Y593167D02*
X1166750Y593500D01*
X1167167Y593750D01*
X1167750Y593833D01*
X1168167Y593750D01*
X1168667Y593500D01*
G01X1173100Y593833D02*
Y590500D01*
G01Y595167D02*
X1172933Y595250D01*
Y595417D01*
X1173100Y595500D01*
X1173267Y595417D01*
Y595250D01*
X1173100Y595167D01*
G01X1178700Y595500D02*
Y590500D01*
G01X1177533Y593833D02*
X1179867D01*
G01X1183050Y592750D02*
X1185717D01*
X1185467Y593333D01*
X1185050Y593667D01*
X1184467Y593833D01*
X1183883Y593750D01*
X1183383Y593500D01*
X1183050Y592917D01*
X1182883Y592417D01*
Y591917D01*
X1183050Y591417D01*
X1183467Y590917D01*
X1183967Y590583D01*
X1184550Y590500D01*
X1185133Y590667D01*
X1185717Y591167D01*
G01X1188733Y590500D02*
Y593833D01*
G01Y593167D02*
X1189150Y593500D01*
X1189567Y593750D01*
X1190150Y593833D01*
X1190567Y593750D01*
X1191067Y593500D01*
G01X1195500Y593833D02*
Y590500D01*
G01Y595167D02*
X1195333Y595250D01*
Y595417D01*
X1195500Y595500D01*
X1195667Y595417D01*
Y595250D01*
X1195500Y595167D01*
G01X1202600Y590500D02*
Y593833D01*
G01Y593250D02*
X1202267Y593583D01*
X1201767Y593750D01*
X1201183Y593833D01*
X1200600Y593667D01*
X1200100Y593333D01*
X1199767Y592833D01*
X1199600Y592167D01*
X1199767Y591500D01*
X1200100Y591000D01*
X1200600Y590667D01*
X1201183Y590500D01*
X1201767Y590583D01*
X1202267Y590833D01*
X1202600Y591167D01*
G01X1106417Y735500D02*
X1108500Y730500D01*
X1110583Y735500D01*
G01X1113100D02*
X1115100D01*
G01X1114100D02*
Y730500D01*
G01X1113100D02*
X1115100D01*
G01X1118033D02*
Y735500D01*
X1120033D01*
X1120700Y735250D01*
X1121200Y734667D01*
X1121367Y734000D01*
X1121200Y733333D01*
X1120783Y732833D01*
X1120033Y732583D01*
X1118033D01*
G01X1184667Y150367D02*
X1185000Y150617D01*
X1185250Y151033D01*
X1185417Y151617D01*
X1185250Y152117D01*
X1184917Y152450D01*
X1184333Y152700D01*
X1182083D01*
Y147700D01*
X1184833D01*
X1185417Y148033D01*
X1185750Y148533D01*
X1185917Y149117D01*
X1185750Y149700D01*
X1185250Y150200D01*
X1184667Y150367D01*
X1182083D01*
G01X1187517Y147700D02*
X1189600Y152700D01*
X1191683Y147700D01*
G01X1190933Y149450D02*
X1188267D01*
G01X1197033Y152283D02*
X1196533Y152533D01*
X1195950Y152700D01*
X1195283D01*
X1194533Y152450D01*
X1193950Y152033D01*
X1193533Y151533D01*
X1193200Y150700D01*
X1193117Y149950D01*
X1193283Y149200D01*
X1193533Y148700D01*
X1194033Y148200D01*
X1194617Y147867D01*
X1195200Y147700D01*
X1195783D01*
X1196367Y147867D01*
X1196867Y148117D01*
X1197283Y148450D01*
G01X1198967Y147700D02*
Y152700D01*
G01X1202133D02*
X1198967Y149617D01*
G01X1202633Y147700D02*
X1200383Y151033D01*
G01X1210167Y147700D02*
Y152700D01*
X1211833D01*
X1212500Y152450D01*
X1213000Y152117D01*
X1213417Y151617D01*
X1213750Y151033D01*
X1213833Y150200D01*
X1213750Y149367D01*
X1213417Y148783D01*
X1213000Y148283D01*
X1212500Y147950D01*
X1211833Y147700D01*
X1210167D01*
G01X1215933D02*
Y152700D01*
X1218017D01*
X1218683Y152450D01*
X1219100Y152117D01*
X1219267Y151450D01*
X1219100Y150783D01*
X1218600Y150367D01*
X1218017Y150117D01*
X1215933D01*
G01X1218017D02*
X1219267Y147700D01*
G01X1222200Y152700D02*
X1224200D01*
G01X1223200D02*
Y147700D01*
G01X1222200D02*
X1224200D01*
G01X1227133Y152700D02*
Y147700D01*
X1230467D01*
G01X1232733Y152700D02*
Y147700D01*
X1236067D01*
G01X1259900D02*
Y151033D01*
G01Y150117D02*
X1260150Y150533D01*
X1260567Y150867D01*
X1261150Y151033D01*
X1261733Y150867D01*
X1262150Y150533D01*
X1262400Y150117D01*
Y147700D01*
G01Y150117D02*
X1262650Y150533D01*
X1263067Y150867D01*
X1263650Y151033D01*
X1264233Y150867D01*
X1264650Y150533D01*
X1264900Y150033D01*
Y147700D01*
G01X1268000Y151033D02*
Y147700D01*
G01Y152367D02*
X1267833Y152450D01*
Y152617D01*
X1268000Y152700D01*
X1268167Y152617D01*
Y152450D01*
X1268000Y152367D01*
G01X1273600Y147700D02*
Y152700D01*
G01X1277950Y148283D02*
X1278367Y147950D01*
X1278950Y147700D01*
X1279450D01*
X1279950Y147867D01*
X1280283Y148117D01*
X1280450Y148450D01*
X1280367Y148950D01*
X1280033Y149200D01*
X1278533Y149700D01*
X1278200Y150283D01*
X1278367Y150700D01*
X1278700Y150950D01*
X1279200Y151033D01*
X1279700Y150950D01*
X1280200Y150700D01*
G01X1284383Y146033D02*
X1283550Y146867D01*
X1283133Y147700D01*
Y151033D01*
X1283550Y151867D01*
X1284383Y152700D01*
G01X1288483Y147700D02*
Y152700D01*
X1292317Y147700D01*
Y152700D01*
G01X1294333Y147700D02*
Y152700D01*
X1296333D01*
X1297000Y152450D01*
X1297500Y151867D01*
X1297667Y151200D01*
X1297500Y150533D01*
X1297083Y150033D01*
X1296333Y149783D01*
X1294333D01*
G01X1301600Y152700D02*
Y147700D01*
G01X1299683Y152700D02*
X1303517D01*
G01X1305450Y147700D02*
Y152700D01*
G01X1308950D02*
Y147700D01*
G01Y150200D02*
X1305450D01*
G01X1313217Y146033D02*
X1314050Y146867D01*
X1314467Y147700D01*
Y151033D01*
X1314050Y151867D01*
X1313217Y152700D01*
G01X1136167Y157700D02*
Y162700D01*
X1137833D01*
X1138500Y162450D01*
X1139000Y162117D01*
X1139417Y161617D01*
X1139750Y161033D01*
X1139833Y160200D01*
X1139750Y159367D01*
X1139417Y158783D01*
X1139000Y158283D01*
X1138500Y157950D01*
X1137833Y157700D01*
X1136167D01*
G01X1142017Y161867D02*
X1142517Y162367D01*
X1143100Y162617D01*
X1143767Y162700D01*
X1144600Y162533D01*
X1145183Y162117D01*
X1145350Y161617D01*
X1145267Y161117D01*
X1144933Y160700D01*
X1143267Y159867D01*
X1142517Y159283D01*
X1142017Y158450D01*
X1141850Y157700D01*
X1145350D01*
G01X1178750Y315500D02*
Y320500D01*
G01X1182250D02*
Y315500D01*
G01Y318000D02*
X1178750D01*
G01X1186100Y315500D02*
X1185433Y315583D01*
X1184850Y315917D01*
X1184350Y316417D01*
X1184017Y317000D01*
X1183850Y317667D01*
Y318333D01*
X1184017Y319000D01*
X1184350Y319583D01*
X1184850Y320083D01*
X1185433Y320417D01*
X1186100Y320500D01*
X1186767Y320417D01*
X1187350Y320083D01*
X1187850Y319583D01*
X1188183Y319000D01*
X1188350Y318333D01*
Y317667D01*
X1188183Y317000D01*
X1187850Y316417D01*
X1187350Y315917D01*
X1186767Y315583D01*
X1186100Y315500D01*
G01X1190033Y320500D02*
Y315500D01*
X1193367D01*
G01X1198967D02*
X1195633D01*
Y320500D01*
X1198967D01*
G01X1197633Y318083D02*
X1195633D01*
G01X1222800Y315500D02*
Y318833D01*
G01Y317917D02*
X1223050Y318333D01*
X1223467Y318667D01*
X1224050Y318833D01*
X1224633Y318667D01*
X1225050Y318333D01*
X1225300Y317917D01*
Y315500D01*
G01Y317917D02*
X1225550Y318333D01*
X1225967Y318667D01*
X1226550Y318833D01*
X1227133Y318667D01*
X1227550Y318333D01*
X1227800Y317833D01*
Y315500D01*
G01X1230900Y318833D02*
Y315500D01*
G01Y320167D02*
X1230733Y320250D01*
Y320417D01*
X1230900Y320500D01*
X1231067Y320417D01*
Y320250D01*
X1230900Y320167D01*
G01X1236500Y315500D02*
Y320500D01*
G01X1240850Y316083D02*
X1241267Y315750D01*
X1241850Y315500D01*
X1242350D01*
X1242850Y315667D01*
X1243183Y315917D01*
X1243350Y316250D01*
X1243267Y316750D01*
X1242933Y317000D01*
X1241433Y317500D01*
X1241100Y318083D01*
X1241267Y318500D01*
X1241600Y318750D01*
X1242100Y318833D01*
X1242600Y318750D01*
X1243100Y318500D01*
G01X1247283Y313833D02*
X1246450Y314667D01*
X1246033Y315500D01*
Y318833D01*
X1246450Y319667D01*
X1247283Y320500D01*
G01X1251633Y315500D02*
Y320500D01*
X1253633D01*
X1254300Y320250D01*
X1254800Y319667D01*
X1254967Y319000D01*
X1254800Y318333D01*
X1254383Y317833D01*
X1253633Y317583D01*
X1251633D01*
G01X1258900Y320500D02*
Y315500D01*
G01X1256983Y320500D02*
X1260817D01*
G01X1262750Y315500D02*
Y320500D01*
G01X1266250D02*
Y315500D01*
G01Y318000D02*
X1262750D01*
G01X1270517Y313833D02*
X1271350Y314667D01*
X1271767Y315500D01*
Y318833D01*
X1271350Y319667D01*
X1270517Y320500D01*
G01X1135167Y315700D02*
Y320700D01*
X1136833D01*
X1137500Y320450D01*
X1138000Y320117D01*
X1138417Y319617D01*
X1138750Y319033D01*
X1138833Y318200D01*
X1138750Y317367D01*
X1138417Y316783D01*
X1138000Y316283D01*
X1137500Y315950D01*
X1136833Y315700D01*
X1135167D01*
G01X1142600D02*
Y320700D01*
X1141600Y319700D01*
G01Y315700D02*
X1143600D01*
G01X1136833Y619917D02*
X1136250Y620250D01*
X1135750Y620333D01*
X1135083Y620167D01*
X1134583Y619833D01*
X1134250Y619250D01*
X1134167Y618667D01*
X1134250Y618083D01*
X1134583Y617583D01*
X1135083Y617167D01*
X1135750Y617000D01*
X1136333Y617167D01*
X1136833Y617500D01*
G01X1141100Y617000D02*
X1140600Y617083D01*
X1140100Y617417D01*
X1139767Y618000D01*
X1139600Y618667D01*
X1139767Y619333D01*
X1140100Y619917D01*
X1140600Y620250D01*
X1141100Y620333D01*
X1141600Y620250D01*
X1142100Y619917D01*
X1142433Y619333D01*
X1142517Y618667D01*
X1142433Y618000D01*
X1142100Y617417D01*
X1141600Y617083D01*
X1141100Y617000D01*
G01X1145200Y615333D02*
Y620333D01*
G01Y619583D02*
X1145617Y620000D01*
X1146033Y620250D01*
X1146700Y620333D01*
X1147283Y620250D01*
X1147867Y619833D01*
X1148117Y619250D01*
X1148200Y618667D01*
X1148117Y618083D01*
X1147867Y617500D01*
X1147367Y617167D01*
X1146700Y617000D01*
X1146117Y617083D01*
X1145533Y617333D01*
X1145200Y617667D01*
G01X1150800Y615333D02*
Y620333D01*
G01Y619583D02*
X1151217Y620000D01*
X1151633Y620250D01*
X1152300Y620333D01*
X1152883Y620250D01*
X1153467Y619833D01*
X1153717Y619250D01*
X1153800Y618667D01*
X1153717Y618083D01*
X1153467Y617500D01*
X1152967Y617167D01*
X1152300Y617000D01*
X1151717Y617083D01*
X1151133Y617333D01*
X1150800Y617667D01*
G01X1156650Y619250D02*
X1159317D01*
X1159067Y619833D01*
X1158650Y620167D01*
X1158067Y620333D01*
X1157483Y620250D01*
X1156983Y620000D01*
X1156650Y619417D01*
X1156483Y618917D01*
Y618417D01*
X1156650Y617917D01*
X1157067Y617417D01*
X1157567Y617083D01*
X1158150Y617000D01*
X1158733Y617167D01*
X1159317Y617667D01*
G01X1162333Y617000D02*
Y620333D01*
G01Y619667D02*
X1162750Y620000D01*
X1163167Y620250D01*
X1163750Y620333D01*
X1164167Y620250D01*
X1164667Y620000D01*
G01X1180417Y734500D02*
X1182500Y729500D01*
X1184583Y734500D01*
G01X1188100Y729500D02*
X1187433Y729583D01*
X1186850Y729917D01*
X1186350Y730417D01*
X1186017Y731000D01*
X1185850Y731667D01*
Y732333D01*
X1186017Y733000D01*
X1186350Y733583D01*
X1186850Y734083D01*
X1187433Y734417D01*
X1188100Y734500D01*
X1188767Y734417D01*
X1189350Y734083D01*
X1189850Y733583D01*
X1190183Y733000D01*
X1190350Y732333D01*
Y731667D01*
X1190183Y731000D01*
X1189850Y730417D01*
X1189350Y729917D01*
X1188767Y729583D01*
X1188100Y729500D01*
G01X1192033D02*
Y734500D01*
X1194033D01*
X1194700Y734250D01*
X1195200Y733667D01*
X1195367Y733000D01*
X1195200Y732333D01*
X1194783Y731833D01*
X1194033Y731583D01*
X1192033D01*
G01X1210333Y218700D02*
Y213700D01*
X1213667D01*
G01X1216350Y217033D02*
X1218850Y213700D01*
G01Y217033D02*
X1216350Y213700D01*
G01X1218250Y281583D02*
X1218667Y281250D01*
X1219250Y281000D01*
X1219750D01*
X1220250Y281167D01*
X1220583Y281417D01*
X1220750Y281750D01*
X1220667Y282250D01*
X1220333Y282500D01*
X1218833Y283000D01*
X1218500Y283583D01*
X1218667Y284000D01*
X1219000Y284250D01*
X1219500Y284333D01*
X1220000Y284250D01*
X1220500Y284000D01*
G01X1225100Y286000D02*
Y281000D01*
G01X1223933Y284333D02*
X1226267D01*
G01X1229283D02*
Y282000D01*
X1229617Y281417D01*
X1230117Y281083D01*
X1230700Y281000D01*
X1231283Y281083D01*
X1231783Y281417D01*
X1232117Y282000D01*
G01Y281000D02*
Y284333D01*
G01X1234800Y281000D02*
Y286000D01*
G01Y283500D02*
X1235217Y284000D01*
X1235717Y284250D01*
X1236217Y284333D01*
X1236967Y284167D01*
X1237467Y283833D01*
X1237800Y283250D01*
Y282583D01*
X1237633Y281917D01*
X1237300Y281417D01*
X1236717Y281083D01*
X1236217Y281000D01*
X1235717Y281083D01*
X1235217Y281333D01*
X1234800Y281750D01*
G01X1247500Y281000D02*
Y286000D01*
G01X1251850Y283250D02*
X1254517D01*
X1254267Y283833D01*
X1253850Y284167D01*
X1253267Y284333D01*
X1252683Y284250D01*
X1252183Y284000D01*
X1251850Y283417D01*
X1251683Y282917D01*
Y282417D01*
X1251850Y281917D01*
X1252267Y281417D01*
X1252767Y281083D01*
X1253350Y281000D01*
X1253933Y281167D01*
X1254517Y281667D01*
G01X1257283Y281000D02*
Y284333D01*
G01Y283500D02*
X1257617Y283917D01*
X1258117Y284250D01*
X1258783Y284333D01*
X1259367Y284250D01*
X1259867Y283917D01*
X1260117Y283333D01*
Y281000D01*
G01X1263133Y279750D02*
X1263717Y279417D01*
X1264383Y279333D01*
X1264967Y279417D01*
X1265467Y279833D01*
X1265800Y280417D01*
Y284333D01*
G01Y283667D02*
X1265467Y284000D01*
X1264967Y284250D01*
X1264383Y284333D01*
X1263717Y284167D01*
X1263300Y283833D01*
X1262967Y283250D01*
X1262800Y282667D01*
X1262883Y282167D01*
X1263217Y281583D01*
X1263717Y281167D01*
X1264383Y281000D01*
X1264883Y281083D01*
X1265467Y281417D01*
X1265800Y281750D01*
G01X1269900Y286000D02*
Y281000D01*
G01X1268733Y284333D02*
X1271067D01*
G01X1274083Y281000D02*
Y286000D01*
G01Y283583D02*
X1274500Y284000D01*
X1274917Y284250D01*
X1275583Y284333D01*
X1276083Y284250D01*
X1276667Y283917D01*
X1276917Y283417D01*
Y281000D01*
G01X1280017Y281917D02*
X1282183D01*
G01Y283417D02*
X1280017D01*
G01X1285117Y283083D02*
X1285700Y283667D01*
X1286200Y284000D01*
X1286867Y284167D01*
X1287450Y284000D01*
X1287867Y283667D01*
X1288200Y283167D01*
X1288283Y282583D01*
X1288200Y282083D01*
X1287867Y281583D01*
X1287367Y281167D01*
X1286783Y281000D01*
X1286117Y281167D01*
X1285533Y281667D01*
X1285200Y282417D01*
X1285117Y283250D01*
X1285283Y284333D01*
X1285533Y284917D01*
X1285950Y285500D01*
X1286533Y285917D01*
X1287117Y286000D01*
X1287700Y285833D01*
X1288117Y285417D01*
G01X1291383Y282667D02*
X1293383D01*
G01X1292300Y283750D02*
Y281583D01*
G01X1296400Y280833D02*
X1299400Y286000D01*
G01X1302417Y282667D02*
X1304583D01*
G01X1307267Y281750D02*
X1307767Y281333D01*
X1308350Y281083D01*
X1309100Y281000D01*
X1309850Y281167D01*
X1310433Y281500D01*
X1310850Y282083D01*
X1310933Y282750D01*
X1310767Y283417D01*
X1310350Y283833D01*
X1309767Y284167D01*
X1309183Y284250D01*
X1308600Y284167D01*
X1307850Y283833D01*
X1308100Y286000D01*
X1310350D01*
G01X1312200Y281000D02*
Y284333D01*
G01Y283417D02*
X1312450Y283833D01*
X1312867Y284167D01*
X1313450Y284333D01*
X1314033Y284167D01*
X1314450Y283833D01*
X1314700Y283417D01*
Y281000D01*
G01Y283417D02*
X1314950Y283833D01*
X1315367Y284167D01*
X1315950Y284333D01*
X1316533Y284167D01*
X1316950Y283833D01*
X1317200Y283333D01*
Y281000D01*
G01X1320300Y284333D02*
Y281000D01*
G01Y285667D02*
X1320133Y285750D01*
Y285917D01*
X1320300Y286000D01*
X1320467Y285917D01*
Y285750D01*
X1320300Y285667D01*
G01X1325900Y281000D02*
Y286000D01*
G01X1207333Y260500D02*
Y255500D01*
X1210667D01*
G01X1213183D02*
Y258833D01*
G01Y258000D02*
X1213517Y258417D01*
X1214017Y258750D01*
X1214683Y258833D01*
X1215267Y258750D01*
X1215767Y258417D01*
X1216017Y257833D01*
Y255500D01*
G01X1242793Y785443D02*
X1241960Y786277D01*
X1241543Y787110D01*
Y790443D01*
X1241960Y791277D01*
X1242793Y792110D01*
G01X1248810Y787110D02*
Y792110D01*
X1247810Y791110D01*
G01Y787110D02*
X1249810D01*
G01X1254410Y786943D02*
X1254243Y787027D01*
Y787193D01*
X1254410Y787277D01*
X1254577Y787193D01*
Y787027D01*
X1254410Y786943D01*
G01X1258427Y791277D02*
X1258927Y791777D01*
X1259510Y792027D01*
X1260177Y792110D01*
X1261010Y791943D01*
X1261593Y791527D01*
X1261760Y791027D01*
X1261677Y790527D01*
X1261343Y790110D01*
X1259677Y789277D01*
X1258927Y788693D01*
X1258427Y787860D01*
X1258260Y787110D01*
X1261760D01*
G01X1263110D02*
Y790443D01*
G01Y789527D02*
X1263360Y789943D01*
X1263777Y790277D01*
X1264360Y790443D01*
X1264943Y790277D01*
X1265360Y789943D01*
X1265610Y789527D01*
Y787110D01*
G01Y789527D02*
X1265860Y789943D01*
X1266277Y790277D01*
X1266860Y790443D01*
X1267443Y790277D01*
X1267860Y789943D01*
X1268110Y789443D01*
Y787110D01*
G01X1268710D02*
Y790443D01*
G01Y789527D02*
X1268960Y789943D01*
X1269377Y790277D01*
X1269960Y790443D01*
X1270543Y790277D01*
X1270960Y789943D01*
X1271210Y789527D01*
Y787110D01*
G01Y789527D02*
X1271460Y789943D01*
X1271877Y790277D01*
X1272460Y790443D01*
X1273043Y790277D01*
X1273460Y789943D01*
X1273710Y789443D01*
Y787110D01*
G01X1280243D02*
Y792110D01*
X1282410Y787943D01*
X1284577Y792110D01*
Y787110D01*
G01X1289510D02*
Y790443D01*
G01Y789860D02*
X1289177Y790193D01*
X1288677Y790360D01*
X1288093Y790443D01*
X1287510Y790277D01*
X1287010Y789943D01*
X1286677Y789443D01*
X1286510Y788777D01*
X1286677Y788110D01*
X1287010Y787610D01*
X1287510Y787277D01*
X1288093Y787110D01*
X1288677Y787193D01*
X1289177Y787443D01*
X1289510Y787777D01*
G01X1292360Y790443D02*
X1294860Y787110D01*
G01Y790443D02*
X1292360Y787110D01*
G01X1299627Y785443D02*
X1300460Y786277D01*
X1300877Y787110D01*
Y790443D01*
X1300460Y791277D01*
X1299627Y792110D01*
G01X1244877Y797230D02*
X1241543Y798897D01*
X1244877Y800563D01*
G01X1247727Y798147D02*
X1249893D01*
G01Y799647D02*
X1247727D01*
G01X1254410Y802230D02*
X1253743Y802063D01*
X1253243Y801647D01*
X1252910Y801147D01*
X1252660Y800480D01*
X1252577Y799730D01*
X1252660Y798980D01*
X1252910Y798313D01*
X1253243Y797813D01*
X1253743Y797397D01*
X1254410Y797230D01*
X1255077Y797397D01*
X1255577Y797813D01*
X1255910Y798313D01*
X1256160Y798980D01*
X1256243Y799730D01*
X1256160Y800480D01*
X1255910Y801147D01*
X1255577Y801647D01*
X1255077Y802063D01*
X1254410Y802230D01*
G01X1260010Y797063D02*
X1259843Y797147D01*
Y797313D01*
X1260010Y797397D01*
X1260177Y797313D01*
Y797147D01*
X1260010Y797063D01*
G01X1265443Y797230D02*
X1265610Y798313D01*
X1265860Y799230D01*
X1266193Y800063D01*
X1266610Y800980D01*
X1267277Y802230D01*
X1263943D01*
G01X1269377Y797980D02*
X1269877Y797563D01*
X1270460Y797313D01*
X1271210Y797230D01*
X1271960Y797397D01*
X1272543Y797730D01*
X1272960Y798313D01*
X1273043Y798980D01*
X1272877Y799647D01*
X1272460Y800063D01*
X1271877Y800397D01*
X1271293Y800480D01*
X1270710Y800397D01*
X1269960Y800063D01*
X1270210Y802230D01*
X1272460D01*
G01X1275310Y797063D02*
X1278310Y802230D01*
G01X1275310D02*
X1274810Y802063D01*
X1274560Y801813D01*
X1274393Y801313D01*
X1274560Y800813D01*
X1274810Y800563D01*
X1275310Y800397D01*
X1275810Y800563D01*
X1276060Y800813D01*
X1276227Y801313D01*
X1276060Y801813D01*
X1275810Y802063D01*
X1275310Y802230D01*
G01X1278310Y798897D02*
X1277810Y798730D01*
X1277560Y798480D01*
X1277393Y797980D01*
X1277560Y797480D01*
X1277810Y797230D01*
X1278310Y797063D01*
X1278810Y797230D01*
X1279060Y797480D01*
X1279227Y797980D01*
X1279060Y798480D01*
X1278810Y798730D01*
X1278310Y798897D01*
G01X1234540Y850500D02*
Y782000D01*
G01X1241083Y841667D02*
X1243083D01*
G01X1242000Y842750D02*
Y840583D01*
G01X1246100Y839833D02*
X1249100Y845000D01*
G01X1252117Y841667D02*
X1254283D01*
G01X1256967Y840750D02*
X1257467Y840333D01*
X1258050Y840083D01*
X1258800Y840000D01*
X1259550Y840167D01*
X1260133Y840500D01*
X1260550Y841083D01*
X1260633Y841750D01*
X1260467Y842417D01*
X1260050Y842833D01*
X1259467Y843167D01*
X1258883Y843250D01*
X1258300Y843167D01*
X1257550Y842833D01*
X1257800Y845000D01*
X1260050D01*
G01X1261900Y840000D02*
Y843333D01*
G01Y842417D02*
X1262150Y842833D01*
X1262567Y843167D01*
X1263150Y843333D01*
X1263733Y843167D01*
X1264150Y842833D01*
X1264400Y842417D01*
Y840000D01*
G01Y842417D02*
X1264650Y842833D01*
X1265067Y843167D01*
X1265650Y843333D01*
X1266233Y843167D01*
X1266650Y842833D01*
X1266900Y842333D01*
Y840000D01*
G01X1270000Y843333D02*
Y840000D01*
G01Y844667D02*
X1269833Y844750D01*
Y844917D01*
X1270000Y845000D01*
X1270167Y844917D01*
Y844750D01*
X1270000Y844667D01*
G01X1275600Y840000D02*
Y845000D01*
G01X1241083Y826667D02*
X1243083D01*
G01X1242000Y827750D02*
Y825583D01*
G01X1246100Y824833D02*
X1249100Y830000D01*
G01X1252117Y826667D02*
X1254283D01*
G01X1256967Y825750D02*
X1257467Y825333D01*
X1258050Y825083D01*
X1258800Y825000D01*
X1259550Y825167D01*
X1260133Y825500D01*
X1260550Y826083D01*
X1260633Y826750D01*
X1260467Y827417D01*
X1260050Y827833D01*
X1259467Y828167D01*
X1258883Y828250D01*
X1258300Y828167D01*
X1257550Y827833D01*
X1257800Y830000D01*
X1260050D01*
G01X1261900Y825000D02*
Y828333D01*
G01Y827417D02*
X1262150Y827833D01*
X1262567Y828167D01*
X1263150Y828333D01*
X1263733Y828167D01*
X1264150Y827833D01*
X1264400Y827417D01*
Y825000D01*
G01Y827417D02*
X1264650Y827833D01*
X1265067Y828167D01*
X1265650Y828333D01*
X1266233Y828167D01*
X1266650Y827833D01*
X1266900Y827333D01*
Y825000D01*
G01X1270000Y828333D02*
Y825000D01*
G01Y829667D02*
X1269833Y829750D01*
Y829917D01*
X1270000Y830000D01*
X1270167Y829917D01*
Y829750D01*
X1270000Y829667D01*
G01X1275600Y825000D02*
Y830000D01*
G01X1241083Y811667D02*
X1243083D01*
G01X1242000Y812750D02*
Y810583D01*
G01X1246100Y809833D02*
X1249100Y815000D01*
G01X1252117Y811667D02*
X1254283D01*
G01X1257217Y814167D02*
X1257717Y814667D01*
X1258300Y814917D01*
X1258967Y815000D01*
X1259800Y814833D01*
X1260383Y814417D01*
X1260550Y813917D01*
X1260467Y813417D01*
X1260133Y813000D01*
X1258467Y812167D01*
X1257717Y811583D01*
X1257217Y810750D01*
X1257050Y810000D01*
X1260550D01*
G01X1261900D02*
Y813333D01*
G01Y812417D02*
X1262150Y812833D01*
X1262567Y813167D01*
X1263150Y813333D01*
X1263733Y813167D01*
X1264150Y812833D01*
X1264400Y812417D01*
Y810000D01*
G01Y812417D02*
X1264650Y812833D01*
X1265067Y813167D01*
X1265650Y813333D01*
X1266233Y813167D01*
X1266650Y812833D01*
X1266900Y812333D01*
Y810000D01*
G01X1270000Y813333D02*
Y810000D01*
G01Y814667D02*
X1269833Y814750D01*
Y814917D01*
X1270000Y815000D01*
X1270167Y814917D01*
Y814750D01*
X1270000Y814667D01*
G01X1275600Y810000D02*
Y815000D01*
G01X1343000Y850610D02*
Y782110D01*
G54D12*
G01X865852Y712354D02*
Y635354D01*
G01X872727Y628479D02*
Y721979D01*
G01X857602Y628479D02*
X872727D01*
G01X857602Y635354D02*
Y628479D01*
G01X865852Y635354D02*
X843852D01*
G01D02*
Y712354D01*
G01X857602Y721979D02*
Y715104D01*
G01X872727Y721979D02*
X857602D01*
G01X843852Y712354D02*
X865852D01*
G01X934602Y628479D02*
X949727D01*
G01X934602Y635354D02*
Y628479D01*
G01X942852Y635354D02*
Y712354D01*
G01X898852D02*
Y635354D01*
G01D02*
X942852D01*
G01X907102Y628479D02*
Y635354D01*
G01X891977Y628479D02*
X907102D01*
G01X891977Y721979D02*
Y628479D01*
G01X934602Y721979D02*
Y715104D01*
G01X949727Y721979D02*
X934602D01*
G01X942852Y712354D02*
X898852D01*
G01X907102Y715104D02*
Y721979D01*
G01D02*
X891977D01*
G01X984102Y628479D02*
Y635354D01*
G01X975852Y712354D02*
Y635354D01*
G01D02*
X1019852D01*
G01X968977Y628479D02*
X984102D01*
G01X968977Y721979D02*
Y628479D01*
G01X949727D02*
Y721979D01*
G01X984102Y715104D02*
Y721979D01*
G01X1019852Y712354D02*
X975852D01*
G01X984102Y721979D02*
X968977D01*
G01X1061102Y628479D02*
Y635354D01*
G01X1045977Y628479D02*
X1061102D01*
G01X1045977Y719229D02*
Y628479D01*
G01X1052852Y712354D02*
Y635354D01*
G01D02*
X1096852D01*
G01X1026727Y628479D02*
Y719229D01*
G01X1019852Y635354D02*
Y712354D01*
G01X1011602Y628479D02*
X1026727D01*
G01X1011602Y635354D02*
Y628479D01*
G01X1061102Y719229D02*
X1045977D01*
G01X1061102Y712354D02*
Y719229D01*
G01X1096852Y712354D02*
X1052852D01*
G01X1011602Y719229D02*
Y712354D01*
G01X1026727Y719229D02*
X1011602D01*
G01X1129852Y712354D02*
Y635354D01*
G01D02*
X1173852D01*
G01X1122977Y628479D02*
X1138102D01*
G01X1096852Y635354D02*
Y712354D01*
G01X1088602Y628479D02*
X1122977D01*
G01X1088602Y635354D02*
Y628479D01*
G01X1173852Y712354D02*
X1129852D01*
G01X1138102Y719229D02*
X1103727D01*
G01X1088602D02*
Y712354D01*
G01X1103727Y719229D02*
X1088602D01*
G01X1180727Y628479D02*
Y719229D01*
G01X1165602Y628479D02*
X1180727D01*
G01X1165602Y635354D02*
Y628479D01*
G01X1173852Y635354D02*
Y712354D01*
G01X1138102Y628479D02*
Y635354D01*
G01X1165602Y719229D02*
Y712354D01*
G01X1180727Y719229D02*
X1165602D01*
G01X1138102Y712354D02*
Y719229D01*
G01X1250852Y635354D02*
Y712354D01*
G01X1215102Y628479D02*
Y635354D01*
G01X1206852Y712354D02*
Y635354D01*
G01D02*
X1250852D01*
G01X1199977Y628479D02*
X1215102D01*
G01X1199977Y719229D02*
Y628479D01*
G01X1215102Y712354D02*
Y719229D01*
G01X1250852Y712354D02*
X1206852D01*
G01X1215102Y719229D02*
X1199977D01*
G54D13*
G01X303090Y319830D02*
Y303830D01*
G01X292090Y340830D02*
Y357830D01*
G01X341590Y319830D02*
Y303830D01*
G01X352590Y340830D02*
Y357830D01*
G01X356482Y330153D02*
X352452Y324663D01*
X356652Y324643D01*
G01X345680Y327680D02*
G02X350362Y319860I-4190J-7820D01*
G01X348190Y321780D01*
X351420Y321950D01*
X350460Y319850D01*
G01X439562Y301543D02*
X435532Y296053D01*
X439732Y296033D01*
G54D14*
G01X891702Y710347D02*
X883070Y718978D01*
G01X891702Y708014D02*
X880607Y719107D01*
G01X881854Y681089D02*
X891702Y690937D01*
G01X856340Y725829D02*
X872925D01*
G01X891702Y705679D02*
X876553Y720829D01*
G01X874327Y723054D02*
X871552Y725829D01*
G01X891702Y703346D02*
X869219Y725829D01*
G01X891702Y701013D02*
X866886Y725829D01*
G01X891702Y698679D02*
X873002Y717379D01*
G01X871152Y719229D02*
X864552Y725829D01*
G01X891702Y696346D02*
X873002Y715046D01*
G01X868819Y719229D02*
X862219Y725829D01*
G01X891702Y694013D02*
X873002Y712712D01*
G01X866485Y719229D02*
X859885Y725829D01*
G01X891702Y691679D02*
X873002Y710379D01*
G01X864151Y719229D02*
X857551Y725829D01*
G01X891702Y689346D02*
X873002Y708046D01*
G01X861818Y719229D02*
X855779Y725267D01*
G01X891702Y687012D02*
X873002Y705711D01*
G01X859485Y719229D02*
X854613Y724101D01*
G01X891702Y684678D02*
X873002Y703378D01*
G01X857327Y719053D02*
X853752Y722628D01*
G01X891702Y682345D02*
X873002Y701045D01*
G01X857327Y716720D02*
X853752Y720295D01*
G01X891702Y680012D02*
X873002Y698711D01*
G01X857327Y714387D02*
X853752Y717961D01*
G01X856750Y712629D02*
X853752Y715628D01*
G01X854417Y712629D02*
X853752Y713295D01*
G01X873002Y690905D02*
X891702Y709604D01*
G01X873002Y693238D02*
X891702Y711938D01*
G01X873002Y695572D02*
X891702Y714272D01*
G01X873002Y697906D02*
X891702Y716605D01*
G01X873002Y700239D02*
X891702Y718939D01*
G01X873002Y702572D02*
X896258Y725829D01*
G01X873002Y704906D02*
X893925Y725829D01*
G01X873002Y707239D02*
X885106Y719344D01*
G01X873002Y709572D02*
X882382Y718952D01*
G01X873002Y711907D02*
X880270Y719174D01*
G01X873002Y714240D02*
X878496Y719734D01*
G01X873002Y716573D02*
X876971Y720542D01*
G01X873002Y718907D02*
X875655Y721560D01*
G01X870991Y719229D02*
X874536Y722775D01*
G01X868658Y719229D02*
X873618Y724189D01*
G01X866324Y719229D02*
X872924Y725829D01*
G01X863991Y719229D02*
X870591Y725829D01*
G01X855058Y712629D02*
X857327Y714899D01*
G01X861658Y719229D02*
X868258Y725829D01*
G01X853752Y713657D02*
X857327Y717232D01*
G01X859323Y719229D02*
X865923Y725829D01*
G01X853752Y715991D02*
X863590Y725829D01*
G01X853752Y718324D02*
X861257Y725829D01*
G01X853752Y720657D02*
X858923Y725829D01*
G01X853752Y722991D02*
X856590Y725829D01*
G01X872925D02*
G03X891779I9427J3024D01*
G01X853752Y723240D02*
X856340Y725829D01*
G01X853752Y712629D02*
Y723240D01*
G01X857327Y712629D02*
X853752D01*
G01X857327Y719504D02*
Y712629D01*
G01X857602Y719229D02*
X857327Y719504D01*
G01X873002Y719229D02*
X857602D01*
G01X891702Y677678D02*
X873002Y696378D01*
G01X887198Y679848D02*
X873002Y694045D01*
G01X883703Y681010D02*
X873002Y691711D01*
G01X881330Y681049D02*
X873002Y689377D01*
G01X879392Y680653D02*
X873002Y687044D01*
G01X877738Y679974D02*
X873002Y684711D01*
G01X876310Y679069D02*
X873002Y682377D01*
G01X875080Y677966D02*
X873002Y680044D01*
G01X874045Y676668D02*
X873002Y677711D01*
G01X873215Y675163D02*
X873002Y675377D01*
G01X878929Y680497D02*
X891702Y693270D01*
G01X873002Y676905D02*
X891702Y695603D01*
G01X873002Y679238D02*
X891702Y697938D01*
G01X873002Y681571D02*
X891702Y700271D01*
G01X873002Y683905D02*
X891702Y702604D01*
G01X873002Y686238D02*
X891702Y704938D01*
G01X873002Y688571D02*
X891702Y707271D01*
G01X873002Y674644D02*
Y719229D01*
G01Y674645D02*
Y674644D01*
G01X891701Y674645D02*
G03X873003I-9349J-3541D01*
G01X947085Y624629D02*
X943510Y628204D01*
G01X934327Y635053D02*
X934300Y635079D01*
G01X934327Y632720D02*
X931967Y635079D01*
G01X934327Y630387D02*
X930752Y633961D01*
G01X933037Y624933D02*
X936307Y628204D01*
G01X931869Y626100D02*
X934327Y628556D01*
G01X930752Y627315D02*
X934327Y630890D01*
G01X930752Y629649D02*
X934327Y633224D01*
G01X930752Y631983D02*
X933848Y635079D01*
G01X930752Y634316D02*
X931515Y635079D01*
G01X934327Y628204D02*
X950002D01*
G01X934327Y635079D02*
Y628204D01*
G01X930752Y635079D02*
X934327D01*
G01X930752Y627218D02*
Y635079D01*
G01X944750Y624629D02*
X941175Y628204D01*
G01X942417Y624629D02*
X938842Y628204D01*
G01X940084Y624629D02*
X936509Y628204D01*
G01X937750Y624629D02*
X930752Y631627D01*
G01X935417Y624629D02*
X930752Y629294D01*
G01X944400Y624629D02*
X947975Y628204D01*
G01X942066Y624629D02*
X945640Y628203D01*
G01X939733Y624629D02*
X943307Y628204D01*
G01X937399Y624629D02*
X940974Y628203D01*
G01X935066Y624629D02*
X938640Y628203D01*
G01X985362Y624629D02*
X933340D01*
G01D02*
X930752Y627218D01*
G01X968702Y701017D02*
X943889Y725829D01*
G01X947881Y719504D02*
X941556Y725829D01*
G01X945548Y719504D02*
X939223Y725829D01*
G01X943214Y719504D02*
X936889Y725829D01*
G01X940881Y719504D02*
X934556Y725829D01*
G01X938546Y719504D02*
X932223Y725829D01*
G01X936213Y719504D02*
X929888Y725829D01*
G01X934327Y719058D02*
X927555Y725829D01*
G01X934327Y716725D02*
X925222Y725829D01*
G01X934327Y714390D02*
X922888Y725829D01*
G01X933755Y712629D02*
X920555Y725829D01*
G01X931422Y712629D02*
X918222Y725829D01*
G01X929088Y712629D02*
X915888Y725829D01*
G01X926754Y712629D02*
X913554Y725829D01*
G01X943603Y719504D02*
X949925Y725826D01*
G01X941270Y719504D02*
X947595Y725829D01*
G01X932061Y712629D02*
X934327Y714894D01*
G01X938936Y719504D02*
X945261Y725829D01*
G01X929728Y712629D02*
X934327Y717228D01*
G01X936603Y719504D02*
X942928Y725829D01*
G01X927395Y712629D02*
X940595Y725829D01*
G01X925062Y712629D02*
X938260Y725829D01*
G01X922727Y712629D02*
X935927Y725829D01*
G01X920394Y712629D02*
X933594Y725829D01*
G01X918061Y712629D02*
X931260Y725829D01*
G01X915727Y712629D02*
X928927Y725829D01*
G01X913394Y712629D02*
X926593Y725828D01*
G01X934327Y719504D02*
Y712629D01*
G01X950002Y719504D02*
X934327D01*
G01X924420Y712629D02*
X911221Y725829D01*
G01X891779D02*
X949925D01*
G01X922087Y712629D02*
X908887Y725829D01*
G01X919754Y712629D02*
X906554Y725829D01*
G01X917420Y712629D02*
X904221Y725829D01*
G01X915087Y712629D02*
X901887Y725829D01*
G01X912754Y712629D02*
X907377Y718006D01*
G01X905840Y719543D02*
X899554Y725829D01*
G01X910421Y712629D02*
X907377Y715673D01*
G01X903507Y719543D02*
X897221Y725829D01*
G01X908086Y712629D02*
X907377Y713339D01*
G01X901173Y719543D02*
X894886Y725829D01*
G01X898840Y719543D02*
X892553Y725829D01*
G01X896507Y719543D02*
X891342Y724707D01*
G01X894172Y719543D02*
X890494Y723221D01*
G01X891927Y719455D02*
X889440Y721942D01*
G01X891702Y717347D02*
X888191Y720857D01*
G01X891702Y715014D02*
X886738Y719977D01*
G01X891702Y712680D02*
X885053Y719328D01*
G01X911061Y712629D02*
X924260Y725829D01*
G01X908727Y712629D02*
X921927Y725829D01*
G01X907377Y713613D02*
X919592Y725828D01*
G01X907377Y715946D02*
X917259Y725829D01*
G01X907377Y718280D02*
X914926Y725829D01*
G01X906307Y719543D02*
X912592Y725828D01*
G01X903972Y719543D02*
X910259Y725829D01*
G01X901639Y719543D02*
X907926Y725829D01*
G01X899306Y719543D02*
X905593Y725829D01*
G01X896972Y719543D02*
X903258Y725829D01*
G01X894639Y719543D02*
X900925Y725829D01*
G01X892306Y719543D02*
X898592Y725829D01*
G01X892015Y719543D02*
X891702Y719229D01*
G01X907157Y719543D02*
X892015D01*
G01X907377Y719504D02*
X907157Y719543D01*
G01X907377Y712629D02*
Y719504D01*
G01X934327Y712629D02*
X907377D01*
G01X891702Y675345D02*
X891096Y675951D01*
G01X890957Y676193D02*
X891702Y676936D01*
G01X889988Y677557D02*
X891702Y679270D01*
G01X888823Y678725D02*
X891702Y681604D01*
G01X887462Y679697D02*
X891702Y683937D01*
G01X885887Y680455D02*
X891702Y686270D01*
G01X884054Y680956D02*
X891702Y688604D01*
G01Y674644D02*
X891701Y674645D01*
G01X891702Y719229D02*
Y674644D01*
G01X987952Y632764D02*
X985637Y635078D01*
G01X987952Y630431D02*
X984377Y634006D01*
G01X987952Y628098D02*
X984377Y631673D01*
G01X987225Y626490D02*
X984377Y629338D01*
G01X986058Y625324D02*
X983178Y628204D01*
G01X984377Y629605D02*
X987952Y633180D01*
G01X984377Y631938D02*
X987517Y635079D01*
G01X984377Y634272D02*
X985184Y635079D01*
G01X987952D02*
Y627218D01*
G01X984377Y635079D02*
X987952D01*
G01X984377Y628204D02*
Y635079D01*
G01X984420Y624629D02*
X980845Y628204D01*
G01X984069Y624629D02*
X987952Y628512D01*
G01X981735Y624629D02*
X987952Y630845D01*
G01X979402Y624629D02*
X982977Y628204D01*
G01X987952Y627218D02*
X985362Y624629D01*
G01X968702Y670682D02*
X950002Y689382D01*
G01X968702Y668349D02*
X950002Y687048D01*
G01X968702Y666015D02*
X950002Y684715D01*
G01X968702Y663681D02*
X950002Y682381D01*
G01X968702Y661348D02*
X950002Y680047D01*
G01X968702Y659014D02*
X950002Y677714D01*
G01Y658233D02*
X968702Y676932D01*
G01X950002Y660566D02*
X968702Y679266D01*
G01X950002Y662899D02*
X968702Y681599D01*
G01X950002Y665234D02*
X968702Y683932D01*
G01X950002Y667567D02*
X968702Y686267D01*
G01X950002Y669900D02*
X968702Y688600D01*
G01X950002Y672234D02*
X968702Y690933D01*
G01Y656681D02*
X950002Y675381D01*
G01X968702Y654348D02*
X950002Y673048D01*
G01X968702Y652014D02*
X950002Y670714D01*
G01X968702Y649681D02*
X950002Y668381D01*
G01X968702Y647348D02*
X950002Y666048D01*
G01X968702Y645013D02*
X950002Y663713D01*
G01X968702Y642680D02*
X950002Y661380D01*
G01X968702Y640347D02*
X950002Y659047D01*
G01X982086Y624629D02*
X978512Y628204D01*
G01X968702Y638014D02*
X950002Y656713D01*
G01X979752Y624629D02*
X976177Y628204D01*
G01X968702Y635680D02*
X950002Y654380D01*
G01X968702Y633347D02*
X950002Y652047D01*
G01X968702Y631014D02*
X950002Y649713D01*
G01X968702Y628679D02*
X950002Y647379D01*
G01Y630232D02*
X968702Y648932D01*
G01X950002Y632565D02*
X968702Y651265D01*
G01X950002Y634898D02*
X968702Y653598D01*
G01X950002Y637232D02*
X968702Y655931D01*
G01X950002Y639565D02*
X968702Y658265D01*
G01X950002Y641898D02*
X968702Y660598D01*
G01X950002Y644232D02*
X968702Y662931D01*
G01X950002Y646565D02*
X968702Y665265D01*
G01X950002Y648899D02*
X968702Y667599D01*
G01X950002Y651233D02*
X968702Y669932D01*
G01X950002Y653566D02*
X968702Y672266D01*
G01X950002Y655899D02*
X968702Y674599D01*
G01Y628204D02*
X984377D01*
G01X968702Y719504D02*
Y628204D01*
G01X950002D02*
Y719504D01*
G01X977419Y624629D02*
X973844Y628204D01*
G01X975085Y624629D02*
X971511Y628204D01*
G01X972752Y624629D02*
X969177Y628204D01*
G01X970419Y624629D02*
X950002Y645046D01*
G01X968086Y624629D02*
X950002Y642712D01*
G01X965752Y624629D02*
X950002Y640379D01*
G01X963419Y624629D02*
X950002Y638046D01*
G01X961085Y624629D02*
X950002Y635712D01*
G01X958751Y624629D02*
X950002Y633379D01*
G01X956418Y624629D02*
X950002Y631046D01*
G01X954085Y624629D02*
X950002Y628711D01*
G01X951751Y624629D02*
X948176Y628204D01*
G01X977068Y624629D02*
X980642Y628204D01*
G01X974734Y624629D02*
X978309Y628204D01*
G01X972401Y624629D02*
X975976Y628204D01*
G01X970068Y624629D02*
X973643Y628204D01*
G01X967734Y624629D02*
X971309Y628204D01*
G01X965401Y624629D02*
X968976Y628204D01*
G01X963068Y624629D02*
X968702Y630263D01*
G01X960733Y624629D02*
X968702Y632597D01*
G01X958400Y624629D02*
X968702Y634931D01*
G01X956067Y624629D02*
X968702Y637264D01*
G01X953733Y624629D02*
X968702Y639597D01*
G01X951400Y624629D02*
X968702Y641931D01*
G01X949067Y624629D02*
X968702Y644264D01*
G01X946733Y624629D02*
X968702Y646597D01*
G01X949418Y624629D02*
X945843Y628204D01*
G01X987952Y721436D02*
X983558Y725829D01*
G01X987952Y719102D02*
X981224Y725829D01*
G01X987952Y714435D02*
X984377Y718009D01*
G01X987424Y712629D02*
X984377Y715676D01*
G01X985091Y712629D02*
X984377Y713343D01*
G01X985731Y712629D02*
X987952Y714850D01*
G01X984377Y713608D02*
X987952Y717183D01*
G01X984377Y715942D02*
X987952Y719517D01*
G01X984377Y718276D02*
X987952Y721851D01*
G01X983271Y719504D02*
X987480Y723712D01*
G01X980938Y719504D02*
X986313Y724879D01*
G01X984377Y712629D02*
Y719504D01*
G01X987952Y712629D02*
X984377D01*
G01X987952Y723240D02*
Y712629D01*
G01X985362Y725829D02*
X987952Y723240D01*
G01Y716769D02*
X978891Y725829D01*
G01X968779D02*
X985362D01*
G01X982883Y719504D02*
X976558Y725829D01*
G01X980549Y719504D02*
X974224Y725829D01*
G01X978216Y719504D02*
X971891Y725829D01*
G01X975883Y719504D02*
X969558Y725829D01*
G01X973548Y719504D02*
X968343Y724709D01*
G01X971215Y719504D02*
X967496Y723223D01*
G01X968882Y719504D02*
X966442Y721943D01*
G01X968702Y717350D02*
X965193Y720859D01*
G01X968702Y715017D02*
X963741Y719978D01*
G01X968702Y712684D02*
X962057Y719329D01*
G01X968702Y710350D02*
X960073Y718978D01*
G01X968702Y708017D02*
X957613Y719106D01*
G01X968702Y705684D02*
X953567Y720819D01*
G01X951317Y723067D02*
X948556Y725829D01*
G01X968702Y698683D02*
X950002Y717383D01*
G01X968702Y696350D02*
X950002Y715049D01*
G01X968702Y694016D02*
X950002Y712716D01*
G01X968702Y691683D02*
X950002Y710383D01*
G01Y690901D02*
X968702Y709601D01*
G01X978605Y719504D02*
X984930Y725829D01*
G01X950002Y693234D02*
X968702Y711934D01*
G01X976271Y719504D02*
X982596Y725829D01*
G01X950002Y695568D02*
X968702Y714267D01*
G01X973938Y719504D02*
X980263Y725829D01*
G01X950002Y697901D02*
X968702Y716601D01*
G01X971605Y719504D02*
X977930Y725829D01*
G01X950002Y700234D02*
X968702Y718934D01*
G01X969271Y719504D02*
X975596Y725829D01*
G01X950002Y702569D02*
X973262Y725828D01*
G01X950002Y704902D02*
X970929Y725829D01*
G01X950002Y707235D02*
X962112Y719345D01*
G01X950002Y709569D02*
X959386Y718952D01*
G01X950002Y711902D02*
X957273Y719173D01*
G01X950002Y714235D02*
X955499Y719733D01*
G01X950002Y716569D02*
X953974Y720540D01*
G01X950002Y718903D02*
X952657Y721558D01*
G01X948269Y719504D02*
X951539Y722772D01*
G01X984377Y719504D02*
X968702D01*
G01X949925Y725829D02*
G03X968779I9427J3024D01*
G01X968702Y689350D02*
X950002Y708049D01*
G01X968702Y687016D02*
X950002Y705716D01*
G01X968702Y684683D02*
X950002Y703383D01*
G01X968702Y682350D02*
X950002Y701048D01*
G01X968702Y680015D02*
X950002Y698715D01*
G01X968702Y677682D02*
X950002Y696382D01*
G01X968702Y675349D02*
X950002Y694048D01*
G01X968702Y673015D02*
X950002Y691715D01*
G01Y674567D02*
X968702Y693267D01*
G01X950002Y676900D02*
X968702Y695600D01*
G01X950002Y679233D02*
X968702Y697933D01*
G01X950002Y681567D02*
X968702Y700267D01*
G01X950002Y683901D02*
X968702Y702601D01*
G01X950002Y686234D02*
X968702Y704934D01*
G01X950002Y688568D02*
X968702Y707268D01*
G01Y703350D02*
X946222Y725829D01*
G01X945936Y719504D02*
X950619Y724187D01*
G01X1120658Y632879D02*
X1122702Y634922D01*
G01X1118325Y632879D02*
X1122702Y637256D01*
G01X1115991Y632879D02*
X1122702Y639589D01*
G01X1113658Y632879D02*
X1122702Y641922D01*
G01X1111325Y632879D02*
X1122702Y644257D01*
G01Y714829D02*
Y632879D01*
G01X1104002Y658224D02*
X1122702Y676924D01*
G01X1104002Y660559D02*
X1122702Y679259D01*
G01X1104002Y662892D02*
X1122702Y681592D01*
G01X1104002Y665225D02*
X1122702Y683925D01*
G01X1104002Y667559D02*
X1122702Y686258D01*
G01X1104002Y669892D02*
X1122702Y688592D01*
G01X1104002Y672225D02*
X1122702Y690925D01*
G01Y670690D02*
X1104002Y689390D01*
G01X1122702Y668356D02*
X1104002Y687056D01*
G01X1122702Y666022D02*
X1104002Y684722D01*
G01X1122702Y663689D02*
X1104002Y682389D01*
G01X1122702Y661356D02*
X1104002Y680056D01*
G01X1122702Y659023D02*
X1104002Y677722D01*
G01X1122702Y656689D02*
X1104002Y675389D01*
G01X1122702Y654356D02*
X1104002Y673056D01*
G01X1122702Y652023D02*
X1104002Y670721D01*
G01X1122702Y649688D02*
X1104002Y668388D01*
G01X1122702Y647355D02*
X1104002Y666055D01*
G01X1108990Y632879D02*
X1122702Y646590D01*
G01X1106657Y632879D02*
X1122702Y648923D01*
G01X1104324Y632879D02*
X1122702Y651257D01*
G01X1104002Y634890D02*
X1122702Y653590D01*
G01X1104002Y637224D02*
X1122702Y655923D01*
G01X1104002Y639557D02*
X1122702Y658257D01*
G01X1104002Y641890D02*
X1122702Y660590D01*
G01X1104002Y644225D02*
X1122702Y662924D01*
G01X1104002Y646558D02*
X1122702Y665258D01*
G01X1104002Y648891D02*
X1122702Y667591D01*
G01X1104002Y651225D02*
X1122702Y669924D01*
G01X1104002Y653558D02*
X1122702Y672258D01*
G01X1104002Y655891D02*
X1122702Y674591D01*
G01Y645022D02*
X1104002Y663721D01*
G01X1122702Y642688D02*
X1104002Y661388D01*
G01X1122702Y640355D02*
X1104002Y659055D01*
G01X1122702Y638022D02*
X1104002Y656721D01*
G01X1122702Y635688D02*
X1104002Y654388D01*
G01X1122702Y633354D02*
X1104002Y652054D01*
G01X1120844Y632879D02*
X1104002Y649720D01*
G01X1118510Y632879D02*
X1104002Y647387D01*
G01X1116177Y632879D02*
X1104002Y645054D01*
G01X1113844Y632879D02*
X1104002Y642720D01*
G01X1111509Y632879D02*
X1104002Y640387D01*
G01X1109176Y632879D02*
X1104002Y638054D01*
G01X1106843Y632879D02*
X1104002Y635721D01*
G01X1104509Y632879D02*
X1104002Y633386D01*
G01X1122702Y632879D02*
X1104002D01*
G01D02*
Y714829D01*
G01X1122702Y712692D02*
X1120565Y714829D01*
G01X1122702Y710359D02*
X1118231Y714829D01*
G01X1122702Y708025D02*
X1115897Y714829D01*
G01X1122702Y705692D02*
X1113564Y714829D01*
G01X1104002Y690893D02*
X1122702Y709593D01*
G01X1104002Y693226D02*
X1122702Y711926D01*
G01X1104002Y695561D02*
X1122702Y714259D01*
G01X1104002Y697894D02*
X1120937Y714829D01*
G01X1104002Y700227D02*
X1118604Y714829D01*
G01X1104002Y702561D02*
X1116270Y714829D01*
G01X1104002Y704894D02*
X1113937Y714829D01*
G01X1104002Y707227D02*
X1111604Y714829D01*
G01X1104002Y709561D02*
X1109270Y714829D01*
G01X1104002Y711894D02*
X1106937Y714829D01*
G01X1104002Y714228D02*
X1104604Y714829D01*
G01X1122702Y703358D02*
X1111231Y714829D01*
G01X1122702Y701024D02*
X1108897Y714829D01*
G01X1122702Y698691D02*
X1106564Y714829D01*
G01X1122702Y696358D02*
X1104231Y714829D01*
G01X1122702Y694024D02*
X1104002Y712724D01*
G01X1122702Y691691D02*
X1104002Y710391D01*
G01X1122702Y689358D02*
X1104002Y708057D01*
G01X1122702Y687023D02*
X1104002Y705723D01*
G01X1122702Y684690D02*
X1104002Y703390D01*
G01X1122702Y682357D02*
X1104002Y701056D01*
G01X1122702Y680023D02*
X1104002Y698723D01*
G01Y714829D02*
X1122702D01*
G01X1104002Y674559D02*
X1122702Y693258D01*
G01X1104002Y676892D02*
X1122702Y695592D01*
G01X1104002Y679226D02*
X1122702Y697926D01*
G01X1104002Y681560D02*
X1122702Y700259D01*
G01X1104002Y683893D02*
X1122702Y702593D01*
G01X1104002Y686226D02*
X1122702Y704926D01*
G01X1104002Y688560D02*
X1122702Y707259D01*
G01Y677690D02*
X1104002Y696390D01*
G01X1122702Y675357D02*
X1104002Y694057D01*
G01X1122702Y673023D02*
X1104002Y691723D01*
G01X1181002Y658221D02*
X1199702Y676921D01*
G01X1181002Y660554D02*
X1199702Y679254D01*
G01X1181002Y662888D02*
X1199702Y681587D01*
G01X1181002Y665221D02*
X1199702Y683921D01*
G01X1181002Y667555D02*
X1199702Y686255D01*
G01X1181002Y669888D02*
X1199702Y688588D01*
G01X1181002Y672222D02*
X1199702Y690922D01*
G01Y666027D02*
X1181002Y684727D01*
G01X1199702Y663694D02*
X1181002Y682392D01*
G01X1199702Y661359D02*
X1181002Y680059D01*
G01X1199702Y659026D02*
X1181002Y677726D01*
G01X1192995Y632879D02*
X1199702Y639586D01*
G01X1190662Y632879D02*
X1199702Y641919D01*
G01X1188328Y632879D02*
X1199702Y644252D01*
G01X1185995Y632879D02*
X1199702Y646585D01*
G01X1183662Y632879D02*
X1199702Y648919D01*
G01X1181327Y632879D02*
X1199702Y651253D01*
G01X1181002Y634887D02*
X1199702Y653586D01*
G01X1181002Y637220D02*
X1199702Y655920D01*
G01X1181002Y639553D02*
X1199702Y658253D01*
G01X1181002Y641887D02*
X1199702Y660586D01*
G01X1181002Y644220D02*
X1199702Y662920D01*
G01X1181002Y646553D02*
X1199702Y665253D01*
G01X1181002Y648888D02*
X1199702Y667586D01*
G01X1181002Y651221D02*
X1199702Y669921D01*
G01X1181002Y653554D02*
X1199702Y672254D01*
G01X1181002Y655888D02*
X1199702Y674587D01*
G01Y656693D02*
X1181002Y675393D01*
G01X1199702Y654359D02*
X1181002Y673059D01*
G01X1199702Y652026D02*
X1181002Y670726D01*
G01X1199702Y649693D02*
X1181002Y668393D01*
G01X1199702Y647360D02*
X1181002Y666059D01*
G01X1199702Y645025D02*
X1181002Y663725D01*
G01X1199702Y642692D02*
X1181002Y661392D01*
G01X1199702Y640359D02*
X1181002Y659058D01*
G01X1199702Y638025D02*
X1181002Y656725D01*
G01X1199702Y635692D02*
X1181002Y654392D01*
G01X1199702Y633359D02*
X1181002Y652058D01*
G01X1197847Y632879D02*
X1181002Y649725D01*
G01X1195514Y632879D02*
X1181002Y647392D01*
G01X1193181Y632879D02*
X1181002Y645057D01*
G01X1190847Y632879D02*
X1181002Y642724D01*
G01X1188514Y632879D02*
X1181002Y640391D01*
G01X1186181Y632879D02*
X1181002Y638057D01*
G01X1183846Y632879D02*
X1181002Y635724D01*
G01X1181513Y632879D02*
X1181002Y633391D01*
G01X1199702Y632879D02*
X1181002D01*
G01D02*
Y714829D01*
G01Y690889D02*
X1199702Y709589D01*
G01X1181002Y693223D02*
X1199702Y711922D01*
G01X1181002Y695556D02*
X1199702Y714256D01*
G01X1181002Y697889D02*
X1197941Y714829D01*
G01X1181002Y700223D02*
X1195608Y714829D01*
G01X1181002Y702557D02*
X1193275Y714829D01*
G01X1181002Y704890D02*
X1190940Y714829D01*
G01X1181002Y707224D02*
X1188607Y714829D01*
G01X1181002Y709557D02*
X1186274Y714829D01*
G01X1181002Y711890D02*
X1183940Y714829D01*
G01X1181002Y714224D02*
X1181607Y714829D01*
G01X1199702Y708029D02*
X1192902Y714829D01*
G01X1199702Y705696D02*
X1190569Y714829D01*
G01X1199702Y703362D02*
X1188234Y714829D01*
G01X1199702Y701029D02*
X1185901Y714829D01*
G01X1199702Y698696D02*
X1183568Y714829D01*
G01X1199702Y696361D02*
X1181234Y714829D01*
G01X1199702Y694028D02*
X1181002Y712728D01*
G01X1199702Y691695D02*
X1181002Y710394D01*
G01Y714829D02*
X1199702D01*
G01X1181002Y674555D02*
X1199702Y693255D01*
G01X1181002Y676888D02*
X1199702Y695588D01*
G01X1181002Y679222D02*
X1199702Y697922D01*
G01X1181002Y681555D02*
X1199702Y700255D01*
G01X1181002Y683888D02*
X1199702Y702588D01*
G01X1181002Y686223D02*
X1199702Y704922D01*
G01X1181002Y688556D02*
X1199702Y707256D01*
G01Y689361D02*
X1181002Y708061D01*
G01X1199702Y687028D02*
X1181002Y705728D01*
G01X1199702Y684695D02*
X1181002Y703394D01*
G01X1199702Y682361D02*
X1181002Y701061D01*
G01X1199702Y680027D02*
X1181002Y698727D01*
G01X1199702Y677694D02*
X1181002Y696393D01*
G01X1199702Y675360D02*
X1181002Y694060D01*
G01X1199702Y673027D02*
X1181002Y691727D01*
G01X1199702Y670694D02*
X1181002Y689393D01*
G01X1199702Y668360D02*
X1181002Y687060D01*
G01X1197662Y632879D02*
X1199702Y634919D01*
G01X1195328Y632879D02*
X1199702Y637252D01*
G01Y714829D02*
Y632879D01*
G01Y712695D02*
X1197568Y714829D01*
G01X1199702Y710362D02*
X1195235Y714829D01*
M02*
